(kicad_sch
	(version 20250114)
	(generator "eeschema")
	(generator_version "9.0")
	(paper "A3")
	(title_block
		(title "Antmicro Baseboard for Jetson AGX Thor")
		(date "2026-02-17")
		(rev "1.1.0")
		(company "Antmicro Ltd")
		(comment 1 "www.antmicro.com")
	)
	(text "V_{EN(ON)} = 1.18V"
		(exclude_from_sim no)
		(at 290.068 124.968 0)
		(effects
			(font
				(size 1.27 1.27)
			)
		)
	)
	(text "1V8 @ 1.35A"
		(exclude_from_sim no)
		(at 337.82 114.3 0)
		(effects
			(font
				(size 1.27 1.27)
			)
			(justify left bottom)
		)
	)
	(text "ADDR: 0x43"
		(exclude_from_sim no)
		(at 206.248 136.398 0)
		(effects
			(font
				(size 1.27 1.27)
			)
			(justify left bottom)
		)
	)
	(text "V_{OUT} = 0.6*(330k+10k)/10k = 20.4[V]"
		(exclude_from_sim no)
		(at 91.948 133.604 0)
		(effects
			(font
				(size 1.27 1.27)
			)
			(justify left bottom)
		)
	)
	(text "V_{EN(ON)} = 1.18V"
		(exclude_from_sim no)
		(at 290.068 191.008 0)
		(effects
			(font
				(size 1.27 1.27)
			)
		)
	)
	(text "+5V DC/DC converter (peripherals)"
		(exclude_from_sim no)
		(at 85.852 199.136 0)
		(effects
			(font
				(size 2.54 2.54)
				(thickness 0.4)
				(bold yes)
			)
			(justify left bottom)
		)
	)
	(text "5V_{AON} @ 6A\n"
		(exclude_from_sim no)
		(at 144.78 165.1 0)
		(effects
			(font
				(size 1.27 1.27)
			)
			(justify left bottom)
		)
	)
	(text "ADDR: 0x41"
		(exclude_from_sim no)
		(at 200.66 236.22 0)
		(effects
			(font
				(size 1.27 1.27)
			)
			(justify left bottom)
		)
	)
	(text "V_{EN(ON)} = 1.6V"
		(exclude_from_sim no)
		(at 86.106 166.624 0)
		(effects
			(font
				(size 1.27 1.27)
			)
		)
	)
	(text "+3V3 DC/DC converter (peripherals)"
		(exclude_from_sim no)
		(at 85.852 246.38 0)
		(effects
			(font
				(size 2.54 2.54)
				(thickness 0.4)
				(bold yes)
			)
			(justify left bottom)
		)
	)
	(text "V_{OUT} = 0.6*(R_{FB_H}+R_{FB_L})/R_{FB_L}\n"
		(exclude_from_sim no)
		(at 311.912 66.548 0)
		(effects
			(font
				(size 1.27 1.27)
			)
			(justify left bottom)
		)
	)
	(text "SoM High voltage DC/DC converter"
		(exclude_from_sim no)
		(at 78.486 20.574 0)
		(effects
			(font
				(size 2.54 2.54)
				(thickness 0.4)
				(bold yes)
			)
			(justify left bottom)
		)
	)
	(text "V_{out} = 1.8 V\nf_{SW} = 1200 kHz\nI_{L} = 1.0 A\nΔI_{L} = 71% \nI_{Lpeak} = 1.35 A"
		(exclude_from_sim no)
		(at 317.5 139.7 0)
		(effects
			(font
				(size 1.27 1.27)
			)
			(justify left bottom)
		)
	)
	(text "V_{OUT} = 0.6*(R_{FB_H}+R_{FB_L})/R_{FB_L}\n"
		(exclude_from_sim no)
		(at 91.948 65.024 0)
		(effects
			(font
				(size 1.27 1.27)
			)
			(justify left bottom)
		)
	)
	(text "1V15 @ 1A"
		(exclude_from_sim no)
		(at 337.82 180.34 0)
		(effects
			(font
				(size 1.27 1.27)
			)
			(justify left bottom)
		)
	)
	(text "V_{OUT} = 0.6*(191k+10k)/10k = 12.06[V]"
		(exclude_from_sim no)
		(at 311.912 69.088 0)
		(effects
			(font
				(size 1.27 1.27)
			)
			(justify left bottom)
		)
	)
	(text "V_{OUT} = 0.6*(255k+10k)/10k = 15.9[V]"
		(exclude_from_sim no)
		(at 91.948 67.564 0)
		(effects
			(font
				(size 1.27 1.27)
			)
			(justify left bottom)
		)
	)
	(text "ADDR: 0x45"
		(exclude_from_sim no)
		(at 205.994 70.104 0)
		(effects
			(font
				(size 1.27 1.27)
			)
			(justify left bottom)
		)
	)
	(text "+5V_{AON} DC/DC converter (5V_{SOM}, 3V3_{AON})"
		(exclude_from_sim no)
		(at 82.804 154.178 0)
		(effects
			(font
				(size 2.54 2.54)
				(thickness 0.4)
				(bold yes)
			)
			(justify left bottom)
		)
	)
	(text "12V @ 2A\n"
		(exclude_from_sim no)
		(at 364.49 35.56 0)
		(effects
			(font
				(size 1.27 1.27)
			)
			(justify left bottom)
		)
	)
	(text "V_{OUT} = 0.6*(R_{FB_H}+R_{FB_L})/R_{FB_L}\n"
		(exclude_from_sim no)
		(at 141.986 248.92 0)
		(effects
			(font
				(size 1.27 1.27)
			)
			(justify left bottom)
		)
	)
	(text "V_{OUT} = 0.6*(45k3+10k)/10k = 3.318[V]"
		(exclude_from_sim no)
		(at 141.986 251.46 0)
		(effects
			(font
				(size 1.27 1.27)
			)
			(justify left bottom)
		)
	)
	(text "ADDR: 0x42"
		(exclude_from_sim no)
		(at 200.914 283.718 0)
		(effects
			(font
				(size 1.27 1.27)
			)
			(justify left bottom)
		)
	)
	(text "3V3 @ 12A"
		(exclude_from_sim no)
		(at 148.59 256.54 0)
		(effects
			(font
				(size 1.27 1.27)
			)
			(justify left bottom)
		)
	)
	(text "V_{OUT} = 0.6*(R_{FB_H}+R_{FB_L})/R_{FB_L}\n"
		(exclude_from_sim no)
		(at 139.446 202.184 0)
		(effects
			(font
				(size 1.27 1.27)
			)
			(justify left bottom)
		)
	)
	(text "V_{OUT} = 0.6*(73.2k+10k)/10k = 4.992[V]"
		(exclude_from_sim no)
		(at 133.604 159.766 0)
		(effects
			(font
				(size 1.27 1.27)
			)
			(justify left bottom)
		)
	)
	(text "20V @ 10A\n"
		(exclude_from_sim no)
		(at 146.05 99.06 0)
		(effects
			(font
				(size 1.27 1.27)
			)
			(justify left bottom)
		)
	)
	(text "5V @ 12A\n"
		(exclude_from_sim no)
		(at 146.05 209.55 0)
		(effects
			(font
				(size 1.27 1.27)
			)
			(justify left bottom)
		)
	)
	(text "V_{OUT} = 0.6*(R_{FB_H}+R_{FB_L})/R_{FB_L}\n"
		(exclude_from_sim no)
		(at 133.604 157.226 0)
		(effects
			(font
				(size 1.27 1.27)
			)
			(justify left bottom)
		)
	)
	(text "+1V8 DC/DC converter"
		(exclude_from_sim no)
		(at 303.53 105.41 0)
		(effects
			(font
				(size 2.54 2.54)
				(thickness 0.4)
				(bold yes)
			)
			(justify left)
		)
	)
	(text "+20V DC/DC converter (USB PD)"
		(exclude_from_sim no)
		(at 77.978 88.138 0)
		(effects
			(font
				(size 2.54 2.54)
				(thickness 0.4)
				(bold yes)
			)
			(justify left bottom)
		)
	)
	(text "V_{OUT} = 0.6*(73.2k+10k)/10k = 4.992[V]"
		(exclude_from_sim no)
		(at 139.446 204.47 0)
		(effects
			(font
				(size 1.27 1.27)
			)
			(justify left bottom)
		)
	)
	(text "16V @ 9.5A\n"
		(exclude_from_sim no)
		(at 146.05 33.02 0)
		(effects
			(font
				(size 1.27 1.27)
			)
			(justify left bottom)
		)
	)
	(text "+1V15 DC/DC converter (USB hub)"
		(exclude_from_sim no)
		(at 292.354 171.45 0)
		(effects
			(font
				(size 2.54 2.54)
				(thickness 0.4)
				(bold yes)
			)
			(justify left)
		)
	)
	(text "V_{OUT} = 0.6*(R_{FB_H}+R_{FB_L})/R_{FB_L}\n"
		(exclude_from_sim no)
		(at 91.948 131.064 0)
		(effects
			(font
				(size 1.27 1.27)
			)
			(justify left bottom)
		)
	)
	(text "ADDR: 0x46"
		(exclude_from_sim no)
		(at 200.66 191.77 0)
		(effects
			(font
				(size 1.27 1.27)
			)
			(justify left bottom)
		)
	)
	(text "+12V DC/DC converter"
		(exclude_from_sim no)
		(at 301.498 20.066 0)
		(effects
			(font
				(size 2.54 2.54)
				(thickness 0.4)
				(bold yes)
			)
			(justify left bottom)
		)
	)
	(junction
		(at 24.13 158.75)
		(diameter 0)
		(color 0 0 0 0)
	)
	(junction
		(at 220.98 109.22)
		(diameter 0)
		(color 0 0 0 0)
	)
	(junction
		(at 115.57 274.32)
		(diameter 0)
		(color 0 0 0 0)
	)
	(junction
		(at 346.71 116.84)
		(diameter 0)
		(color 0 0 0 0)
	)
	(junction
		(at 363.22 38.1)
		(diameter 0)
		(color 0 0 0 0)
	)
	(junction
		(at 232.41 259.08)
		(diameter 0)
		(color 0 0 0 0)
	)
	(junction
		(at 271.78 33.02)
		(diameter 0)
		(color 0 0 0 0)
	)
	(junction
		(at 374.65 38.1)
		(diameter 0)
		(color 0 0 0 0)
	)
	(junction
		(at 154.94 50.8)
		(diameter 0)
		(color 0 0 0 0)
	)
	(junction
		(at 143.51 259.08)
		(diameter 0)
		(color 0 0 0 0)
	)
	(junction
		(at 162.56 35.56)
		(diameter 0)
		(color 0 0 0 0)
	)
	(junction
		(at 140.97 212.09)
		(diameter 0)
		(color 0 0 0 0)
	)
	(junction
		(at 203.2 101.6)
		(diameter 0)
		(color 0 0 0 0)
	)
	(junction
		(at 43.18 158.75)
		(diameter 0)
		(color 0 0 0 0)
	)
	(junction
		(at 365.76 116.84)
		(diameter 0)
		(color 0 0 0 0)
	)
	(junction
		(at 220.98 54.61)
		(diameter 0)
		(color 0 0 0 0)
	)
	(junction
		(at 27.94 254)
		(diameter 0)
		(color 0 0 0 0)
	)
	(junction
		(at 154.94 132.08)
		(diameter 0)
		(color 0 0 0 0)
	)
	(junction
		(at 40.64 254)
		(diameter 0)
		(color 0 0 0 0)
	)
	(junction
		(at 374.65 116.84)
		(diameter 0)
		(color 0 0 0 0)
	)
	(junction
		(at 27.94 96.52)
		(diameter 0)
		(color 0 0 0 0)
	)
	(junction
		(at 162.56 116.84)
		(diameter 0)
		(color 0 0 0 0)
	)
	(junction
		(at 154.94 116.84)
		(diameter 0)
		(color 0 0 0 0)
	)
	(junction
		(at 143.51 212.09)
		(diameter 0)
		(color 0 0 0 0)
	)
	(junction
		(at 151.13 116.84)
		(diameter 0)
		(color 0 0 0 0)
	)
	(junction
		(at 232.41 212.09)
		(diameter 0)
		(color 0 0 0 0)
	)
	(junction
		(at 154.94 66.04)
		(diameter 0)
		(color 0 0 0 0)
	)
	(junction
		(at 153.67 167.64)
		(diameter 0)
		(color 0 0 0 0)
	)
	(junction
		(at 360.68 38.1)
		(diameter 0)
		(color 0 0 0 0)
	)
	(junction
		(at 177.8 259.08)
		(diameter 0)
		(color 0 0 0 0)
	)
	(junction
		(at 162.56 212.09)
		(diameter 0)
		(color 0 0 0 0)
	)
	(junction
		(at 372.11 38.1)
		(diameter 0)
		(color 0 0 0 0)
	)
	(junction
		(at 177.8 212.09)
		(diameter 0)
		(color 0 0 0 0)
	)
	(junction
		(at 177.8 101.6)
		(diameter 0)
		(color 0 0 0 0)
	)
	(junction
		(at 21.59 30.48)
		(diameter 0)
		(color 0 0 0 0)
	)
	(junction
		(at 220.98 120.65)
		(diameter 0)
		(color 0 0 0 0)
	)
	(junction
		(at 55.88 40.64)
		(diameter 0)
		(color 0 0 0 0)
	)
	(junction
		(at 72.39 269.24)
		(diameter 0)
		(color 0 0 0 0)
	)
	(junction
		(at 170.18 66.04)
		(diameter 0)
		(color 0 0 0 0)
	)
	(junction
		(at 220.98 43.18)
		(diameter 0)
		(color 0 0 0 0)
	)
	(junction
		(at 176.53 167.64)
		(diameter 0)
		(color 0 0 0 0)
	)
	(junction
		(at 27.94 207.01)
		(diameter 0)
		(color 0 0 0 0)
	)
	(junction
		(at 233.68 101.6)
		(diameter 0)
		(color 0 0 0 0)
	)
	(junction
		(at 72.39 222.25)
		(diameter 0)
		(color 0 0 0 0)
	)
	(junction
		(at 151.13 35.56)
		(diameter 0)
		(color 0 0 0 0)
	)
	(junction
		(at 177.8 50.8)
		(diameter 0)
		(color 0 0 0 0)
	)
	(junction
		(at 215.9 166.37)
		(diameter 0)
		(color 0 0 0 0)
	)
	(junction
		(at 177.8 66.04)
		(diameter 0)
		(color 0 0 0 0)
	)
	(junction
		(at 275.59 116.84)
		(diameter 0)
		(color 0 0 0 0)
	)
	(junction
		(at 255.27 33.02)
		(diameter 0)
		(color 0 0 0 0)
	)
	(junction
		(at 198.12 257.81)
		(diameter 0)
		(color 0 0 0 0)
	)
	(junction
		(at 48.26 135.89)
		(diameter 0)
		(color 0 0 0 0)
	)
	(junction
		(at 143.51 175.26)
		(diameter 0)
		(color 0 0 0 0)
	)
	(junction
		(at 48.26 207.01)
		(diameter 0)
		(color 0 0 0 0)
	)
	(junction
		(at 294.64 48.26)
		(diameter 0)
		(color 0 0 0 0)
	)
	(junction
		(at 363.22 45.72)
		(diameter 0)
		(color 0 0 0 0)
	)
	(junction
		(at 143.51 43.18)
		(diameter 0)
		(color 0 0 0 0)
	)
	(junction
		(at 215.9 224.79)
		(diameter 0)
		(color 0 0 0 0)
	)
	(junction
		(at 21.59 207.01)
		(diameter 0)
		(color 0 0 0 0)
	)
	(junction
		(at 170.18 259.08)
		(diameter 0)
		(color 0 0 0 0)
	)
	(junction
		(at 215.9 180.34)
		(diameter 0)
		(color 0 0 0 0)
	)
	(junction
		(at 185.42 35.56)
		(diameter 0)
		(color 0 0 0 0)
	)
	(junction
		(at 55.88 217.17)
		(diameter 0)
		(color 0 0 0 0)
	)
	(junction
		(at 154.94 259.08)
		(diameter 0)
		(color 0 0 0 0)
	)
	(junction
		(at 335.28 53.34)
		(diameter 0)
		(color 0 0 0 0)
	)
	(junction
		(at 215.9 203.2)
		(diameter 0)
		(color 0 0 0 0)
	)
	(junction
		(at 48.26 30.48)
		(diameter 0)
		(color 0 0 0 0)
	)
	(junction
		(at 215.9 250.19)
		(diameter 0)
		(color 0 0 0 0)
	)
	(junction
		(at 140.97 167.64)
		(diameter 0)
		(color 0 0 0 0)
	)
	(junction
		(at 143.51 101.6)
		(diameter 0)
		(color 0 0 0 0)
	)
	(junction
		(at 198.12 271.78)
		(diameter 0)
		(color 0 0 0 0)
	)
	(junction
		(at 151.13 50.8)
		(diameter 0)
		(color 0 0 0 0)
	)
	(junction
		(at 397.51 38.1)
		(diameter 0)
		(color 0 0 0 0)
	)
	(junction
		(at 143.51 167.64)
		(diameter 0)
		(color 0 0 0 0)
	)
	(junction
		(at 162.56 132.08)
		(diameter 0)
		(color 0 0 0 0)
	)
	(junction
		(at 34.29 254)
		(diameter 0)
		(color 0 0 0 0)
	)
	(junction
		(at 36.83 158.75)
		(diameter 0)
		(color 0 0 0 0)
	)
	(junction
		(at 336.55 124.46)
		(diameter 0)
		(color 0 0 0 0)
	)
	(junction
		(at 220.98 62.23)
		(diameter 0)
		(color 0 0 0 0)
	)
	(junction
		(at 140.97 101.6)
		(diameter 0)
		(color 0 0 0 0)
	)
	(junction
		(at 21.59 96.52)
		(diameter 0)
		(color 0 0 0 0)
	)
	(junction
		(at 215.9 158.75)
		(diameter 0)
		(color 0 0 0 0)
	)
	(junction
		(at 26.67 180.34)
		(diameter 0)
		(color 0 0 0 0)
	)
	(junction
		(at 143.51 35.56)
		(diameter 0)
		(color 0 0 0 0)
	)
	(junction
		(at 50.8 158.75)
		(diameter 0)
		(color 0 0 0 0)
	)
	(junction
		(at 170.18 50.8)
		(diameter 0)
		(color 0 0 0 0)
	)
	(junction
		(at 232.41 167.64)
		(diameter 0)
		(color 0 0 0 0)
	)
	(junction
		(at 162.56 66.04)
		(diameter 0)
		(color 0 0 0 0)
	)
	(junction
		(at 185.42 101.6)
		(diameter 0)
		(color 0 0 0 0)
	)
	(junction
		(at 115.57 227.33)
		(diameter 0)
		(color 0 0 0 0)
	)
	(junction
		(at 143.51 109.22)
		(diameter 0)
		(color 0 0 0 0)
	)
	(junction
		(at 299.72 127)
		(diameter 0)
		(color 0 0 0 0)
	)
	(junction
		(at 154.94 35.56)
		(diameter 0)
		(color 0 0 0 0)
	)
	(junction
		(at 140.97 259.08)
		(diameter 0)
		(color 0 0 0 0)
	)
	(junction
		(at 34.29 96.52)
		(diameter 0)
		(color 0 0 0 0)
	)
	(junction
		(at 198.12 158.75)
		(diameter 0)
		(color 0 0 0 0)
	)
	(junction
		(at 72.39 45.72)
		(diameter 0)
		(color 0 0 0 0)
	)
	(junction
		(at 27.94 30.48)
		(diameter 0)
		(color 0 0 0 0)
	)
	(junction
		(at 40.64 96.52)
		(diameter 0)
		(color 0 0 0 0)
	)
	(junction
		(at 34.29 30.48)
		(diameter 0)
		(color 0 0 0 0)
	)
	(junction
		(at 154.94 212.09)
		(diameter 0)
		(color 0 0 0 0)
	)
	(junction
		(at 251.46 33.02)
		(diameter 0)
		(color 0 0 0 0)
	)
	(junction
		(at 215.9 187.96)
		(diameter 0)
		(color 0 0 0 0)
	)
	(junction
		(at 262.89 33.02)
		(diameter 0)
		(color 0 0 0 0)
	)
	(junction
		(at 383.54 38.1)
		(diameter 0)
		(color 0 0 0 0)
	)
	(junction
		(at 170.18 101.6)
		(diameter 0)
		(color 0 0 0 0)
	)
	(junction
		(at 275.59 182.88)
		(diameter 0)
		(color 0 0 0 0)
	)
	(junction
		(at 154.94 101.6)
		(diameter 0)
		(color 0 0 0 0)
	)
	(junction
		(at 162.56 259.08)
		(diameter 0)
		(color 0 0 0 0)
	)
	(junction
		(at 170.18 212.09)
		(diameter 0)
		(color 0 0 0 0)
	)
	(junction
		(at 115.57 182.88)
		(diameter 0)
		(color 0 0 0 0)
	)
	(junction
		(at 346.71 182.88)
		(diameter 0)
		(color 0 0 0 0)
	)
	(junction
		(at 162.56 101.6)
		(diameter 0)
		(color 0 0 0 0)
	)
	(junction
		(at 74.93 177.8)
		(diameter 0)
		(color 0 0 0 0)
	)
	(junction
		(at 203.2 109.22)
		(diameter 0)
		(color 0 0 0 0)
	)
	(junction
		(at 16.51 158.75)
		(diameter 0)
		(color 0 0 0 0)
	)
	(junction
		(at 170.18 132.08)
		(diameter 0)
		(color 0 0 0 0)
	)
	(junction
		(at 21.59 254)
		(diameter 0)
		(color 0 0 0 0)
	)
	(junction
		(at 215.9 271.78)
		(diameter 0)
		(color 0 0 0 0)
	)
	(junction
		(at 336.55 190.5)
		(diameter 0)
		(color 0 0 0 0)
	)
	(junction
		(at 198.12 166.37)
		(diameter 0)
		(color 0 0 0 0)
	)
	(junction
		(at 198.12 203.2)
		(diameter 0)
		(color 0 0 0 0)
	)
	(junction
		(at 115.57 50.8)
		(diameter 0)
		(color 0 0 0 0)
	)
	(junction
		(at 374.65 55.88)
		(diameter 0)
		(color 0 0 0 0)
	)
	(junction
		(at 215.9 210.82)
		(diameter 0)
		(color 0 0 0 0)
	)
	(junction
		(at 233.68 35.56)
		(diameter 0)
		(color 0 0 0 0)
	)
	(junction
		(at 170.18 35.56)
		(diameter 0)
		(color 0 0 0 0)
	)
	(junction
		(at 336.55 116.84)
		(diameter 0)
		(color 0 0 0 0)
	)
	(junction
		(at 115.57 116.84)
		(diameter 0)
		(color 0 0 0 0)
	)
	(junction
		(at 255.27 50.8)
		(diameter 0)
		(color 0 0 0 0)
	)
	(junction
		(at 16.51 180.34)
		(diameter 0)
		(color 0 0 0 0)
	)
	(junction
		(at 355.6 182.88)
		(diameter 0)
		(color 0 0 0 0)
	)
	(junction
		(at 355.6 116.84)
		(diameter 0)
		(color 0 0 0 0)
	)
	(junction
		(at 365.76 182.88)
		(diameter 0)
		(color 0 0 0 0)
	)
	(junction
		(at 220.98 101.6)
		(diameter 0)
		(color 0 0 0 0)
	)
	(junction
		(at 34.29 207.01)
		(diameter 0)
		(color 0 0 0 0)
	)
	(junction
		(at 143.51 219.71)
		(diameter 0)
		(color 0 0 0 0)
	)
	(junction
		(at 266.7 116.84)
		(diameter 0)
		(color 0 0 0 0)
	)
	(junction
		(at 55.88 264.16)
		(diameter 0)
		(color 0 0 0 0)
	)
	(junction
		(at 162.56 50.8)
		(diameter 0)
		(color 0 0 0 0)
	)
	(junction
		(at 374.65 182.88)
		(diameter 0)
		(color 0 0 0 0)
	)
	(junction
		(at 203.2 62.23)
		(diameter 0)
		(color 0 0 0 0)
	)
	(junction
		(at 203.2 35.56)
		(diameter 0)
		(color 0 0 0 0)
	)
	(junction
		(at 215.9 257.81)
		(diameter 0)
		(color 0 0 0 0)
	)
	(junction
		(at 198.12 210.82)
		(diameter 0)
		(color 0 0 0 0)
	)
	(junction
		(at 140.97 35.56)
		(diameter 0)
		(color 0 0 0 0)
	)
	(junction
		(at 74.93 111.76)
		(diameter 0)
		(color 0 0 0 0)
	)
	(junction
		(at 143.51 266.7)
		(diameter 0)
		(color 0 0 0 0)
	)
	(junction
		(at 203.2 43.18)
		(diameter 0)
		(color 0 0 0 0)
	)
	(junction
		(at 151.13 101.6)
		(diameter 0)
		(color 0 0 0 0)
	)
	(junction
		(at 30.48 158.75)
		(diameter 0)
		(color 0 0 0 0)
	)
	(junction
		(at 161.29 167.64)
		(diameter 0)
		(color 0 0 0 0)
	)
	(junction
		(at 220.98 128.27)
		(diameter 0)
		(color 0 0 0 0)
	)
	(junction
		(at 48.26 96.52)
		(diameter 0)
		(color 0 0 0 0)
	)
	(junction
		(at 48.26 254)
		(diameter 0)
		(color 0 0 0 0)
	)
	(junction
		(at 170.18 116.84)
		(diameter 0)
		(color 0 0 0 0)
	)
	(junction
		(at 58.42 172.72)
		(diameter 0)
		(color 0 0 0 0)
	)
	(junction
		(at 40.64 207.01)
		(diameter 0)
		(color 0 0 0 0)
	)
	(junction
		(at 40.64 30.48)
		(diameter 0)
		(color 0 0 0 0)
	)
	(junction
		(at 220.98 35.56)
		(diameter 0)
		(color 0 0 0 0)
	)
	(junction
		(at 336.55 182.88)
		(diameter 0)
		(color 0 0 0 0)
	)
	(junction
		(at 215.9 279.4)
		(diameter 0)
		(color 0 0 0 0)
	)
	(junction
		(at 215.9 232.41)
		(diameter 0)
		(color 0 0 0 0)
	)
	(junction
		(at 177.8 35.56)
		(diameter 0)
		(color 0 0 0 0)
	)
	(junction
		(at 177.8 116.84)
		(diameter 0)
		(color 0 0 0 0)
	)
	(junction
		(at 299.72 193.04)
		(diameter 0)
		(color 0 0 0 0)
	)
	(junction
		(at 198.12 250.19)
		(diameter 0)
		(color 0 0 0 0)
	)
	(junction
		(at 266.7 182.88)
		(diameter 0)
		(color 0 0 0 0)
	)
	(junction
		(at 278.13 43.18)
		(diameter 0)
		(color 0 0 0 0)
	)
	(junction
		(at 168.91 167.64)
		(diameter 0)
		(color 0 0 0 0)
	)
	(junction
		(at 203.2 123.19)
		(diameter 0)
		(color 0 0 0 0)
	)
	(junction
		(at 177.8 132.08)
		(diameter 0)
		(color 0 0 0 0)
	)
	(junction
		(at 55.88 106.68)
		(diameter 0)
		(color 0 0 0 0)
	)
	(no_connect
		(at 92.71 116.84)
	)
	(no_connect
		(at 114.3 38.1)
	)
	(no_connect
		(at 334.01 40.64)
	)
	(no_connect
		(at 312.42 53.34)
	)
	(no_connect
		(at 114.3 214.63)
	)
	(no_connect
		(at 92.71 227.33)
	)
	(no_connect
		(at 114.3 261.62)
	)
	(no_connect
		(at 92.71 274.32)
	)
	(no_connect
		(at 114.3 104.14)
	)
	(no_connect
		(at 114.3 170.18)
	)
	(bus_entry
		(at 185.42 273.05)
		(size 1.27 1.27)
		(stroke
			(width 0)
			(type default)
		)
	)
	(bus_entry
		(at 193.04 55.88)
		(size 1.27 1.27)
		(stroke
			(width 0)
			(type default)
		)
	)
	(bus_entry
		(at 193.04 119.38)
		(size 1.27 1.27)
		(stroke
			(width 0)
			(type default)
		)
	)
	(bus_entry
		(at 185.42 181.61)
		(size 1.27 1.27)
		(stroke
			(width 0)
			(type default)
		)
	)
	(bus_entry
		(at 193.04 119.38)
		(size 1.27 1.27)
		(stroke
			(width 0)
			(type default)
		)
	)
	(bus_entry
		(at 193.04 121.92)
		(size 1.27 1.27)
		(stroke
			(width 0)
			(type default)
		)
	)
	(bus_entry
		(at 193.04 53.34)
		(size 1.27 1.27)
		(stroke
			(width 0)
			(type default)
		)
	)
	(bus_entry
		(at 185.42 179.07)
		(size 1.27 1.27)
		(stroke
			(width 0)
			(type default)
		)
	)
	(bus_entry
		(at 185.42 270.51)
		(size 1.27 1.27)
		(stroke
			(width 0)
			(type default)
		)
	)
	(bus_entry
		(at 193.04 121.92)
		(size 1.27 1.27)
		(stroke
			(width 0)
			(type default)
		)
	)
	(bus_entry
		(at 185.42 226.06)
		(size 1.27 1.27)
		(stroke
			(width 0)
			(type default)
		)
	)
	(bus_entry
		(at 185.42 223.52)
		(size 1.27 1.27)
		(stroke
			(width 0)
			(type default)
		)
	)
	(bus_entry
		(at 193.04 55.88)
		(size 1.27 1.27)
		(stroke
			(width 0)
			(type default)
		)
	)
	(bus_entry
		(at 193.04 53.34)
		(size 1.27 1.27)
		(stroke
			(width 0)
			(type default)
		)
	)
	(wire
		(pts
			(xy 64.77 43.18) (xy 64.77 49.53)
		)
		(stroke
			(width 0)
			(type default)
		)
	)
	(wire
		(pts
			(xy 162.56 50.8) (xy 162.56 53.34)
		)
		(stroke
			(width 0)
			(type default)
		)
	)
	(bus
		(pts
			(xy 193.04 31.75) (xy 193.04 53.34)
		)
		(stroke
			(width 0)
			(type default)
		)
	)
	(wire
		(pts
			(xy 55.88 215.9) (xy 55.88 217.17)
		)
		(stroke
			(width 0)
			(type default)
		)
	)
	(wire
		(pts
			(xy 204.47 203.2) (xy 198.12 203.2)
		)
		(stroke
			(width 0)
			(type default)
		)
	)
	(wire
		(pts
			(xy 40.64 105.41) (xy 40.64 107.95)
		)
		(stroke
			(width 0)
			(type default)
		)
	)
	(wire
		(pts
			(xy 177.8 139.7) (xy 177.8 140.97)
		)
		(stroke
			(width 0)
			(type default)
		)
	)
	(wire
		(pts
			(xy 55.88 106.68) (xy 55.88 115.57)
		)
		(stroke
			(width 0)
			(type default)
		)
	)
	(wire
		(pts
			(xy 177.8 259.08) (xy 177.8 267.97)
		)
		(stroke
			(width 0)
			(type default)
		)
	)
	(wire
		(pts
			(xy 251.46 33.02) (xy 255.27 33.02)
		)
		(stroke
			(width 0)
			(type default)
		)
	)
	(wire
		(pts
			(xy 64.77 278.13) (xy 64.77 279.4)
		)
		(stroke
			(width 0)
			(type default)
		)
	)
	(wire
		(pts
			(xy 115.57 121.92) (xy 115.57 116.84)
		)
		(stroke
			(width 0)
			(type default)
		)
	)
	(wire
		(pts
			(xy 300.99 190.5) (xy 299.72 190.5)
		)
		(stroke
			(width 0)
			(type default)
		)
	)
	(wire
		(pts
			(xy 219.71 54.61) (xy 220.98 54.61)
		)
		(stroke
			(width 0)
			(type default)
		)
	)
	(wire
		(pts
			(xy 162.56 116.84) (xy 162.56 119.38)
		)
		(stroke
			(width 0)
			(type default)
		)
	)
	(wire
		(pts
			(xy 170.18 132.08) (xy 177.8 132.08)
		)
		(stroke
			(width 0)
			(type default)
		)
	)
	(wire
		(pts
			(xy 198.12 166.37) (xy 198.12 175.26)
		)
		(stroke
			(width 0)
			(type default)
		)
	)
	(wire
		(pts
			(xy 162.56 124.46) (xy 162.56 125.73)
		)
		(stroke
			(width 0)
			(type default)
		)
	)
	(wire
		(pts
			(xy 170.18 139.7) (xy 170.18 140.97)
		)
		(stroke
			(width 0)
			(type default)
		)
	)
	(wire
		(pts
			(xy 161.29 175.26) (xy 161.29 176.53)
		)
		(stroke
			(width 0)
			(type default)
		)
	)
	(bus
		(pts
			(xy 193.04 53.34) (xy 193.04 55.88)
		)
		(stroke
			(width 0)
			(type default)
		)
	)
	(wire
		(pts
			(xy 336.55 182.88) (xy 336.55 184.15)
		)
		(stroke
			(width 0)
			(type default)
		)
	)
	(wire
		(pts
			(xy 130.81 162.56) (xy 130.81 165.1)
		)
		(stroke
			(width 0)
			(type default)
		)
	)
	(wire
		(pts
			(xy 154.94 116.84) (xy 162.56 116.84)
		)
		(stroke
			(width 0)
			(type default)
		)
	)
	(wire
		(pts
			(xy 114.3 40.64) (xy 140.97 40.64)
		)
		(stroke
			(width 0)
			(type default)
		)
	)
	(wire
		(pts
			(xy 143.51 101.6) (xy 143.51 102.87)
		)
		(stroke
			(width 0)
			(type default)
		)
	)
	(wire
		(pts
			(xy 346.71 116.84) (xy 346.71 121.92)
		)
		(stroke
			(width 0)
			(type default)
		)
	)
	(wire
		(pts
			(xy 72.39 273.05) (xy 72.39 269.24)
		)
		(stroke
			(width 0)
			(type default)
		)
	)
	(wire
		(pts
			(xy 55.88 120.65) (xy 55.88 121.92)
		)
		(stroke
			(width 0)
			(type default)
		)
	)
	(wire
		(pts
			(xy 74.93 115.57) (xy 74.93 111.76)
		)
		(stroke
			(width 0)
			(type default)
		)
	)
	(wire
		(pts
			(xy 214.63 109.22) (xy 220.98 109.22)
		)
		(stroke
			(width 0)
			(type default)
		)
	)
	(wire
		(pts
			(xy 55.88 40.64) (xy 92.71 40.64)
		)
		(stroke
			(width 0)
			(type default)
		)
	)
	(wire
		(pts
			(xy 215.9 231.14) (xy 215.9 232.41)
		)
		(stroke
			(width 0)
			(type default)
		)
	)
	(wire
		(pts
			(xy 203.2 43.18) (xy 209.55 43.18)
		)
		(stroke
			(width 0)
			(type default)
		)
	)
	(wire
		(pts
			(xy 64.77 266.7) (xy 92.71 266.7)
		)
		(stroke
			(width 0)
			(type default)
		)
	)
	(wire
		(pts
			(xy 220.98 101.6) (xy 233.68 101.6)
		)
		(stroke
			(width 0)
			(type default)
		)
	)
	(wire
		(pts
			(xy 40.64 30.48) (xy 48.26 30.48)
		)
		(stroke
			(width 0)
			(type default)
		)
	)
	(wire
		(pts
			(xy 24.13 165.1) (xy 24.13 167.64)
		)
		(stroke
			(width 0)
			(type default)
		)
	)
	(wire
		(pts
			(xy 177.8 35.56) (xy 185.42 35.56)
		)
		(stroke
			(width 0)
			(type default)
		)
	)
	(wire
		(pts
			(xy 251.46 50.8) (xy 251.46 33.02)
		)
		(stroke
			(width 0)
			(type default)
		)
	)
	(wire
		(pts
			(xy 363.22 38.1) (xy 372.11 38.1)
		)
		(stroke
			(width 0)
			(type default)
		)
	)
	(wire
		(pts
			(xy 154.94 116.84) (xy 151.13 116.84)
		)
		(stroke
			(width 0)
			(type default)
		)
	)
	(bus
		(pts
			(xy 193.04 97.79) (xy 191.77 96.52)
		)
		(stroke
			(width 0)
			(type default)
		)
	)
	(wire
		(pts
			(xy 383.54 55.88) (xy 374.65 55.88)
		)
		(stroke
			(width 0)
			(type default)
		)
	)
	(wire
		(pts
			(xy 255.27 43.18) (xy 255.27 44.45)
		)
		(stroke
			(width 0)
			(type default)
		)
	)
	(wire
		(pts
			(xy 222.25 271.78) (xy 222.25 270.51)
		)
		(stroke
			(width 0)
			(type default)
		)
	)
	(wire
		(pts
			(xy 154.94 124.46) (xy 154.94 125.73)
		)
		(stroke
			(width 0)
			(type default)
		)
	)
	(wire
		(pts
			(xy 143.51 110.49) (xy 143.51 109.22)
		)
		(stroke
			(width 0)
			(type default)
		)
	)
	(wire
		(pts
			(xy 114.3 109.22) (xy 143.51 109.22)
		)
		(stroke
			(width 0)
			(type default)
		)
	)
	(wire
		(pts
			(xy 215.9 250.19) (xy 215.9 251.46)
		)
		(stroke
			(width 0)
			(type default)
		)
	)
	(wire
		(pts
			(xy 83.82 224.79) (xy 83.82 226.06)
		)
		(stroke
			(width 0)
			(type default)
		)
	)
	(polyline
		(pts
			(xy 12.7 82.55) (xy 248.285 82.55)
		)
		(stroke
			(width 0)
			(type default)
		)
	)
	(wire
		(pts
			(xy 204.47 158.75) (xy 198.12 158.75)
		)
		(stroke
			(width 0)
			(type default)
		)
	)
	(wire
		(pts
			(xy 372.11 182.88) (xy 374.65 182.88)
		)
		(stroke
			(width 0)
			(type default)
		)
	)
	(wire
		(pts
			(xy 203.2 115.57) (xy 203.2 109.22)
		)
		(stroke
			(width 0)
			(type default)
		)
	)
	(wire
		(pts
			(xy 177.8 212.09) (xy 177.8 220.98)
		)
		(stroke
			(width 0)
			(type default)
		)
	)
	(wire
		(pts
			(xy 185.42 50.8) (xy 185.42 53.34)
		)
		(stroke
			(width 0)
			(type default)
		)
	)
	(wire
		(pts
			(xy 215.9 210.82) (xy 215.9 219.71)
		)
		(stroke
			(width 0)
			(type default)
		)
	)
	(wire
		(pts
			(xy 55.88 106.68) (xy 92.71 106.68)
		)
		(stroke
			(width 0)
			(type default)
		)
	)
	(wire
		(pts
			(xy 115.57 185.42) (xy 115.57 182.88)
		)
		(stroke
			(width 0)
			(type default)
		)
	)
	(wire
		(pts
			(xy 86.36 36.83) (xy 87.63 36.83)
		)
		(stroke
			(width 0)
			(type default)
		)
	)
	(wire
		(pts
			(xy 355.6 130.81) (xy 355.6 127)
		)
		(stroke
			(width 0)
			(type default)
		)
	)
	(wire
		(pts
			(xy 34.29 30.48) (xy 34.29 34.29)
		)
		(stroke
			(width 0)
			(type default)
		)
	)
	(wire
		(pts
			(xy 193.04 232.41) (xy 199.39 232.41)
		)
		(stroke
			(width 0)
			(type default)
		)
	)
	(wire
		(pts
			(xy 91.44 213.36) (xy 91.44 214.63)
		)
		(stroke
			(width 0)
			(type default)
		)
	)
	(wire
		(pts
			(xy 55.88 39.37) (xy 55.88 40.64)
		)
		(stroke
			(width 0)
			(type default)
		)
	)
	(wire
		(pts
			(xy 191.77 250.19) (xy 191.77 259.08)
		)
		(stroke
			(width 0)
			(type default)
		)
	)
	(wire
		(pts
			(xy 220.98 128.27) (xy 220.98 132.08)
		)
		(stroke
			(width 0)
			(type default)
		)
	)
	(wire
		(pts
			(xy 170.18 35.56) (xy 170.18 38.1)
		)
		(stroke
			(width 0)
			(type default)
		)
	)
	(wire
		(pts
			(xy 21.59 29.21) (xy 21.59 30.48)
		)
		(stroke
			(width 0)
			(type default)
		)
	)
	(wire
		(pts
			(xy 114.3 50.8) (xy 115.57 50.8)
		)
		(stroke
			(width 0)
			(type default)
		)
	)
	(wire
		(pts
			(xy 355.6 116.84) (xy 355.6 121.92)
		)
		(stroke
			(width 0)
			(type default)
		)
	)
	(wire
		(pts
			(xy 153.67 167.64) (xy 161.29 167.64)
		)
		(stroke
			(width 0)
			(type default)
		)
	)
	(polyline
		(pts
			(xy 12.7 148.59) (xy 248.285 148.59)
		)
		(stroke
			(width 0)
			(type default)
		)
	)
	(wire
		(pts
			(xy 64.77 231.14) (xy 64.77 232.41)
		)
		(stroke
			(width 0)
			(type default)
		)
	)
	(wire
		(pts
			(xy 26.67 186.69) (xy 26.67 187.96)
		)
		(stroke
			(width 0)
			(type default)
		)
	)
	(wire
		(pts
			(xy 50.8 165.1) (xy 50.8 167.64)
		)
		(stroke
			(width 0)
			(type default)
		)
	)
	(wire
		(pts
			(xy 198.12 158.75) (xy 191.77 158.75)
		)
		(stroke
			(width 0)
			(type default)
		)
	)
	(wire
		(pts
			(xy 36.83 158.75) (xy 43.18 158.75)
		)
		(stroke
			(width 0)
			(type default)
		)
	)
	(wire
		(pts
			(xy 233.68 101.6) (xy 237.49 101.6)
		)
		(stroke
			(width 0)
			(type default)
		)
	)
	(wire
		(pts
			(xy 222.25 167.64) (xy 232.41 167.64)
		)
		(stroke
			(width 0)
			(type default)
		)
	)
	(wire
		(pts
			(xy 64.77 109.22) (xy 64.77 115.57)
		)
		(stroke
			(width 0)
			(type default)
		)
	)
	(wire
		(pts
			(xy 204.47 49.53) (xy 203.2 49.53)
		)
		(stroke
			(width 0)
			(type default)
		)
	)
	(wire
		(pts
			(xy 232.41 166.37) (xy 232.41 167.64)
		)
		(stroke
			(width 0)
			(type default)
		)
	)
	(wire
		(pts
			(xy 72.39 45.72) (xy 92.71 45.72)
		)
		(stroke
			(width 0)
			(type default)
		)
	)
	(wire
		(pts
			(xy 198.12 250.19) (xy 191.77 250.19)
		)
		(stroke
			(width 0)
			(type default)
		)
	)
	(wire
		(pts
			(xy 266.7 116.84) (xy 266.7 119.38)
		)
		(stroke
			(width 0)
			(type default)
		)
	)
	(wire
		(pts
			(xy 114.3 30.48) (xy 124.46 30.48)
		)
		(stroke
			(width 0)
			(type default)
		)
	)
	(wire
		(pts
			(xy 162.56 101.6) (xy 170.18 101.6)
		)
		(stroke
			(width 0)
			(type default)
		)
	)
	(wire
		(pts
			(xy 185.42 101.6) (xy 203.2 101.6)
		)
		(stroke
			(width 0)
			(type default)
		)
	)
	(wire
		(pts
			(xy 397.51 38.1) (xy 397.51 46.99)
		)
		(stroke
			(width 0)
			(type default)
		)
	)
	(wire
		(pts
			(xy 335.28 58.42) (xy 335.28 53.34)
		)
		(stroke
			(width 0)
			(type default)
		)
	)
	(wire
		(pts
			(xy 88.9 158.75) (xy 88.9 162.56)
		)
		(stroke
			(width 0)
			(type default)
		)
	)
	(wire
		(pts
			(xy 114.3 96.52) (xy 124.46 96.52)
		)
		(stroke
			(width 0)
			(type default)
		)
	)
	(wire
		(pts
			(xy 40.64 100.33) (xy 40.64 96.52)
		)
		(stroke
			(width 0)
			(type default)
		)
	)
	(wire
		(pts
			(xy 233.68 212.09) (xy 232.41 212.09)
		)
		(stroke
			(width 0)
			(type default)
		)
	)
	(wire
		(pts
			(xy 154.94 43.18) (xy 154.94 44.45)
		)
		(stroke
			(width 0)
			(type default)
		)
	)
	(wire
		(pts
			(xy 349.25 33.02) (xy 350.52 33.02)
		)
		(stroke
			(width 0)
			(type default)
		)
	)
	(wire
		(pts
			(xy 170.18 109.22) (xy 170.18 110.49)
		)
		(stroke
			(width 0)
			(type default)
		)
	)
	(wire
		(pts
			(xy 355.6 182.88) (xy 355.6 187.96)
		)
		(stroke
			(width 0)
			(type default)
		)
	)
	(wire
		(pts
			(xy 346.71 182.88) (xy 336.55 182.88)
		)
		(stroke
			(width 0)
			(type default)
		)
	)
	(wire
		(pts
			(xy 143.51 49.53) (xy 143.51 55.88)
		)
		(stroke
			(width 0)
			(type default)
		)
	)
	(wire
		(pts
			(xy 154.94 273.05) (xy 154.94 279.4)
		)
		(stroke
			(width 0)
			(type default)
		)
	)
	(polyline
		(pts
			(xy 248.285 148.59) (xy 407.67 148.59)
		)
		(stroke
			(width 0)
			(type default)
		)
	)
	(wire
		(pts
			(xy 334.01 35.56) (xy 350.52 35.56)
		)
		(stroke
			(width 0)
			(type default)
		)
	)
	(wire
		(pts
			(xy 162.56 132.08) (xy 170.18 132.08)
		)
		(stroke
			(width 0)
			(type default)
		)
	)
	(wire
		(pts
			(xy 162.56 35.56) (xy 170.18 35.56)
		)
		(stroke
			(width 0)
			(type default)
		)
	)
	(wire
		(pts
			(xy 215.9 232.41) (xy 215.9 234.95)
		)
		(stroke
			(width 0)
			(type default)
		)
	)
	(wire
		(pts
			(xy 170.18 132.08) (xy 170.18 134.62)
		)
		(stroke
			(width 0)
			(type default)
		)
	)
	(wire
		(pts
			(xy 154.94 259.08) (xy 162.56 259.08)
		)
		(stroke
			(width 0)
			(type default)
		)
	)
	(wire
		(pts
			(xy 170.18 35.56) (xy 177.8 35.56)
		)
		(stroke
			(width 0)
			(type default)
		)
	)
	(wire
		(pts
			(xy 27.94 254) (xy 34.29 254)
		)
		(stroke
			(width 0)
			(type default)
		)
	)
	(wire
		(pts
			(xy 140.97 106.68) (xy 140.97 101.6)
		)
		(stroke
			(width 0)
			(type default)
		)
	)
	(wire
		(pts
			(xy 215.9 180.34) (xy 222.25 180.34)
		)
		(stroke
			(width 0)
			(type default)
		)
	)
	(wire
		(pts
			(xy 154.94 50.8) (xy 154.94 53.34)
		)
		(stroke
			(width 0)
			(type default)
		)
	)
	(wire
		(pts
			(xy 363.22 52.07) (xy 363.22 58.42)
		)
		(stroke
			(width 0)
			(type default)
		)
	)
	(wire
		(pts
			(xy 115.57 50.8) (xy 115.57 48.26)
		)
		(stroke
			(width 0)
			(type default)
		)
	)
	(bus
		(pts
			(xy 185.42 179.07) (xy 185.42 181.61)
		)
		(stroke
			(width 0)
			(type default)
		)
	)
	(wire
		(pts
			(xy 271.78 33.02) (xy 312.42 33.02)
		)
		(stroke
			(width 0)
			(type default)
		)
	)
	(wire
		(pts
			(xy 185.42 139.7) (xy 185.42 140.97)
		)
		(stroke
			(width 0)
			(type default)
		)
	)
	(wire
		(pts
			(xy 139.7 212.09) (xy 140.97 212.09)
		)
		(stroke
			(width 0)
			(type default)
		)
	)
	(wire
		(pts
			(xy 214.63 180.34) (xy 215.9 180.34)
		)
		(stroke
			(width 0)
			(type default)
		)
	)
	(wire
		(pts
			(xy 355.6 116.84) (xy 365.76 116.84)
		)
		(stroke
			(width 0)
			(type default)
		)
	)
	(wire
		(pts
			(xy 198.12 64.77) (xy 198.12 63.5)
		)
		(stroke
			(width 0)
			(type default)
		)
	)
	(wire
		(pts
			(xy 72.39 278.13) (xy 72.39 279.4)
		)
		(stroke
			(width 0)
			(type default)
		)
	)
	(wire
		(pts
			(xy 209.55 166.37) (xy 215.9 166.37)
		)
		(stroke
			(width 0)
			(type default)
		)
	)
	(wire
		(pts
			(xy 203.2 128.27) (xy 203.2 123.19)
		)
		(stroke
			(width 0)
			(type default)
		)
	)
	(wire
		(pts
			(xy 219.71 128.27) (xy 220.98 128.27)
		)
		(stroke
			(width 0)
			(type default)
		)
	)
	(wire
		(pts
			(xy 232.41 167.64) (xy 232.41 176.53)
		)
		(stroke
			(width 0)
			(type default)
		)
	)
	(wire
		(pts
			(xy 168.91 167.64) (xy 176.53 167.64)
		)
		(stroke
			(width 0)
			(type default)
		)
	)
	(wire
		(pts
			(xy 27.94 224.79) (xy 27.94 232.41)
		)
		(stroke
			(width 0)
			(type default)
		)
	)
	(wire
		(pts
			(xy 48.26 224.79) (xy 48.26 232.41)
		)
		(stroke
			(width 0)
			(type default)
		)
	)
	(wire
		(pts
			(xy 162.56 116.84) (xy 170.18 116.84)
		)
		(stroke
			(width 0)
			(type default)
		)
	)
	(wire
		(pts
			(xy 346.71 182.88) (xy 355.6 182.88)
		)
		(stroke
			(width 0)
			(type default)
		)
	)
	(wire
		(pts
			(xy 114.3 116.84) (xy 115.57 116.84)
		)
		(stroke
			(width 0)
			(type default)
		)
	)
	(wire
		(pts
			(xy 40.64 34.29) (xy 40.64 30.48)
		)
		(stroke
			(width 0)
			(type default)
		)
	)
	(wire
		(pts
			(xy 359.41 38.1) (xy 360.68 38.1)
		)
		(stroke
			(width 0)
			(type default)
		)
	)
	(wire
		(pts
			(xy 299.72 121.92) (xy 300.99 121.92)
		)
		(stroke
			(width 0)
			(type default)
		)
	)
	(wire
		(pts
			(xy 374.65 38.1) (xy 383.54 38.1)
		)
		(stroke
			(width 0)
			(type default)
		)
	)
	(wire
		(pts
			(xy 41.91 135.89) (xy 48.26 135.89)
		)
		(stroke
			(width 0)
			(type default)
		)
	)
	(wire
		(pts
			(xy 346.71 182.88) (xy 346.71 187.96)
		)
		(stroke
			(width 0)
			(type default)
		)
	)
	(wire
		(pts
			(xy 74.93 186.69) (xy 74.93 187.96)
		)
		(stroke
			(width 0)
			(type default)
		)
	)
	(wire
		(pts
			(xy 255.27 33.02) (xy 255.27 38.1)
		)
		(stroke
			(width 0)
			(type default)
		)
	)
	(wire
		(pts
			(xy 285.75 45.72) (xy 285.75 52.07)
		)
		(stroke
			(width 0)
			(type default)
		)
	)
	(wire
		(pts
			(xy 140.97 264.16) (xy 140.97 259.08)
		)
		(stroke
			(width 0)
			(type default)
		)
	)
	(wire
		(pts
			(xy 203.2 109.22) (xy 209.55 109.22)
		)
		(stroke
			(width 0)
			(type default)
		)
	)
	(wire
		(pts
			(xy 200.66 125.73) (xy 200.66 132.08)
		)
		(stroke
			(width 0)
			(type default)
		)
	)
	(wire
		(pts
			(xy 203.2 43.18) (xy 203.2 49.53)
		)
		(stroke
			(width 0)
			(type default)
		)
	)
	(wire
		(pts
			(xy 114.3 48.26) (xy 115.57 48.26)
		)
		(stroke
			(width 0)
			(type default)
		)
	)
	(wire
		(pts
			(xy 336.55 124.46) (xy 336.55 125.73)
		)
		(stroke
			(width 0)
			(type default)
		)
	)
	(wire
		(pts
			(xy 143.51 167.64) (xy 153.67 167.64)
		)
		(stroke
			(width 0)
			(type default)
		)
	)
	(wire
		(pts
			(xy 40.64 254) (xy 48.26 254)
		)
		(stroke
			(width 0)
			(type default)
		)
	)
	(wire
		(pts
			(xy 66.04 186.69) (xy 66.04 187.96)
		)
		(stroke
			(width 0)
			(type default)
		)
	)
	(wire
		(pts
			(xy 143.51 176.53) (xy 143.51 175.26)
		)
		(stroke
			(width 0)
			(type default)
		)
	)
	(wire
		(pts
			(xy 198.12 229.87) (xy 199.39 229.87)
		)
		(stroke
			(width 0)
			(type default)
		)
	)
	(wire
		(pts
			(xy 186.69 180.34) (xy 199.39 180.34)
		)
		(stroke
			(width 0)
			(type default)
		)
	)
	(wire
		(pts
			(xy 55.88 231.14) (xy 55.88 232.41)
		)
		(stroke
			(width 0)
			(type default)
		)
	)
	(wire
		(pts
			(xy 114.3 165.1) (xy 130.81 165.1)
		)
		(stroke
			(width 0)
			(type default)
		)
	)
	(wire
		(pts
			(xy 198.12 257.81) (xy 198.12 266.7)
		)
		(stroke
			(width 0)
			(type default)
		)
	)
	(wire
		(pts
			(xy 72.39 54.61) (xy 72.39 55.88)
		)
		(stroke
			(width 0)
			(type default)
		)
	)
	(wire
		(pts
			(xy 115.57 274.32) (xy 115.57 271.78)
		)
		(stroke
			(width 0)
			(type default)
		)
	)
	(wire
		(pts
			(xy 233.68 101.6) (xy 233.68 100.33)
		)
		(stroke
			(width 0)
			(type default)
		)
	)
	(wire
		(pts
			(xy 233.68 111.76) (xy 233.68 114.3)
		)
		(stroke
			(width 0)
			(type default)
		)
	)
	(wire
		(pts
			(xy 143.51 273.05) (xy 143.51 279.4)
		)
		(stroke
			(width 0)
			(type default)
		)
	)
	(wire
		(pts
			(xy 303.53 50.8) (xy 312.42 50.8)
		)
		(stroke
			(width 0)
			(type default)
		)
	)
	(wire
		(pts
			(xy 203.2 59.69) (xy 204.47 59.69)
		)
		(stroke
			(width 0)
			(type default)
		)
	)
	(wire
		(pts
			(xy 48.26 254) (xy 92.71 254)
		)
		(stroke
			(width 0)
			(type default)
		)
	)
	(wire
		(pts
			(xy 185.42 132.08) (xy 185.42 134.62)
		)
		(stroke
			(width 0)
			(type default)
		)
	)
	(wire
		(pts
			(xy 275.59 116.84) (xy 275.59 119.38)
		)
		(stroke
			(width 0)
			(type default)
		)
	)
	(wire
		(pts
			(xy 34.29 96.52) (xy 34.29 100.33)
		)
		(stroke
			(width 0)
			(type default)
		)
	)
	(wire
		(pts
			(xy 233.68 35.56) (xy 237.49 35.56)
		)
		(stroke
			(width 0)
			(type default)
		)
	)
	(wire
		(pts
			(xy 220.98 62.23) (xy 220.98 66.04)
		)
		(stroke
			(width 0)
			(type default)
		)
	)
	(wire
		(pts
			(xy 214.63 279.4) (xy 215.9 279.4)
		)
		(stroke
			(width 0)
			(type default)
		)
	)
	(wire
		(pts
			(xy 162.56 73.66) (xy 162.56 74.93)
		)
		(stroke
			(width 0)
			(type default)
		)
	)
	(wire
		(pts
			(xy 55.88 40.64) (xy 55.88 49.53)
		)
		(stroke
			(width 0)
			(type default)
		)
	)
	(wire
		(pts
			(xy 177.8 132.08) (xy 177.8 134.62)
		)
		(stroke
			(width 0)
			(type default)
		)
	)
	(wire
		(pts
			(xy 143.51 115.57) (xy 143.51 121.92)
		)
		(stroke
			(width 0)
			(type default)
		)
	)
	(wire
		(pts
			(xy 162.56 101.6) (xy 162.56 104.14)
		)
		(stroke
			(width 0)
			(type default)
		)
	)
	(wire
		(pts
			(xy 16.51 158.75) (xy 24.13 158.75)
		)
		(stroke
			(width 0)
			(type default)
		)
	)
	(wire
		(pts
			(xy 233.68 35.56) (xy 233.68 34.29)
		)
		(stroke
			(width 0)
			(type default)
		)
	)
	(wire
		(pts
			(xy 176.53 167.64) (xy 191.77 167.64)
		)
		(stroke
			(width 0)
			(type default)
		)
	)
	(wire
		(pts
			(xy 232.41 273.05) (xy 232.41 279.4)
		)
		(stroke
			(width 0)
			(type default)
		)
	)
	(wire
		(pts
			(xy 170.18 116.84) (xy 177.8 116.84)
		)
		(stroke
			(width 0)
			(type default)
		)
	)
	(wire
		(pts
			(xy 91.44 191.77) (xy 90.17 191.77)
		)
		(stroke
			(width 0)
			(type default)
		)
	)
	(wire
		(pts
			(xy 55.88 262.89) (xy 55.88 264.16)
		)
		(stroke
			(width 0)
			(type default)
		)
	)
	(wire
		(pts
			(xy 209.55 210.82) (xy 215.9 210.82)
		)
		(stroke
			(width 0)
			(type default)
		)
	)
	(wire
		(pts
			(xy 24.13 158.75) (xy 30.48 158.75)
		)
		(stroke
			(width 0)
			(type default)
		)
	)
	(wire
		(pts
			(xy 198.12 158.75) (xy 198.12 160.02)
		)
		(stroke
			(width 0)
			(type default)
		)
	)
	(wire
		(pts
			(xy 336.55 123.19) (xy 336.55 124.46)
		)
		(stroke
			(width 0)
			(type default)
		)
	)
	(wire
		(pts
			(xy 215.9 203.2) (xy 215.9 204.47)
		)
		(stroke
			(width 0)
			(type default)
		)
	)
	(wire
		(pts
			(xy 30.48 165.1) (xy 30.48 167.64)
		)
		(stroke
			(width 0)
			(type default)
		)
	)
	(wire
		(pts
			(xy 177.8 50.8) (xy 177.8 53.34)
		)
		(stroke
			(width 0)
			(type default)
		)
	)
	(wire
		(pts
			(xy 130.81 96.52) (xy 130.81 99.06)
		)
		(stroke
			(width 0)
			(type default)
		)
	)
	(wire
		(pts
			(xy 185.42 116.84) (xy 185.42 119.38)
		)
		(stroke
			(width 0)
			(type default)
		)
	)
	(wire
		(pts
			(xy 220.98 120.65) (xy 220.98 121.92)
		)
		(stroke
			(width 0)
			(type default)
		)
	)
	(wire
		(pts
			(xy 154.94 259.08) (xy 154.94 267.97)
		)
		(stroke
			(width 0)
			(type default)
		)
	)
	(wire
		(pts
			(xy 153.67 167.64) (xy 153.67 170.18)
		)
		(stroke
			(width 0)
			(type default)
		)
	)
	(wire
		(pts
			(xy 114.3 35.56) (xy 134.62 35.56)
		)
		(stroke
			(width 0)
			(type default)
		)
	)
	(bus
		(pts
			(xy 185.42 163.83) (xy 185.42 179.07)
		)
		(stroke
			(width 0)
			(type default)
		)
	)
	(wire
		(pts
			(xy 74.93 177.8) (xy 92.71 177.8)
		)
		(stroke
			(width 0)
			(type default)
		)
	)
	(wire
		(pts
			(xy 64.77 43.18) (xy 92.71 43.18)
		)
		(stroke
			(width 0)
			(type default)
		)
	)
	(wire
		(pts
			(xy 220.98 109.22) (xy 220.98 115.57)
		)
		(stroke
			(width 0)
			(type default)
		)
	)
	(wire
		(pts
			(xy 140.97 212.09) (xy 143.51 212.09)
		)
		(stroke
			(width 0)
			(type default)
		)
	)
	(wire
		(pts
			(xy 316.23 182.88) (xy 326.39 182.88)
		)
		(stroke
			(width 0)
			(type default)
		)
	)
	(wire
		(pts
			(xy 36.83 158.75) (xy 36.83 160.02)
		)
		(stroke
			(width 0)
			(type default)
		)
	)
	(wire
		(pts
			(xy 55.88 256.54) (xy 72.39 256.54)
		)
		(stroke
			(width 0)
			(type default)
		)
	)
	(wire
		(pts
			(xy 83.82 180.34) (xy 92.71 180.34)
		)
		(stroke
			(width 0)
			(type default)
		)
	)
	(wire
		(pts
			(xy 48.26 105.41) (xy 48.26 107.95)
		)
		(stroke
			(width 0)
			(type default)
		)
	)
	(wire
		(pts
			(xy 143.51 41.91) (xy 143.51 43.18)
		)
		(stroke
			(width 0)
			(type default)
		)
	)
	(wire
		(pts
			(xy 215.9 158.75) (xy 215.9 160.02)
		)
		(stroke
			(width 0)
			(type default)
		)
	)
	(wire
		(pts
			(xy 220.98 120.65) (xy 227.33 120.65)
		)
		(stroke
			(width 0)
			(type default)
		)
	)
	(wire
		(pts
			(xy 115.57 182.88) (xy 115.57 180.34)
		)
		(stroke
			(width 0)
			(type default)
		)
	)
	(wire
		(pts
			(xy 336.55 189.23) (xy 336.55 190.5)
		)
		(stroke
			(width 0)
			(type default)
		)
	)
	(wire
		(pts
			(xy 203.2 102.87) (xy 203.2 101.6)
		)
		(stroke
			(width 0)
			(type default)
		)
	)
	(wire
		(pts
			(xy 91.44 260.35) (xy 91.44 261.62)
		)
		(stroke
			(width 0)
			(type default)
		)
	)
	(wire
		(pts
			(xy 196.85 276.86) (xy 199.39 276.86)
		)
		(stroke
			(width 0)
			(type default)
		)
	)
	(bus
		(pts
			(xy 185.42 255.27) (xy 184.15 254)
		)
		(stroke
			(width 0)
			(type default)
		)
	)
	(wire
		(pts
			(xy 55.88 33.02) (xy 72.39 33.02)
		)
		(stroke
			(width 0)
			(type default)
		)
	)
	(wire
		(pts
			(xy 83.82 186.69) (xy 83.82 187.96)
		)
		(stroke
			(width 0)
			(type default)
		)
	)
	(wire
		(pts
			(xy 91.44 261.62) (xy 92.71 261.62)
		)
		(stroke
			(width 0)
			(type default)
		)
	)
	(wire
		(pts
			(xy 55.88 273.05) (xy 55.88 264.16)
		)
		(stroke
			(width 0)
			(type default)
		)
	)
	(wire
		(pts
			(xy 34.29 30.48) (xy 27.94 30.48)
		)
		(stroke
			(width 0)
			(type default)
		)
	)
	(wire
		(pts
			(xy 262.89 38.1) (xy 262.89 33.02)
		)
		(stroke
			(width 0)
			(type default)
		)
	)
	(wire
		(pts
			(xy 16.51 180.34) (xy 26.67 180.34)
		)
		(stroke
			(width 0)
			(type default)
		)
	)
	(wire
		(pts
			(xy 398.78 38.1) (xy 397.51 38.1)
		)
		(stroke
			(width 0)
			(type default)
		)
	)
	(wire
		(pts
			(xy 262.89 50.8) (xy 255.27 50.8)
		)
		(stroke
			(width 0)
			(type default)
		)
	)
	(wire
		(pts
			(xy 196.85 276.86) (xy 196.85 280.67)
		)
		(stroke
			(width 0)
			(type default)
		)
	)
	(wire
		(pts
			(xy 143.51 181.61) (xy 143.51 185.42)
		)
		(stroke
			(width 0)
			(type default)
		)
	)
	(wire
		(pts
			(xy 58.42 186.69) (xy 58.42 187.96)
		)
		(stroke
			(width 0)
			(type default)
		)
	)
	(wire
		(pts
			(xy 154.94 116.84) (xy 154.94 119.38)
		)
		(stroke
			(width 0)
			(type default)
		)
	)
	(wire
		(pts
			(xy 335.28 53.34) (xy 335.28 50.8)
		)
		(stroke
			(width 0)
			(type default)
		)
	)
	(wire
		(pts
			(xy 186.69 182.88) (xy 199.39 182.88)
		)
		(stroke
			(width 0)
			(type default)
		)
	)
	(wire
		(pts
			(xy 162.56 273.05) (xy 162.56 279.4)
		)
		(stroke
			(width 0)
			(type default)
		)
	)
	(wire
		(pts
			(xy 185.42 58.42) (xy 185.42 59.69)
		)
		(stroke
			(width 0)
			(type default)
		)
	)
	(wire
		(pts
			(xy 233.68 45.72) (xy 233.68 48.26)
		)
		(stroke
			(width 0)
			(type default)
		)
	)
	(wire
		(pts
			(xy 374.65 55.88) (xy 372.11 55.88)
		)
		(stroke
			(width 0)
			(type default)
		)
	)
	(wire
		(pts
			(xy 140.97 101.6) (xy 143.51 101.6)
		)
		(stroke
			(width 0)
			(type default)
		)
	)
	(wire
		(pts
			(xy 50.8 158.75) (xy 50.8 160.02)
		)
		(stroke
			(width 0)
			(type default)
		)
	)
	(wire
		(pts
			(xy 170.18 226.06) (xy 170.18 232.41)
		)
		(stroke
			(width 0)
			(type default)
		)
	)
	(wire
		(pts
			(xy 55.88 33.02) (xy 55.88 34.29)
		)
		(stroke
			(width 0)
			(type default)
		)
	)
	(wire
		(pts
			(xy 177.8 116.84) (xy 185.42 116.84)
		)
		(stroke
			(width 0)
			(type default)
		)
	)
	(wire
		(pts
			(xy 154.94 66.04) (xy 162.56 66.04)
		)
		(stroke
			(width 0)
			(type default)
		)
	)
	(wire
		(pts
			(xy 162.56 139.7) (xy 162.56 140.97)
		)
		(stroke
			(width 0)
			(type default)
		)
	)
	(wire
		(pts
			(xy 311.15 40.64) (xy 312.42 40.64)
		)
		(stroke
			(width 0)
			(type default)
		)
	)
	(wire
		(pts
			(xy 233.68 35.56) (xy 233.68 40.64)
		)
		(stroke
			(width 0)
			(type default)
		)
	)
	(wire
		(pts
			(xy 74.93 120.65) (xy 74.93 121.92)
		)
		(stroke
			(width 0)
			(type default)
		)
	)
	(wire
		(pts
			(xy 48.26 128.27) (xy 48.26 129.54)
		)
		(stroke
			(width 0)
			(type default)
		)
	)
	(wire
		(pts
			(xy 143.51 218.44) (xy 143.51 219.71)
		)
		(stroke
			(width 0)
			(type default)
		)
	)
	(wire
		(pts
			(xy 30.48 158.75) (xy 36.83 158.75)
		)
		(stroke
			(width 0)
			(type default)
		)
	)
	(wire
		(pts
			(xy 365.76 130.81) (xy 365.76 127)
		)
		(stroke
			(width 0)
			(type default)
		)
	)
	(wire
		(pts
			(xy 114.3 114.3) (xy 115.57 114.3)
		)
		(stroke
			(width 0)
			(type default)
		)
	)
	(wire
		(pts
			(xy 154.94 101.6) (xy 162.56 101.6)
		)
		(stroke
			(width 0)
			(type default)
		)
	)
	(wire
		(pts
			(xy 215.9 250.19) (xy 209.55 250.19)
		)
		(stroke
			(width 0)
			(type default)
		)
	)
	(wire
		(pts
			(xy 151.13 101.6) (xy 154.94 101.6)
		)
		(stroke
			(width 0)
			(type default)
		)
	)
	(wire
		(pts
			(xy 233.68 167.64) (xy 232.41 167.64)
		)
		(stroke
			(width 0)
			(type default)
		)
	)
	(wire
		(pts
			(xy 90.17 59.69) (xy 90.17 50.8)
		)
		(stroke
			(width 0)
			(type default)
		)
	)
	(wire
		(pts
			(xy 114.3 219.71) (xy 143.51 219.71)
		)
		(stroke
			(width 0)
			(type default)
		)
	)
	(wire
		(pts
			(xy 232.41 210.82) (xy 232.41 212.09)
		)
		(stroke
			(width 0)
			(type default)
		)
	)
	(wire
		(pts
			(xy 27.94 100.33) (xy 27.94 96.52)
		)
		(stroke
			(width 0)
			(type default)
		)
	)
	(wire
		(pts
			(xy 215.9 209.55) (xy 215.9 210.82)
		)
		(stroke
			(width 0)
			(type default)
		)
	)
	(wire
		(pts
			(xy 88.9 162.56) (xy 92.71 162.56)
		)
		(stroke
			(width 0)
			(type default)
		)
	)
	(wire
		(pts
			(xy 151.13 50.8) (xy 151.13 66.04)
		)
		(stroke
			(width 0)
			(type default)
		)
	)
	(wire
		(pts
			(xy 177.8 101.6) (xy 177.8 104.14)
		)
		(stroke
			(width 0)
			(type default)
		)
	)
	(wire
		(pts
			(xy 43.18 165.1) (xy 43.18 167.64)
		)
		(stroke
			(width 0)
			(type default)
		)
	)
	(wire
		(pts
			(xy 397.51 36.83) (xy 397.51 38.1)
		)
		(stroke
			(width 0)
			(type default)
		)
	)
	(wire
		(pts
			(xy 275.59 182.88) (xy 300.99 182.88)
		)
		(stroke
			(width 0)
			(type default)
		)
	)
	(wire
		(pts
			(xy 215.9 271.78) (xy 222.25 271.78)
		)
		(stroke
			(width 0)
			(type default)
		)
	)
	(wire
		(pts
			(xy 355.6 196.85) (xy 355.6 193.04)
		)
		(stroke
			(width 0)
			(type default)
		)
	)
	(bus
		(pts
			(xy 180.34 162.56) (xy 184.15 162.56)
		)
		(stroke
			(width 0)
			(type default)
		)
	)
	(wire
		(pts
			(xy 26.67 180.34) (xy 26.67 181.61)
		)
		(stroke
			(width 0)
			(type default)
		)
	)
	(wire
		(pts
			(xy 55.88 99.06) (xy 74.93 99.06)
		)
		(stroke
			(width 0)
			(type default)
		)
	)
	(wire
		(pts
			(xy 185.42 189.23) (xy 179.07 189.23)
		)
		(stroke
			(width 0)
			(type default)
		)
	)
	(wire
		(pts
			(xy 203.2 123.19) (xy 204.47 123.19)
		)
		(stroke
			(width 0)
			(type default)
		)
	)
	(wire
		(pts
			(xy 170.18 50.8) (xy 170.18 53.34)
		)
		(stroke
			(width 0)
			(type default)
		)
	)
	(wire
		(pts
			(xy 278.13 52.07) (xy 278.13 43.18)
		)
		(stroke
			(width 0)
			(type default)
		)
	)
	(wire
		(pts
			(xy 203.2 64.77) (xy 198.12 64.77)
		)
		(stroke
			(width 0)
			(type default)
		)
	)
	(wire
		(pts
			(xy 114.3 271.78) (xy 115.57 271.78)
		)
		(stroke
			(width 0)
			(type default)
		)
	)
	(wire
		(pts
			(xy 334.01 53.34) (xy 335.28 53.34)
		)
		(stroke
			(width 0)
			(type default)
		)
	)
	(wire
		(pts
			(xy 350.52 33.02) (xy 350.52 35.56)
		)
		(stroke
			(width 0)
			(type default)
		)
	)
	(wire
		(pts
			(xy 375.92 182.88) (xy 374.65 182.88)
		)
		(stroke
			(width 0)
			(type default)
		)
	)
	(wire
		(pts
			(xy 83.82 114.3) (xy 83.82 115.57)
		)
		(stroke
			(width 0)
			(type default)
		)
	)
	(wire
		(pts
			(xy 151.13 35.56) (xy 151.13 50.8)
		)
		(stroke
			(width 0)
			(type default)
		)
	)
	(wire
		(pts
			(xy 278.13 35.56) (xy 278.13 36.83)
		)
		(stroke
			(width 0)
			(type default)
		)
	)
	(wire
		(pts
			(xy 278.13 57.15) (xy 278.13 58.42)
		)
		(stroke
			(width 0)
			(type default)
		)
	)
	(wire
		(pts
			(xy 114.3 274.32) (xy 115.57 274.32)
		)
		(stroke
			(width 0)
			(type default)
		)
	)
	(wire
		(pts
			(xy 203.2 43.18) (xy 203.2 41.91)
		)
		(stroke
			(width 0)
			(type default)
		)
	)
	(wire
		(pts
			(xy 83.82 48.26) (xy 92.71 48.26)
		)
		(stroke
			(width 0)
			(type default)
		)
	)
	(wire
		(pts
			(xy 74.93 99.06) (xy 74.93 111.76)
		)
		(stroke
			(width 0)
			(type default)
		)
	)
	(wire
		(pts
			(xy 114.3 209.55) (xy 130.81 209.55)
		)
		(stroke
			(width 0)
			(type default)
		)
	)
	(wire
		(pts
			(xy 161.29 167.64) (xy 168.91 167.64)
		)
		(stroke
			(width 0)
			(type default)
		)
	)
	(wire
		(pts
			(xy 168.91 167.64) (xy 168.91 170.18)
		)
		(stroke
			(width 0)
			(type default)
		)
	)
	(wire
		(pts
			(xy 21.59 39.37) (xy 21.59 41.91)
		)
		(stroke
			(width 0)
			(type default)
		)
	)
	(wire
		(pts
			(xy 143.51 259.08) (xy 143.51 260.35)
		)
		(stroke
			(width 0)
			(type default)
		)
	)
	(wire
		(pts
			(xy 177.8 132.08) (xy 185.42 132.08)
		)
		(stroke
			(width 0)
			(type default)
		)
	)
	(wire
		(pts
			(xy 114.3 162.56) (xy 125.73 162.56)
		)
		(stroke
			(width 0)
			(type default)
		)
	)
	(wire
		(pts
			(xy 334.01 38.1) (xy 354.33 38.1)
		)
		(stroke
			(width 0)
			(type default)
		)
	)
	(wire
		(pts
			(xy 383.54 57.15) (xy 383.54 55.88)
		)
		(stroke
			(width 0)
			(type default)
		)
	)
	(wire
		(pts
			(xy 154.94 109.22) (xy 154.94 110.49)
		)
		(stroke
			(width 0)
			(type default)
		)
	)
	(wire
		(pts
			(xy 220.98 101.6) (xy 220.98 102.87)
		)
		(stroke
			(width 0)
			(type default)
		)
	)
	(wire
		(pts
			(xy 214.63 101.6) (xy 220.98 101.6)
		)
		(stroke
			(width 0)
			(type default)
		)
	)
	(wire
		(pts
			(xy 198.12 271.78) (xy 199.39 271.78)
		)
		(stroke
			(width 0)
			(type default)
		)
	)
	(wire
		(pts
			(xy 21.59 105.41) (xy 21.59 107.95)
		)
		(stroke
			(width 0)
			(type default)
		)
	)
	(wire
		(pts
			(xy 316.23 190.5) (xy 336.55 190.5)
		)
		(stroke
			(width 0)
			(type default)
		)
	)
	(wire
		(pts
			(xy 170.18 101.6) (xy 177.8 101.6)
		)
		(stroke
			(width 0)
			(type default)
		)
	)
	(wire
		(pts
			(xy 83.82 180.34) (xy 83.82 181.61)
		)
		(stroke
			(width 0)
			(type default)
		)
	)
	(wire
		(pts
			(xy 40.64 266.7) (xy 40.64 254)
		)
		(stroke
			(width 0)
			(type default)
		)
	)
	(wire
		(pts
			(xy 83.82 114.3) (xy 92.71 114.3)
		)
		(stroke
			(width 0)
			(type default)
		)
	)
	(wire
		(pts
			(xy 83.82 271.78) (xy 92.71 271.78)
		)
		(stroke
			(width 0)
			(type default)
		)
	)
	(wire
		(pts
			(xy 170.18 73.66) (xy 170.18 74.93)
		)
		(stroke
			(width 0)
			(type default)
		)
	)
	(wire
		(pts
			(xy 64.77 54.61) (xy 64.77 55.88)
		)
		(stroke
			(width 0)
			(type default)
		)
	)
	(wire
		(pts
			(xy 391.16 38.1) (xy 397.51 38.1)
		)
		(stroke
			(width 0)
			(type default)
		)
	)
	(wire
		(pts
			(xy 72.39 269.24) (xy 92.71 269.24)
		)
		(stroke
			(width 0)
			(type default)
		)
	)
	(wire
		(pts
			(xy 114.3 227.33) (xy 115.57 227.33)
		)
		(stroke
			(width 0)
			(type default)
		)
	)
	(wire
		(pts
			(xy 130.81 207.01) (xy 130.81 209.55)
		)
		(stroke
			(width 0)
			(type default)
		)
	)
	(wire
		(pts
			(xy 365.76 116.84) (xy 365.76 121.92)
		)
		(stroke
			(width 0)
			(type default)
		)
	)
	(wire
		(pts
			(xy 154.94 73.66) (xy 154.94 74.93)
		)
		(stroke
			(width 0)
			(type default)
		)
	)
	(wire
		(pts
			(xy 55.88 226.06) (xy 55.88 217.17)
		)
		(stroke
			(width 0)
			(type default)
		)
	)
	(wire
		(pts
			(xy 143.51 44.45) (xy 143.51 43.18)
		)
		(stroke
			(width 0)
			(type default)
		)
	)
	(wire
		(pts
			(xy 214.63 35.56) (xy 220.98 35.56)
		)
		(stroke
			(width 0)
			(type default)
		)
	)
	(wire
		(pts
			(xy 289.56 35.56) (xy 289.56 48.26)
		)
		(stroke
			(width 0)
			(type default)
		)
	)
	(wire
		(pts
			(xy 170.18 124.46) (xy 170.18 125.73)
		)
		(stroke
			(width 0)
			(type default)
		)
	)
	(wire
		(pts
			(xy 374.65 48.26) (xy 374.65 49.53)
		)
		(stroke
			(width 0)
			(type default)
		)
	)
	(wire
		(pts
			(xy 21.59 95.25) (xy 21.59 96.52)
		)
		(stroke
			(width 0)
			(type default)
		)
	)
	(wire
		(pts
			(xy 214.63 271.78) (xy 215.9 271.78)
		)
		(stroke
			(width 0)
			(type default)
		)
	)
	(wire
		(pts
			(xy 154.94 212.09) (xy 162.56 212.09)
		)
		(stroke
			(width 0)
			(type default)
		)
	)
	(wire
		(pts
			(xy 139.7 259.08) (xy 140.97 259.08)
		)
		(stroke
			(width 0)
			(type default)
		)
	)
	(wire
		(pts
			(xy 346.71 130.81) (xy 346.71 127)
		)
		(stroke
			(width 0)
			(type default)
		)
	)
	(wire
		(pts
			(xy 48.26 30.48) (xy 48.26 34.29)
		)
		(stroke
			(width 0)
			(type default)
		)
	)
	(polyline
		(pts
			(xy 247.65 82.55) (xy 407.035 82.55)
		)
		(stroke
			(width 0)
			(type default)
		)
	)
	(wire
		(pts
			(xy 154.94 132.08) (xy 154.94 134.62)
		)
		(stroke
			(width 0)
			(type default)
		)
	)
	(wire
		(pts
			(xy 383.54 38.1) (xy 383.54 43.18)
		)
		(stroke
			(width 0)
			(type default)
		)
	)
	(wire
		(pts
			(xy 139.7 167.64) (xy 140.97 167.64)
		)
		(stroke
			(width 0)
			(type default)
		)
	)
	(wire
		(pts
			(xy 203.2 62.23) (xy 203.2 59.69)
		)
		(stroke
			(width 0)
			(type default)
		)
	)
	(wire
		(pts
			(xy 55.88 209.55) (xy 72.39 209.55)
		)
		(stroke
			(width 0)
			(type default)
		)
	)
	(wire
		(pts
			(xy 16.51 186.69) (xy 16.51 187.96)
		)
		(stroke
			(width 0)
			(type default)
		)
	)
	(wire
		(pts
			(xy 48.26 39.37) (xy 48.26 41.91)
		)
		(stroke
			(width 0)
			(type default)
		)
	)
	(wire
		(pts
			(xy 177.8 226.06) (xy 177.8 232.41)
		)
		(stroke
			(width 0)
			(type default)
		)
	)
	(wire
		(pts
			(xy 220.98 60.96) (xy 220.98 62.23)
		)
		(stroke
			(width 0)
			(type default)
		)
	)
	(wire
		(pts
			(xy 336.55 190.5) (xy 336.55 191.77)
		)
		(stroke
			(width 0)
			(type default)
		)
	)
	(wire
		(pts
			(xy 66.04 175.26) (xy 66.04 181.61)
		)
		(stroke
			(width 0)
			(type default)
		)
	)
	(wire
		(pts
			(xy 170.18 212.09) (xy 170.18 220.98)
		)
		(stroke
			(width 0)
			(type default)
		)
	)
	(wire
		(pts
			(xy 154.94 66.04) (xy 151.13 66.04)
		)
		(stroke
			(width 0)
			(type default)
		)
	)
	(wire
		(pts
			(xy 34.29 30.48) (xy 40.64 30.48)
		)
		(stroke
			(width 0)
			(type default)
		)
	)
	(bus
		(pts
			(xy 180.34 207.01) (xy 184.15 207.01)
		)
		(stroke
			(width 0)
			(type default)
		)
	)
	(wire
		(pts
			(xy 139.7 35.56) (xy 140.97 35.56)
		)
		(stroke
			(width 0)
			(type default)
		)
	)
	(wire
		(pts
			(xy 220.98 43.18) (xy 220.98 49.53)
		)
		(stroke
			(width 0)
			(type default)
		)
	)
	(wire
		(pts
			(xy 185.42 185.42) (xy 185.42 189.23)
		)
		(stroke
			(width 0)
			(type default)
		)
	)
	(wire
		(pts
			(xy 177.8 116.84) (xy 177.8 119.38)
		)
		(stroke
			(width 0)
			(type default)
		)
	)
	(wire
		(pts
			(xy 176.53 175.26) (xy 176.53 176.53)
		)
		(stroke
			(width 0)
			(type default)
		)
	)
	(wire
		(pts
			(xy 168.91 175.26) (xy 168.91 176.53)
		)
		(stroke
			(width 0)
			(type default)
		)
	)
	(wire
		(pts
			(xy 299.72 194.31) (xy 299.72 193.04)
		)
		(stroke
			(width 0)
			(type default)
		)
	)
	(wire
		(pts
			(xy 170.18 273.05) (xy 170.18 279.4)
		)
		(stroke
			(width 0)
			(type default)
		)
	)
	(wire
		(pts
			(xy 27.94 96.52) (xy 34.29 96.52)
		)
		(stroke
			(width 0)
			(type default)
		)
	)
	(wire
		(pts
			(xy 143.51 35.56) (xy 143.51 36.83)
		)
		(stroke
			(width 0)
			(type default)
		)
	)
	(wire
		(pts
			(xy 55.88 257.81) (xy 55.88 256.54)
		)
		(stroke
			(width 0)
			(type default)
		)
	)
	(wire
		(pts
			(xy 346.71 116.84) (xy 355.6 116.84)
		)
		(stroke
			(width 0)
			(type default)
		)
	)
	(wire
		(pts
			(xy 161.29 167.64) (xy 161.29 170.18)
		)
		(stroke
			(width 0)
			(type default)
		)
	)
	(wire
		(pts
			(xy 198.12 210.82) (xy 204.47 210.82)
		)
		(stroke
			(width 0)
			(type default)
		)
	)
	(wire
		(pts
			(xy 311.15 39.37) (xy 311.15 40.64)
		)
		(stroke
			(width 0)
			(type default)
		)
	)
	(wire
		(pts
			(xy 177.8 212.09) (xy 191.77 212.09)
		)
		(stroke
			(width 0)
			(type default)
		)
	)
	(wire
		(pts
			(xy 220.98 107.95) (xy 220.98 109.22)
		)
		(stroke
			(width 0)
			(type default)
		)
	)
	(wire
		(pts
			(xy 233.68 101.6) (xy 233.68 106.68)
		)
		(stroke
			(width 0)
			(type default)
		)
	)
	(wire
		(pts
			(xy 199.39 219.71) (xy 198.12 219.71)
		)
		(stroke
			(width 0)
			(type default)
		)
	)
	(wire
		(pts
			(xy 303.53 57.15) (xy 303.53 58.42)
		)
		(stroke
			(width 0)
			(type default)
		)
	)
	(wire
		(pts
			(xy 162.56 259.08) (xy 170.18 259.08)
		)
		(stroke
			(width 0)
			(type default)
		)
	)
	(wire
		(pts
			(xy 162.56 58.42) (xy 162.56 59.69)
		)
		(stroke
			(width 0)
			(type default)
		)
	)
	(wire
		(pts
			(xy 214.63 175.26) (xy 215.9 175.26)
		)
		(stroke
			(width 0)
			(type default)
		)
	)
	(wire
		(pts
			(xy 214.63 232.41) (xy 215.9 232.41)
		)
		(stroke
			(width 0)
			(type default)
		)
	)
	(wire
		(pts
			(xy 16.51 180.34) (xy 16.51 181.61)
		)
		(stroke
			(width 0)
			(type default)
		)
	)
	(wire
		(pts
			(xy 162.56 35.56) (xy 162.56 38.1)
		)
		(stroke
			(width 0)
			(type default)
		)
	)
	(wire
		(pts
			(xy 21.59 252.73) (xy 21.59 254)
		)
		(stroke
			(width 0)
			(type default)
		)
	)
	(wire
		(pts
			(xy 266.7 124.46) (xy 266.7 128.27)
		)
		(stroke
			(width 0)
			(type default)
		)
	)
	(wire
		(pts
			(xy 151.13 35.56) (xy 154.94 35.56)
		)
		(stroke
			(width 0)
			(type default)
		)
	)
	(wire
		(pts
			(xy 30.48 160.02) (xy 30.48 158.75)
		)
		(stroke
			(width 0)
			(type default)
		)
	)
	(wire
		(pts
			(xy 214.63 219.71) (xy 215.9 219.71)
		)
		(stroke
			(width 0)
			(type default)
		)
	)
	(wire
		(pts
			(xy 275.59 124.46) (xy 275.59 128.27)
		)
		(stroke
			(width 0)
			(type default)
		)
	)
	(wire
		(pts
			(xy 365.76 116.84) (xy 367.03 116.84)
		)
		(stroke
			(width 0)
			(type default)
		)
	)
	(wire
		(pts
			(xy 222.25 212.09) (xy 232.41 212.09)
		)
		(stroke
			(width 0)
			(type default)
		)
	)
	(wire
		(pts
			(xy 177.8 259.08) (xy 191.77 259.08)
		)
		(stroke
			(width 0)
			(type default)
		)
	)
	(wire
		(pts
			(xy 48.26 96.52) (xy 92.71 96.52)
		)
		(stroke
			(width 0)
			(type default)
		)
	)
	(wire
		(pts
			(xy 143.51 226.06) (xy 143.51 232.41)
		)
		(stroke
			(width 0)
			(type default)
		)
	)
	(wire
		(pts
			(xy 360.68 43.18) (xy 360.68 38.1)
		)
		(stroke
			(width 0)
			(type default)
		)
	)
	(wire
		(pts
			(xy 40.64 96.52) (xy 48.26 96.52)
		)
		(stroke
			(width 0)
			(type default)
		)
	)
	(wire
		(pts
			(xy 170.18 66.04) (xy 170.18 68.58)
		)
		(stroke
			(width 0)
			(type default)
		)
	)
	(wire
		(pts
			(xy 48.26 96.52) (xy 48.26 100.33)
		)
		(stroke
			(width 0)
			(type default)
		)
	)
	(wire
		(pts
			(xy 214.63 224.79) (xy 215.9 224.79)
		)
		(stroke
			(width 0)
			(type default)
		)
	)
	(wire
		(pts
			(xy 285.75 57.15) (xy 285.75 58.42)
		)
		(stroke
			(width 0)
			(type default)
		)
	)
	(wire
		(pts
			(xy 58.42 165.1) (xy 69.85 165.1)
		)
		(stroke
			(width 0)
			(type default)
		)
	)
	(wire
		(pts
			(xy 143.51 212.09) (xy 154.94 212.09)
		)
		(stroke
			(width 0)
			(type default)
		)
	)
	(wire
		(pts
			(xy 91.44 59.69) (xy 90.17 59.69)
		)
		(stroke
			(width 0)
			(type default)
		)
	)
	(wire
		(pts
			(xy 198.12 229.87) (xy 198.12 234.95)
		)
		(stroke
			(width 0)
			(type default)
		)
	)
	(wire
		(pts
			(xy 74.93 111.76) (xy 92.71 111.76)
		)
		(stroke
			(width 0)
			(type default)
		)
	)
	(wire
		(pts
			(xy 26.67 180.34) (xy 38.1 180.34)
		)
		(stroke
			(width 0)
			(type default)
		)
	)
	(wire
		(pts
			(xy 294.64 52.07) (xy 294.64 48.26)
		)
		(stroke
			(width 0)
			(type default)
		)
	)
	(wire
		(pts
			(xy 222.25 250.19) (xy 222.25 259.08)
		)
		(stroke
			(width 0)
			(type default)
		)
	)
	(wire
		(pts
			(xy 383.54 48.26) (xy 383.54 49.53)
		)
		(stroke
			(width 0)
			(type default)
		)
	)
	(wire
		(pts
			(xy 170.18 259.08) (xy 177.8 259.08)
		)
		(stroke
			(width 0)
			(type default)
		)
	)
	(wire
		(pts
			(xy 372.11 38.1) (xy 374.65 38.1)
		)
		(stroke
			(width 0)
			(type default)
		)
	)
	(wire
		(pts
			(xy 220.98 54.61) (xy 220.98 55.88)
		)
		(stroke
			(width 0)
			(type default)
		)
	)
	(wire
		(pts
			(xy 140.97 172.72) (xy 140.97 167.64)
		)
		(stroke
			(width 0)
			(type default)
		)
	)
	(wire
		(pts
			(xy 177.8 58.42) (xy 177.8 59.69)
		)
		(stroke
			(width 0)
			(type default)
		)
	)
	(wire
		(pts
			(xy 222.25 203.2) (xy 222.25 212.09)
		)
		(stroke
			(width 0)
			(type default)
		)
	)
	(wire
		(pts
			(xy 114.3 224.79) (xy 115.57 224.79)
		)
		(stroke
			(width 0)
			(type default)
		)
	)
	(bus
		(pts
			(xy 193.04 31.75) (xy 191.77 30.48)
		)
		(stroke
			(width 0)
			(type default)
		)
	)
	(wire
		(pts
			(xy 215.9 165.1) (xy 215.9 166.37)
		)
		(stroke
			(width 0)
			(type default)
		)
	)
	(polyline
		(pts
			(xy 12.7 194.31) (xy 250.19 194.31)
		)
		(stroke
			(width 0)
			(type default)
		)
	)
	(wire
		(pts
			(xy 177.8 50.8) (xy 185.42 50.8)
		)
		(stroke
			(width 0)
			(type default)
		)
	)
	(wire
		(pts
			(xy 90.17 191.77) (xy 90.17 182.88)
		)
		(stroke
			(width 0)
			(type default)
		)
	)
	(wire
		(pts
			(xy 198.12 203.2) (xy 198.12 204.47)
		)
		(stroke
			(width 0)
			(type default)
		)
	)
	(wire
		(pts
			(xy 198.12 210.82) (xy 198.12 219.71)
		)
		(stroke
			(width 0)
			(type default)
		)
	)
	(wire
		(pts
			(xy 177.8 101.6) (xy 185.42 101.6)
		)
		(stroke
			(width 0)
			(type default)
		)
	)
	(wire
		(pts
			(xy 374.65 38.1) (xy 374.65 43.18)
		)
		(stroke
			(width 0)
			(type default)
		)
	)
	(wire
		(pts
			(xy 154.94 101.6) (xy 154.94 104.14)
		)
		(stroke
			(width 0)
			(type default)
		)
	)
	(wire
		(pts
			(xy 143.51 265.43) (xy 143.51 266.7)
		)
		(stroke
			(width 0)
			(type default)
		)
	)
	(wire
		(pts
			(xy 262.89 52.07) (xy 262.89 50.8)
		)
		(stroke
			(width 0)
			(type default)
		)
	)
	(wire
		(pts
			(xy 214.63 187.96) (xy 215.9 187.96)
		)
		(stroke
			(width 0)
			(type default)
		)
	)
	(wire
		(pts
			(xy 48.26 207.01) (xy 92.71 207.01)
		)
		(stroke
			(width 0)
			(type default)
		)
	)
	(wire
		(pts
			(xy 130.81 256.54) (xy 130.81 254)
		)
		(stroke
			(width 0)
			(type default)
		)
	)
	(wire
		(pts
			(xy 191.77 158.75) (xy 191.77 167.64)
		)
		(stroke
			(width 0)
			(type default)
		)
	)
	(wire
		(pts
			(xy 232.41 223.52) (xy 232.41 232.41)
		)
		(stroke
			(width 0)
			(type default)
		)
	)
	(wire
		(pts
			(xy 114.3 167.64) (xy 134.62 167.64)
		)
		(stroke
			(width 0)
			(type default)
		)
	)
	(wire
		(pts
			(xy 331.47 116.84) (xy 336.55 116.84)
		)
		(stroke
			(width 0)
			(type default)
		)
	)
	(wire
		(pts
			(xy 177.8 43.18) (xy 177.8 44.45)
		)
		(stroke
			(width 0)
			(type default)
		)
	)
	(wire
		(pts
			(xy 21.59 205.74) (xy 21.59 207.01)
		)
		(stroke
			(width 0)
			(type default)
		)
	)
	(wire
		(pts
			(xy 255.27 57.15) (xy 255.27 58.42)
		)
		(stroke
			(width 0)
			(type default)
		)
	)
	(wire
		(pts
			(xy 233.68 259.08) (xy 232.41 259.08)
		)
		(stroke
			(width 0)
			(type default)
		)
	)
	(wire
		(pts
			(xy 64.77 219.71) (xy 92.71 219.71)
		)
		(stroke
			(width 0)
			(type default)
		)
	)
	(wire
		(pts
			(xy 64.77 120.65) (xy 64.77 121.92)
		)
		(stroke
			(width 0)
			(type default)
		)
	)
	(wire
		(pts
			(xy 27.94 30.48) (xy 21.59 30.48)
		)
		(stroke
			(width 0)
			(type default)
		)
	)
	(wire
		(pts
			(xy 21.59 96.52) (xy 21.59 100.33)
		)
		(stroke
			(width 0)
			(type default)
		)
	)
	(wire
		(pts
			(xy 78.74 170.18) (xy 92.71 170.18)
		)
		(stroke
			(width 0)
			(type default)
		)
	)
	(wire
		(pts
			(xy 40.64 224.79) (xy 40.64 232.41)
		)
		(stroke
			(width 0)
			(type default)
		)
	)
	(wire
		(pts
			(xy 40.64 271.78) (xy 40.64 279.4)
		)
		(stroke
			(width 0)
			(type default)
		)
	)
	(wire
		(pts
			(xy 114.3 33.02) (xy 130.81 33.02)
		)
		(stroke
			(width 0)
			(type default)
		)
	)
	(wire
		(pts
			(xy 55.88 105.41) (xy 55.88 106.68)
		)
		(stroke
			(width 0)
			(type default)
		)
	)
	(wire
		(pts
			(xy 140.97 217.17) (xy 140.97 212.09)
		)
		(stroke
			(width 0)
			(type default)
		)
	)
	(wire
		(pts
			(xy 40.64 219.71) (xy 40.64 207.01)
		)
		(stroke
			(width 0)
			(type default)
		)
	)
	(wire
		(pts
			(xy 203.2 35.56) (xy 209.55 35.56)
		)
		(stroke
			(width 0)
			(type default)
		)
	)
	(wire
		(pts
			(xy 299.72 187.96) (xy 300.99 187.96)
		)
		(stroke
			(width 0)
			(type default)
		)
	)
	(wire
		(pts
			(xy 194.31 57.15) (xy 204.47 57.15)
		)
		(stroke
			(width 0)
			(type default)
		)
	)
	(wire
		(pts
			(xy 162.56 132.08) (xy 162.56 134.62)
		)
		(stroke
			(width 0)
			(type default)
		)
	)
	(wire
		(pts
			(xy 66.04 175.26) (xy 92.71 175.26)
		)
		(stroke
			(width 0)
			(type default)
		)
	)
	(wire
		(pts
			(xy 21.59 271.78) (xy 21.59 279.4)
		)
		(stroke
			(width 0)
			(type default)
		)
	)
	(wire
		(pts
			(xy 21.59 207.01) (xy 21.59 219.71)
		)
		(stroke
			(width 0)
			(type default)
		)
	)
	(wire
		(pts
			(xy 215.9 279.4) (xy 215.9 278.13)
		)
		(stroke
			(width 0)
			(type default)
		)
	)
	(wire
		(pts
			(xy 34.29 39.37) (xy 34.29 41.91)
		)
		(stroke
			(width 0)
			(type default)
		)
	)
	(wire
		(pts
			(xy 34.29 254) (xy 34.29 266.7)
		)
		(stroke
			(width 0)
			(type default)
		)
	)
	(wire
		(pts
			(xy 151.13 116.84) (xy 151.13 132.08)
		)
		(stroke
			(width 0)
			(type default)
		)
	)
	(wire
		(pts
			(xy 162.56 212.09) (xy 162.56 220.98)
		)
		(stroke
			(width 0)
			(type default)
		)
	)
	(wire
		(pts
			(xy 154.94 35.56) (xy 162.56 35.56)
		)
		(stroke
			(width 0)
			(type default)
		)
	)
	(wire
		(pts
			(xy 114.3 256.54) (xy 130.81 256.54)
		)
		(stroke
			(width 0)
			(type default)
		)
	)
	(wire
		(pts
			(xy 266.7 190.5) (xy 266.7 194.31)
		)
		(stroke
			(width 0)
			(type default)
		)
	)
	(wire
		(pts
			(xy 154.94 212.09) (xy 154.94 220.98)
		)
		(stroke
			(width 0)
			(type default)
		)
	)
	(wire
		(pts
			(xy 215.9 203.2) (xy 222.25 203.2)
		)
		(stroke
			(width 0)
			(type default)
		)
	)
	(wire
		(pts
			(xy 83.82 224.79) (xy 92.71 224.79)
		)
		(stroke
			(width 0)
			(type default)
		)
	)
	(wire
		(pts
			(xy 24.13 158.75) (xy 24.13 160.02)
		)
		(stroke
			(width 0)
			(type default)
		)
	)
	(wire
		(pts
			(xy 262.89 57.15) (xy 262.89 58.42)
		)
		(stroke
			(width 0)
			(type default)
		)
	)
	(wire
		(pts
			(xy 58.42 171.45) (xy 58.42 172.72)
		)
		(stroke
			(width 0)
			(type default)
		)
	)
	(wire
		(pts
			(xy 83.82 278.13) (xy 83.82 279.4)
		)
		(stroke
			(width 0)
			(type default)
		)
	)
	(wire
		(pts
			(xy 72.39 256.54) (xy 72.39 269.24)
		)
		(stroke
			(width 0)
			(type default)
		)
	)
	(wire
		(pts
			(xy 72.39 209.55) (xy 72.39 222.25)
		)
		(stroke
			(width 0)
			(type default)
		)
	)
	(wire
		(pts
			(xy 114.3 182.88) (xy 115.57 182.88)
		)
		(stroke
			(width 0)
			(type default)
		)
	)
	(wire
		(pts
			(xy 27.94 207.01) (xy 34.29 207.01)
		)
		(stroke
			(width 0)
			(type default)
		)
	)
	(wire
		(pts
			(xy 55.88 217.17) (xy 92.71 217.17)
		)
		(stroke
			(width 0)
			(type default)
		)
	)
	(wire
		(pts
			(xy 360.68 38.1) (xy 363.22 38.1)
		)
		(stroke
			(width 0)
			(type default)
		)
	)
	(wire
		(pts
			(xy 177.8 73.66) (xy 177.8 74.93)
		)
		(stroke
			(width 0)
			(type default)
		)
	)
	(wire
		(pts
			(xy 176.53 167.64) (xy 176.53 170.18)
		)
		(stroke
			(width 0)
			(type default)
		)
	)
	(wire
		(pts
			(xy 170.18 50.8) (xy 177.8 50.8)
		)
		(stroke
			(width 0)
			(type default)
		)
	)
	(wire
		(pts
			(xy 170.18 116.84) (xy 170.18 119.38)
		)
		(stroke
			(width 0)
			(type default)
		)
	)
	(wire
		(pts
			(xy 34.29 254) (xy 40.64 254)
		)
		(stroke
			(width 0)
			(type default)
		)
	)
	(wire
		(pts
			(xy 177.8 35.56) (xy 177.8 38.1)
		)
		(stroke
			(width 0)
			(type default)
		)
	)
	(wire
		(pts
			(xy 154.94 226.06) (xy 154.94 232.41)
		)
		(stroke
			(width 0)
			(type default)
		)
	)
	(wire
		(pts
			(xy 27.94 266.7) (xy 27.94 254)
		)
		(stroke
			(width 0)
			(type default)
		)
	)
	(bus
		(pts
			(xy 193.04 119.38) (xy 193.04 121.92)
		)
		(stroke
			(width 0)
			(type default)
		)
	)
	(wire
		(pts
			(xy 162.56 66.04) (xy 162.56 68.58)
		)
		(stroke
			(width 0)
			(type default)
		)
	)
	(wire
		(pts
			(xy 115.57 116.84) (xy 115.57 114.3)
		)
		(stroke
			(width 0)
			(type default)
		)
	)
	(wire
		(pts
			(xy 266.7 181.61) (xy 266.7 182.88)
		)
		(stroke
			(width 0)
			(type default)
		)
	)
	(wire
		(pts
			(xy 222.25 259.08) (xy 232.41 259.08)
		)
		(stroke
			(width 0)
			(type default)
		)
	)
	(wire
		(pts
			(xy 16.51 157.48) (xy 16.51 158.75)
		)
		(stroke
			(width 0)
			(type default)
		)
	)
	(bus
		(pts
			(xy 185.42 270.51) (xy 185.42 273.05)
		)
		(stroke
			(width 0)
			(type default)
		)
	)
	(wire
		(pts
			(xy 27.94 219.71) (xy 27.94 207.01)
		)
		(stroke
			(width 0)
			(type default)
		)
	)
	(wire
		(pts
			(xy 220.98 35.56) (xy 233.68 35.56)
		)
		(stroke
			(width 0)
			(type default)
		)
	)
	(wire
		(pts
			(xy 186.69 271.78) (xy 198.12 271.78)
		)
		(stroke
			(width 0)
			(type default)
		)
	)
	(wire
		(pts
			(xy 232.41 212.09) (xy 232.41 218.44)
		)
		(stroke
			(width 0)
			(type default)
		)
	)
	(wire
		(pts
			(xy 114.3 106.68) (xy 140.97 106.68)
		)
		(stroke
			(width 0)
			(type default)
		)
	)
	(wire
		(pts
			(xy 90.17 50.8) (xy 92.71 50.8)
		)
		(stroke
			(width 0)
			(type default)
		)
	)
	(wire
		(pts
			(xy 203.2 36.83) (xy 203.2 35.56)
		)
		(stroke
			(width 0)
			(type default)
		)
	)
	(wire
		(pts
			(xy 222.25 179.07) (xy 222.25 180.34)
		)
		(stroke
			(width 0)
			(type default)
		)
	)
	(wire
		(pts
			(xy 278.13 35.56) (xy 289.56 35.56)
		)
		(stroke
			(width 0)
			(type default)
		)
	)
	(bus
		(pts
			(xy 193.04 97.79) (xy 193.04 119.38)
		)
		(stroke
			(width 0)
			(type default)
		)
	)
	(wire
		(pts
			(xy 200.66 125.73) (xy 204.47 125.73)
		)
		(stroke
			(width 0)
			(type default)
		)
	)
	(wire
		(pts
			(xy 300.99 124.46) (xy 299.72 124.46)
		)
		(stroke
			(width 0)
			(type default)
		)
	)
	(wire
		(pts
			(xy 114.3 212.09) (xy 134.62 212.09)
		)
		(stroke
			(width 0)
			(type default)
		)
	)
	(wire
		(pts
			(xy 114.3 101.6) (xy 134.62 101.6)
		)
		(stroke
			(width 0)
			(type default)
		)
	)
	(wire
		(pts
			(xy 255.27 33.02) (xy 262.89 33.02)
		)
		(stroke
			(width 0)
			(type default)
		)
	)
	(wire
		(pts
			(xy 143.51 173.99) (xy 143.51 175.26)
		)
		(stroke
			(width 0)
			(type default)
		)
	)
	(wire
		(pts
			(xy 331.47 182.88) (xy 336.55 182.88)
		)
		(stroke
			(width 0)
			(type default)
		)
	)
	(wire
		(pts
			(xy 64.77 266.7) (xy 64.77 273.05)
		)
		(stroke
			(width 0)
			(type default)
		)
	)
	(bus
		(pts
			(xy 185.42 223.52) (xy 185.42 226.06)
		)
		(stroke
			(width 0)
			(type default)
		)
	)
	(wire
		(pts
			(xy 383.54 38.1) (xy 386.08 38.1)
		)
		(stroke
			(width 0)
			(type default)
		)
	)
	(wire
		(pts
			(xy 199.39 175.26) (xy 198.12 175.26)
		)
		(stroke
			(width 0)
			(type default)
		)
	)
	(wire
		(pts
			(xy 232.41 257.81) (xy 232.41 259.08)
		)
		(stroke
			(width 0)
			(type default)
		)
	)
	(wire
		(pts
			(xy 74.93 181.61) (xy 74.93 177.8)
		)
		(stroke
			(width 0)
			(type default)
		)
	)
	(wire
		(pts
			(xy 27.94 34.29) (xy 27.94 30.48)
		)
		(stroke
			(width 0)
			(type default)
		)
	)
	(wire
		(pts
			(xy 220.98 127) (xy 220.98 128.27)
		)
		(stroke
			(width 0)
			(type default)
		)
	)
	(wire
		(pts
			(xy 143.51 107.95) (xy 143.51 109.22)
		)
		(stroke
			(width 0)
			(type default)
		)
	)
	(bus
		(pts
			(xy 185.42 255.27) (xy 185.42 270.51)
		)
		(stroke
			(width 0)
			(type default)
		)
	)
	(wire
		(pts
			(xy 215.9 271.78) (xy 215.9 273.05)
		)
		(stroke
			(width 0)
			(type default)
		)
	)
	(wire
		(pts
			(xy 58.42 181.61) (xy 58.42 172.72)
		)
		(stroke
			(width 0)
			(type default)
		)
	)
	(wire
		(pts
			(xy 227.33 119.38) (xy 227.33 120.65)
		)
		(stroke
			(width 0)
			(type default)
		)
	)
	(wire
		(pts
			(xy 191.77 203.2) (xy 191.77 212.09)
		)
		(stroke
			(width 0)
			(type default)
		)
	)
	(wire
		(pts
			(xy 140.97 167.64) (xy 143.51 167.64)
		)
		(stroke
			(width 0)
			(type default)
		)
	)
	(wire
		(pts
			(xy 215.9 180.34) (xy 215.9 181.61)
		)
		(stroke
			(width 0)
			(type default)
		)
	)
	(wire
		(pts
			(xy 198.12 209.55) (xy 198.12 210.82)
		)
		(stroke
			(width 0)
			(type default)
		)
	)
	(wire
		(pts
			(xy 198.12 165.1) (xy 198.12 166.37)
		)
		(stroke
			(width 0)
			(type default)
		)
	)
	(wire
		(pts
			(xy 34.29 224.79) (xy 34.29 232.41)
		)
		(stroke
			(width 0)
			(type default)
		)
	)
	(wire
		(pts
			(xy 215.9 224.79) (xy 215.9 226.06)
		)
		(stroke
			(width 0)
			(type default)
		)
	)
	(wire
		(pts
			(xy 278.13 41.91) (xy 278.13 43.18)
		)
		(stroke
			(width 0)
			(type default)
		)
	)
	(wire
		(pts
			(xy 55.88 278.13) (xy 55.88 279.4)
		)
		(stroke
			(width 0)
			(type default)
		)
	)
	(wire
		(pts
			(xy 294.64 57.15) (xy 294.64 58.42)
		)
		(stroke
			(width 0)
			(type default)
		)
	)
	(wire
		(pts
			(xy 170.18 101.6) (xy 170.18 104.14)
		)
		(stroke
			(width 0)
			(type default)
		)
	)
	(bus
		(pts
			(xy 185.42 208.28) (xy 185.42 223.52)
		)
		(stroke
			(width 0)
			(type default)
		)
	)
	(wire
		(pts
			(xy 215.9 203.2) (xy 209.55 203.2)
		)
		(stroke
			(width 0)
			(type default)
		)
	)
	(wire
		(pts
			(xy 27.94 39.37) (xy 27.94 41.91)
		)
		(stroke
			(width 0)
			(type default)
		)
	)
	(wire
		(pts
			(xy 72.39 231.14) (xy 72.39 232.41)
		)
		(stroke
			(width 0)
			(type default)
		)
	)
	(wire
		(pts
			(xy 27.94 207.01) (xy 21.59 207.01)
		)
		(stroke
			(width 0)
			(type default)
		)
	)
	(wire
		(pts
			(xy 198.12 256.54) (xy 198.12 257.81)
		)
		(stroke
			(width 0)
			(type default)
		)
	)
	(wire
		(pts
			(xy 251.46 31.75) (xy 251.46 33.02)
		)
		(stroke
			(width 0)
			(type default)
		)
	)
	(wire
		(pts
			(xy 363.22 46.99) (xy 363.22 45.72)
		)
		(stroke
			(width 0)
			(type default)
		)
	)
	(wire
		(pts
			(xy 170.18 58.42) (xy 170.18 59.69)
		)
		(stroke
			(width 0)
			(type default)
		)
	)
	(wire
		(pts
			(xy 162.56 66.04) (xy 170.18 66.04)
		)
		(stroke
			(width 0)
			(type default)
		)
	)
	(wire
		(pts
			(xy 72.39 222.25) (xy 92.71 222.25)
		)
		(stroke
			(width 0)
			(type default)
		)
	)
	(wire
		(pts
			(xy 114.3 99.06) (xy 130.81 99.06)
		)
		(stroke
			(width 0)
			(type default)
		)
	)
	(wire
		(pts
			(xy 48.26 30.48) (xy 92.71 30.48)
		)
		(stroke
			(width 0)
			(type default)
		)
	)
	(wire
		(pts
			(xy 255.27 50.8) (xy 251.46 50.8)
		)
		(stroke
			(width 0)
			(type default)
		)
	)
	(wire
		(pts
			(xy 177.8 109.22) (xy 177.8 110.49)
		)
		(stroke
			(width 0)
			(type default)
		)
	)
	(wire
		(pts
			(xy 336.55 116.84) (xy 336.55 118.11)
		)
		(stroke
			(width 0)
			(type default)
		)
	)
	(wire
		(pts
			(xy 154.94 66.04) (xy 154.94 68.58)
		)
		(stroke
			(width 0)
			(type default)
		)
	)
	(wire
		(pts
			(xy 162.56 109.22) (xy 162.56 110.49)
		)
		(stroke
			(width 0)
			(type default)
		)
	)
	(wire
		(pts
			(xy 48.26 207.01) (xy 48.26 219.71)
		)
		(stroke
			(width 0)
			(type default)
		)
	)
	(wire
		(pts
			(xy 129.54 96.52) (xy 130.81 96.52)
		)
		(stroke
			(width 0)
			(type default)
		)
	)
	(wire
		(pts
			(xy 162.56 259.08) (xy 162.56 267.97)
		)
		(stroke
			(width 0)
			(type default)
		)
	)
	(wire
		(pts
			(xy 154.94 35.56) (xy 154.94 38.1)
		)
		(stroke
			(width 0)
			(type default)
		)
	)
	(wire
		(pts
			(xy 203.2 62.23) (xy 204.47 62.23)
		)
		(stroke
			(width 0)
			(type default)
		)
	)
	(wire
		(pts
			(xy 143.51 35.56) (xy 151.13 35.56)
		)
		(stroke
			(width 0)
			(type default)
		)
	)
	(wire
		(pts
			(xy 58.42 165.1) (xy 58.42 166.37)
		)
		(stroke
			(width 0)
			(type default)
		)
	)
	(wire
		(pts
			(xy 27.94 105.41) (xy 27.94 107.95)
		)
		(stroke
			(width 0)
			(type default)
		)
	)
	(wire
		(pts
			(xy 372.11 55.88) (xy 372.11 38.1)
		)
		(stroke
			(width 0)
			(type default)
		)
	)
	(wire
		(pts
			(xy 143.51 101.6) (xy 151.13 101.6)
		)
		(stroke
			(width 0)
			(type default)
		)
	)
	(wire
		(pts
			(xy 374.65 55.88) (xy 374.65 57.15)
		)
		(stroke
			(width 0)
			(type default)
		)
	)
	(wire
		(pts
			(xy 222.25 223.52) (xy 222.25 224.79)
		)
		(stroke
			(width 0)
			(type default)
		)
	)
	(wire
		(pts
			(xy 185.42 35.56) (xy 185.42 38.1)
		)
		(stroke
			(width 0)
			(type default)
		)
	)
	(wire
		(pts
			(xy 83.82 120.65) (xy 83.82 121.92)
		)
		(stroke
			(width 0)
			(type default)
		)
	)
	(wire
		(pts
			(xy 43.18 158.75) (xy 50.8 158.75)
		)
		(stroke
			(width 0)
			(type default)
		)
	)
	(wire
		(pts
			(xy 55.88 99.06) (xy 55.88 100.33)
		)
		(stroke
			(width 0)
			(type default)
		)
	)
	(wire
		(pts
			(xy 35.56 135.89) (xy 36.83 135.89)
		)
		(stroke
			(width 0)
			(type default)
		)
	)
	(wire
		(pts
			(xy 219.71 49.53) (xy 220.98 49.53)
		)
		(stroke
			(width 0)
			(type default)
		)
	)
	(wire
		(pts
			(xy 383.54 62.23) (xy 383.54 63.5)
		)
		(stroke
			(width 0)
			(type default)
		)
	)
	(wire
		(pts
			(xy 114.3 254) (xy 124.46 254)
		)
		(stroke
			(width 0)
			(type default)
		)
	)
	(wire
		(pts
			(xy 219.71 115.57) (xy 220.98 115.57)
		)
		(stroke
			(width 0)
			(type default)
		)
	)
	(wire
		(pts
			(xy 114.3 266.7) (xy 143.51 266.7)
		)
		(stroke
			(width 0)
			(type default)
		)
	)
	(wire
		(pts
			(xy 220.98 35.56) (xy 220.98 36.83)
		)
		(stroke
			(width 0)
			(type default)
		)
	)
	(wire
		(pts
			(xy 185.42 66.04) (xy 185.42 68.58)
		)
		(stroke
			(width 0)
			(type default)
		)
	)
	(wire
		(pts
			(xy 294.64 48.26) (xy 312.42 48.26)
		)
		(stroke
			(width 0)
			(type default)
		)
	)
	(wire
		(pts
			(xy 219.71 120.65) (xy 220.98 120.65)
		)
		(stroke
			(width 0)
			(type default)
		)
	)
	(wire
		(pts
			(xy 143.51 167.64) (xy 143.51 168.91)
		)
		(stroke
			(width 0)
			(type default)
		)
	)
	(wire
		(pts
			(xy 363.22 44.45) (xy 363.22 45.72)
		)
		(stroke
			(width 0)
			(type default)
		)
	)
	(wire
		(pts
			(xy 232.41 181.61) (xy 232.41 187.96)
		)
		(stroke
			(width 0)
			(type default)
		)
	)
	(wire
		(pts
			(xy 130.81 30.48) (xy 130.81 33.02)
		)
		(stroke
			(width 0)
			(type default)
		)
	)
	(wire
		(pts
			(xy 87.63 38.1) (xy 92.71 38.1)
		)
		(stroke
			(width 0)
			(type default)
		)
	)
	(wire
		(pts
			(xy 275.59 116.84) (xy 300.99 116.84)
		)
		(stroke
			(width 0)
			(type default)
		)
	)
	(wire
		(pts
			(xy 185.42 73.66) (xy 185.42 74.93)
		)
		(stroke
			(width 0)
			(type default)
		)
	)
	(wire
		(pts
			(xy 170.18 66.04) (xy 177.8 66.04)
		)
		(stroke
			(width 0)
			(type default)
		)
	)
	(wire
		(pts
			(xy 114.3 175.26) (xy 143.51 175.26)
		)
		(stroke
			(width 0)
			(type default)
		)
	)
	(wire
		(pts
			(xy 299.72 193.04) (xy 300.99 193.04)
		)
		(stroke
			(width 0)
			(type default)
		)
	)
	(wire
		(pts
			(xy 64.77 109.22) (xy 92.71 109.22)
		)
		(stroke
			(width 0)
			(type default)
		)
	)
	(wire
		(pts
			(xy 34.29 105.41) (xy 34.29 107.95)
		)
		(stroke
			(width 0)
			(type default)
		)
	)
	(wire
		(pts
			(xy 227.33 53.34) (xy 227.33 54.61)
		)
		(stroke
			(width 0)
			(type default)
		)
	)
	(wire
		(pts
			(xy 374.65 181.61) (xy 374.65 182.88)
		)
		(stroke
			(width 0)
			(type default)
		)
	)
	(wire
		(pts
			(xy 334.01 43.18) (xy 360.68 43.18)
		)
		(stroke
			(width 0)
			(type default)
		)
	)
	(wire
		(pts
			(xy 334.01 33.02) (xy 344.17 33.02)
		)
		(stroke
			(width 0)
			(type default)
		)
	)
	(wire
		(pts
			(xy 177.8 66.04) (xy 177.8 68.58)
		)
		(stroke
			(width 0)
			(type default)
		)
	)
	(wire
		(pts
			(xy 194.31 120.65) (xy 204.47 120.65)
		)
		(stroke
			(width 0)
			(type default)
		)
	)
	(wire
		(pts
			(xy 83.82 104.14) (xy 92.71 104.14)
		)
		(stroke
			(width 0)
			(type default)
		)
	)
	(wire
		(pts
			(xy 215.9 250.19) (xy 222.25 250.19)
		)
		(stroke
			(width 0)
			(type default)
		)
	)
	(wire
		(pts
			(xy 266.7 116.84) (xy 275.59 116.84)
		)
		(stroke
			(width 0)
			(type default)
		)
	)
	(wire
		(pts
			(xy 21.59 96.52) (xy 27.94 96.52)
		)
		(stroke
			(width 0)
			(type default)
		)
	)
	(bus
		(pts
			(xy 187.96 96.52) (xy 191.77 96.52)
		)
		(stroke
			(width 0)
			(type default)
		)
	)
	(wire
		(pts
			(xy 278.13 43.18) (xy 312.42 43.18)
		)
		(stroke
			(width 0)
			(type default)
		)
	)
	(wire
		(pts
			(xy 365.76 182.88) (xy 367.03 182.88)
		)
		(stroke
			(width 0)
			(type default)
		)
	)
	(bus
		(pts
			(xy 180.34 254) (xy 184.15 254)
		)
		(stroke
			(width 0)
			(type default)
		)
	)
	(wire
		(pts
			(xy 140.97 35.56) (xy 143.51 35.56)
		)
		(stroke
			(width 0)
			(type default)
		)
	)
	(wire
		(pts
			(xy 203.2 109.22) (xy 203.2 107.95)
		)
		(stroke
			(width 0)
			(type default)
		)
	)
	(wire
		(pts
			(xy 346.71 116.84) (xy 336.55 116.84)
		)
		(stroke
			(width 0)
			(type default)
		)
	)
	(wire
		(pts
			(xy 153.67 175.26) (xy 153.67 176.53)
		)
		(stroke
			(width 0)
			(type default)
		)
	)
	(wire
		(pts
			(xy 186.69 274.32) (xy 199.39 274.32)
		)
		(stroke
			(width 0)
			(type default)
		)
	)
	(wire
		(pts
			(xy 266.7 182.88) (xy 275.59 182.88)
		)
		(stroke
			(width 0)
			(type default)
		)
	)
	(wire
		(pts
			(xy 48.26 135.89) (xy 60.96 135.89)
		)
		(stroke
			(width 0)
			(type default)
		)
	)
	(wire
		(pts
			(xy 48.26 271.78) (xy 48.26 279.4)
		)
		(stroke
			(width 0)
			(type default)
		)
	)
	(wire
		(pts
			(xy 215.9 186.69) (xy 215.9 187.96)
		)
		(stroke
			(width 0)
			(type default)
		)
	)
	(wire
		(pts
			(xy 285.75 45.72) (xy 312.42 45.72)
		)
		(stroke
			(width 0)
			(type default)
		)
	)
	(wire
		(pts
			(xy 299.72 190.5) (xy 299.72 193.04)
		)
		(stroke
			(width 0)
			(type default)
		)
	)
	(wire
		(pts
			(xy 21.59 30.48) (xy 21.59 34.29)
		)
		(stroke
			(width 0)
			(type default)
		)
	)
	(wire
		(pts
			(xy 58.42 172.72) (xy 92.71 172.72)
		)
		(stroke
			(width 0)
			(type default)
		)
	)
	(wire
		(pts
			(xy 374.65 62.23) (xy 374.65 63.5)
		)
		(stroke
			(width 0)
			(type default)
		)
	)
	(wire
		(pts
			(xy 355.6 182.88) (xy 365.76 182.88)
		)
		(stroke
			(width 0)
			(type default)
		)
	)
	(wire
		(pts
			(xy 194.31 123.19) (xy 203.2 123.19)
		)
		(stroke
			(width 0)
			(type default)
		)
	)
	(polyline
		(pts
			(xy 12.7 242.57) (xy 248.285 242.57)
		)
		(stroke
			(width 0)
			(type default)
		)
	)
	(wire
		(pts
			(xy 262.89 33.02) (xy 271.78 33.02)
		)
		(stroke
			(width 0)
			(type default)
		)
	)
	(wire
		(pts
			(xy 299.72 127) (xy 300.99 127)
		)
		(stroke
			(width 0)
			(type default)
		)
	)
	(wire
		(pts
			(xy 220.98 41.91) (xy 220.98 43.18)
		)
		(stroke
			(width 0)
			(type default)
		)
	)
	(wire
		(pts
			(xy 34.29 271.78) (xy 34.29 279.4)
		)
		(stroke
			(width 0)
			(type default)
		)
	)
	(wire
		(pts
			(xy 69.85 165.1) (xy 69.85 177.8)
		)
		(stroke
			(width 0)
			(type default)
		)
	)
	(wire
		(pts
			(xy 151.13 101.6) (xy 151.13 116.84)
		)
		(stroke
			(width 0)
			(type default)
		)
	)
	(wire
		(pts
			(xy 48.26 134.62) (xy 48.26 135.89)
		)
		(stroke
			(width 0)
			(type default)
		)
	)
	(wire
		(pts
			(xy 143.51 212.09) (xy 143.51 213.36)
		)
		(stroke
			(width 0)
			(type default)
		)
	)
	(wire
		(pts
			(xy 162.56 50.8) (xy 170.18 50.8)
		)
		(stroke
			(width 0)
			(type default)
		)
	)
	(wire
		(pts
			(xy 262.89 43.18) (xy 262.89 44.45)
		)
		(stroke
			(width 0)
			(type default)
		)
	)
	(wire
		(pts
			(xy 72.39 49.53) (xy 72.39 45.72)
		)
		(stroke
			(width 0)
			(type default)
		)
	)
	(wire
		(pts
			(xy 114.3 43.18) (xy 143.51 43.18)
		)
		(stroke
			(width 0)
			(type default)
		)
	)
	(wire
		(pts
			(xy 114.3 207.01) (xy 124.46 207.01)
		)
		(stroke
			(width 0)
			(type default)
		)
	)
	(wire
		(pts
			(xy 214.63 266.7) (xy 215.9 266.7)
		)
		(stroke
			(width 0)
			(type default)
		)
	)
	(polyline
		(pts
			(xy 27.305 259.08) (xy 27.305 259.715)
		)
		(stroke
			(width 0)
			(type default)
		)
	)
	(wire
		(pts
			(xy 203.2 62.23) (xy 203.2 64.77)
		)
		(stroke
			(width 0)
			(type default)
		)
	)
	(wire
		(pts
			(xy 115.57 279.4) (xy 115.57 274.32)
		)
		(stroke
			(width 0)
			(type default)
		)
	)
	(wire
		(pts
			(xy 64.77 219.71) (xy 64.77 226.06)
		)
		(stroke
			(width 0)
			(type default)
		)
	)
	(wire
		(pts
			(xy 194.31 54.61) (xy 204.47 54.61)
		)
		(stroke
			(width 0)
			(type default)
		)
	)
	(wire
		(pts
			(xy 215.9 224.79) (xy 222.25 224.79)
		)
		(stroke
			(width 0)
			(type default)
		)
	)
	(wire
		(pts
			(xy 83.82 48.26) (xy 83.82 49.53)
		)
		(stroke
			(width 0)
			(type default)
		)
	)
	(wire
		(pts
			(xy 185.42 124.46) (xy 185.42 125.73)
		)
		(stroke
			(width 0)
			(type default)
		)
	)
	(wire
		(pts
			(xy 198.12 250.19) (xy 198.12 251.46)
		)
		(stroke
			(width 0)
			(type default)
		)
	)
	(wire
		(pts
			(xy 72.39 226.06) (xy 72.39 222.25)
		)
		(stroke
			(width 0)
			(type default)
		)
	)
	(wire
		(pts
			(xy 114.3 259.08) (xy 134.62 259.08)
		)
		(stroke
			(width 0)
			(type default)
		)
	)
	(wire
		(pts
			(xy 204.47 128.27) (xy 203.2 128.27)
		)
		(stroke
			(width 0)
			(type default)
		)
	)
	(wire
		(pts
			(xy 21.59 224.79) (xy 21.59 232.41)
		)
		(stroke
			(width 0)
			(type default)
		)
	)
	(wire
		(pts
			(xy 69.85 177.8) (xy 74.93 177.8)
		)
		(stroke
			(width 0)
			(type default)
		)
	)
	(wire
		(pts
			(xy 154.94 50.8) (xy 151.13 50.8)
		)
		(stroke
			(width 0)
			(type default)
		)
	)
	(wire
		(pts
			(xy 203.2 101.6) (xy 209.55 101.6)
		)
		(stroke
			(width 0)
			(type default)
		)
	)
	(wire
		(pts
			(xy 299.72 124.46) (xy 299.72 127)
		)
		(stroke
			(width 0)
			(type default)
		)
	)
	(wire
		(pts
			(xy 115.57 227.33) (xy 115.57 224.79)
		)
		(stroke
			(width 0)
			(type default)
		)
	)
	(wire
		(pts
			(xy 129.54 30.48) (xy 130.81 30.48)
		)
		(stroke
			(width 0)
			(type default)
		)
	)
	(wire
		(pts
			(xy 271.78 33.02) (xy 271.78 45.72)
		)
		(stroke
			(width 0)
			(type default)
		)
	)
	(wire
		(pts
			(xy 143.51 259.08) (xy 154.94 259.08)
		)
		(stroke
			(width 0)
			(type default)
		)
	)
	(wire
		(pts
			(xy 204.47 115.57) (xy 203.2 115.57)
		)
		(stroke
			(width 0)
			(type default)
		)
	)
	(wire
		(pts
			(xy 266.7 115.57) (xy 266.7 116.84)
		)
		(stroke
			(width 0)
			(type default)
		)
	)
	(wire
		(pts
			(xy 34.29 207.01) (xy 34.29 219.71)
		)
		(stroke
			(width 0)
			(type default)
		)
	)
	(wire
		(pts
			(xy 299.72 128.27) (xy 299.72 127)
		)
		(stroke
			(width 0)
			(type default)
		)
	)
	(wire
		(pts
			(xy 43.18 160.02) (xy 43.18 158.75)
		)
		(stroke
			(width 0)
			(type default)
		)
	)
	(wire
		(pts
			(xy 21.59 254) (xy 27.94 254)
		)
		(stroke
			(width 0)
			(type default)
		)
	)
	(bus
		(pts
			(xy 185.42 208.28) (xy 184.15 207.01)
		)
		(stroke
			(width 0)
			(type default)
		)
	)
	(wire
		(pts
			(xy 198.12 279.4) (xy 198.12 271.78)
		)
		(stroke
			(width 0)
			(type default)
		)
	)
	(wire
		(pts
			(xy 170.18 43.18) (xy 170.18 44.45)
		)
		(stroke
			(width 0)
			(type default)
		)
	)
	(wire
		(pts
			(xy 72.39 33.02) (xy 72.39 45.72)
		)
		(stroke
			(width 0)
			(type default)
		)
	)
	(wire
		(pts
			(xy 21.59 254) (xy 21.59 266.7)
		)
		(stroke
			(width 0)
			(type default)
		)
	)
	(wire
		(pts
			(xy 170.18 259.08) (xy 170.18 267.97)
		)
		(stroke
			(width 0)
			(type default)
		)
	)
	(wire
		(pts
			(xy 363.22 38.1) (xy 363.22 39.37)
		)
		(stroke
			(width 0)
			(type default)
		)
	)
	(polyline
		(pts
			(xy 248.285 12.7) (xy 248.285 284.48)
		)
		(stroke
			(width 0)
			(type default)
		)
	)
	(bus
		(pts
			(xy 187.96 30.48) (xy 191.77 30.48)
		)
		(stroke
			(width 0)
			(type default)
		)
	)
	(wire
		(pts
			(xy 143.51 220.98) (xy 143.51 219.71)
		)
		(stroke
			(width 0)
			(type default)
		)
	)
	(wire
		(pts
			(xy 55.88 209.55) (xy 55.88 210.82)
		)
		(stroke
			(width 0)
			(type default)
		)
	)
	(wire
		(pts
			(xy 83.82 231.14) (xy 83.82 232.41)
		)
		(stroke
			(width 0)
			(type default)
		)
	)
	(wire
		(pts
			(xy 34.29 96.52) (xy 40.64 96.52)
		)
		(stroke
			(width 0)
			(type default)
		)
	)
	(wire
		(pts
			(xy 266.7 182.88) (xy 266.7 185.42)
		)
		(stroke
			(width 0)
			(type default)
		)
	)
	(wire
		(pts
			(xy 115.57 55.88) (xy 115.57 50.8)
		)
		(stroke
			(width 0)
			(type default)
		)
	)
	(wire
		(pts
			(xy 140.97 259.08) (xy 143.51 259.08)
		)
		(stroke
			(width 0)
			(type default)
		)
	)
	(wire
		(pts
			(xy 219.71 62.23) (xy 220.98 62.23)
		)
		(stroke
			(width 0)
			(type default)
		)
	)
	(wire
		(pts
			(xy 215.9 257.81) (xy 215.9 266.7)
		)
		(stroke
			(width 0)
			(type default)
		)
	)
	(wire
		(pts
			(xy 198.12 203.2) (xy 191.77 203.2)
		)
		(stroke
			(width 0)
			(type default)
		)
	)
	(wire
		(pts
			(xy 154.94 132.08) (xy 151.13 132.08)
		)
		(stroke
			(width 0)
			(type default)
		)
	)
	(wire
		(pts
			(xy 87.63 38.1) (xy 87.63 36.83)
		)
		(stroke
			(width 0)
			(type default)
		)
	)
	(wire
		(pts
			(xy 162.56 212.09) (xy 170.18 212.09)
		)
		(stroke
			(width 0)
			(type default)
		)
	)
	(wire
		(pts
			(xy 198.12 257.81) (xy 204.47 257.81)
		)
		(stroke
			(width 0)
			(type default)
		)
	)
	(wire
		(pts
			(xy 154.94 58.42) (xy 154.94 59.69)
		)
		(stroke
			(width 0)
			(type default)
		)
	)
	(wire
		(pts
			(xy 346.71 196.85) (xy 346.71 193.04)
		)
		(stroke
			(width 0)
			(type default)
		)
	)
	(wire
		(pts
			(xy 215.9 279.4) (xy 215.9 280.67)
		)
		(stroke
			(width 0)
			(type default)
		)
	)
	(wire
		(pts
			(xy 143.51 267.97) (xy 143.51 266.7)
		)
		(stroke
			(width 0)
			(type default)
		)
	)
	(wire
		(pts
			(xy 154.94 139.7) (xy 154.94 140.97)
		)
		(stroke
			(width 0)
			(type default)
		)
	)
	(wire
		(pts
			(xy 365.76 182.88) (xy 365.76 187.96)
		)
		(stroke
			(width 0)
			(type default)
		)
	)
	(wire
		(pts
			(xy 129.54 207.01) (xy 130.81 207.01)
		)
		(stroke
			(width 0)
			(type default)
		)
	)
	(wire
		(pts
			(xy 215.9 158.75) (xy 222.25 158.75)
		)
		(stroke
			(width 0)
			(type default)
		)
	)
	(wire
		(pts
			(xy 40.64 207.01) (xy 48.26 207.01)
		)
		(stroke
			(width 0)
			(type default)
		)
	)
	(wire
		(pts
			(xy 185.42 109.22) (xy 185.42 110.49)
		)
		(stroke
			(width 0)
			(type default)
		)
	)
	(wire
		(pts
			(xy 186.69 187.96) (xy 199.39 187.96)
		)
		(stroke
			(width 0)
			(type default)
		)
	)
	(wire
		(pts
			(xy 215.9 187.96) (xy 215.9 190.5)
		)
		(stroke
			(width 0)
			(type default)
		)
	)
	(wire
		(pts
			(xy 114.3 264.16) (xy 140.97 264.16)
		)
		(stroke
			(width 0)
			(type default)
		)
	)
	(wire
		(pts
			(xy 209.55 257.81) (xy 215.9 257.81)
		)
		(stroke
			(width 0)
			(type default)
		)
	)
	(wire
		(pts
			(xy 375.92 116.84) (xy 374.65 116.84)
		)
		(stroke
			(width 0)
			(type default)
		)
	)
	(wire
		(pts
			(xy 316.23 116.84) (xy 326.39 116.84)
		)
		(stroke
			(width 0)
			(type default)
		)
	)
	(wire
		(pts
			(xy 139.7 101.6) (xy 140.97 101.6)
		)
		(stroke
			(width 0)
			(type default)
		)
	)
	(wire
		(pts
			(xy 204.47 250.19) (xy 198.12 250.19)
		)
		(stroke
			(width 0)
			(type default)
		)
	)
	(wire
		(pts
			(xy 170.18 212.09) (xy 177.8 212.09)
		)
		(stroke
			(width 0)
			(type default)
		)
	)
	(wire
		(pts
			(xy 90.17 182.88) (xy 92.71 182.88)
		)
		(stroke
			(width 0)
			(type default)
		)
	)
	(wire
		(pts
			(xy 365.76 196.85) (xy 365.76 193.04)
		)
		(stroke
			(width 0)
			(type default)
		)
	)
	(wire
		(pts
			(xy 34.29 207.01) (xy 40.64 207.01)
		)
		(stroke
			(width 0)
			(type default)
		)
	)
	(wire
		(pts
			(xy 215.9 256.54) (xy 215.9 257.81)
		)
		(stroke
			(width 0)
			(type default)
		)
	)
	(wire
		(pts
			(xy 177.8 124.46) (xy 177.8 125.73)
		)
		(stroke
			(width 0)
			(type default)
		)
	)
	(wire
		(pts
			(xy 186.69 224.79) (xy 199.39 224.79)
		)
		(stroke
			(width 0)
			(type default)
		)
	)
	(wire
		(pts
			(xy 185.42 185.42) (xy 199.39 185.42)
		)
		(stroke
			(width 0)
			(type default)
		)
	)
	(wire
		(pts
			(xy 199.39 266.7) (xy 198.12 266.7)
		)
		(stroke
			(width 0)
			(type default)
		)
	)
	(wire
		(pts
			(xy 186.69 227.33) (xy 199.39 227.33)
		)
		(stroke
			(width 0)
			(type default)
		)
	)
	(wire
		(pts
			(xy 214.63 43.18) (xy 220.98 43.18)
		)
		(stroke
			(width 0)
			(type default)
		)
	)
	(wire
		(pts
			(xy 27.94 271.78) (xy 27.94 279.4)
		)
		(stroke
			(width 0)
			(type default)
		)
	)
	(wire
		(pts
			(xy 289.56 48.26) (xy 294.64 48.26)
		)
		(stroke
			(width 0)
			(type default)
		)
	)
	(wire
		(pts
			(xy 40.64 39.37) (xy 40.64 41.91)
		)
		(stroke
			(width 0)
			(type default)
		)
	)
	(wire
		(pts
			(xy 83.82 54.61) (xy 83.82 55.88)
		)
		(stroke
			(width 0)
			(type default)
		)
	)
	(wire
		(pts
			(xy 114.3 180.34) (xy 115.57 180.34)
		)
		(stroke
			(width 0)
			(type default)
		)
	)
	(wire
		(pts
			(xy 162.56 226.06) (xy 162.56 232.41)
		)
		(stroke
			(width 0)
			(type default)
		)
	)
	(wire
		(pts
			(xy 220.98 54.61) (xy 227.33 54.61)
		)
		(stroke
			(width 0)
			(type default)
		)
	)
	(bus
		(pts
			(xy 185.42 163.83) (xy 184.15 162.56)
		)
		(stroke
			(width 0)
			(type default)
		)
	)
	(wire
		(pts
			(xy 372.11 116.84) (xy 374.65 116.84)
		)
		(stroke
			(width 0)
			(type default)
		)
	)
	(wire
		(pts
			(xy 16.51 158.75) (xy 16.51 173.99)
		)
		(stroke
			(width 0)
			(type default)
		)
	)
	(wire
		(pts
			(xy 55.88 54.61) (xy 55.88 55.88)
		)
		(stroke
			(width 0)
			(type default)
		)
	)
	(wire
		(pts
			(xy 185.42 43.18) (xy 185.42 44.45)
		)
		(stroke
			(width 0)
			(type default)
		)
	)
	(wire
		(pts
			(xy 36.83 165.1) (xy 36.83 167.64)
		)
		(stroke
			(width 0)
			(type default)
		)
	)
	(wire
		(pts
			(xy 374.65 115.57) (xy 374.65 116.84)
		)
		(stroke
			(width 0)
			(type default)
		)
	)
	(wire
		(pts
			(xy 334.01 45.72) (xy 363.22 45.72)
		)
		(stroke
			(width 0)
			(type default)
		)
	)
	(wire
		(pts
			(xy 232.41 259.08) (xy 232.41 267.97)
		)
		(stroke
			(width 0)
			(type default)
		)
	)
	(wire
		(pts
			(xy 179.07 189.23) (xy 179.07 187.96)
		)
		(stroke
			(width 0)
			(type default)
		)
	)
	(wire
		(pts
			(xy 185.42 35.56) (xy 203.2 35.56)
		)
		(stroke
			(width 0)
			(type default)
		)
	)
	(wire
		(pts
			(xy 130.81 254) (xy 129.54 254)
		)
		(stroke
			(width 0)
			(type default)
		)
	)
	(wire
		(pts
			(xy 177.8 66.04) (xy 185.42 66.04)
		)
		(stroke
			(width 0)
			(type default)
		)
	)
	(wire
		(pts
			(xy 114.3 217.17) (xy 140.97 217.17)
		)
		(stroke
			(width 0)
			(type default)
		)
	)
	(wire
		(pts
			(xy 50.8 158.75) (xy 88.9 158.75)
		)
		(stroke
			(width 0)
			(type default)
		)
	)
	(wire
		(pts
			(xy 55.88 264.16) (xy 92.71 264.16)
		)
		(stroke
			(width 0)
			(type default)
		)
	)
	(wire
		(pts
			(xy 177.8 273.05) (xy 177.8 279.4)
		)
		(stroke
			(width 0)
			(type default)
		)
	)
	(wire
		(pts
			(xy 222.25 158.75) (xy 222.25 167.64)
		)
		(stroke
			(width 0)
			(type default)
		)
	)
	(wire
		(pts
			(xy 215.9 166.37) (xy 215.9 175.26)
		)
		(stroke
			(width 0)
			(type default)
		)
	)
	(wire
		(pts
			(xy 154.94 132.08) (xy 162.56 132.08)
		)
		(stroke
			(width 0)
			(type default)
		)
	)
	(wire
		(pts
			(xy 154.94 50.8) (xy 162.56 50.8)
		)
		(stroke
			(width 0)
			(type default)
		)
	)
	(wire
		(pts
			(xy 303.53 50.8) (xy 303.53 52.07)
		)
		(stroke
			(width 0)
			(type default)
		)
	)
	(wire
		(pts
			(xy 198.12 166.37) (xy 204.47 166.37)
		)
		(stroke
			(width 0)
			(type default)
		)
	)
	(wire
		(pts
			(xy 83.82 271.78) (xy 83.82 273.05)
		)
		(stroke
			(width 0)
			(type default)
		)
	)
	(wire
		(pts
			(xy 199.39 279.4) (xy 198.12 279.4)
		)
		(stroke
			(width 0)
			(type default)
		)
	)
	(wire
		(pts
			(xy 48.26 254) (xy 48.26 266.7)
		)
		(stroke
			(width 0)
			(type default)
		)
	)
	(wire
		(pts
			(xy 397.51 52.07) (xy 397.51 58.42)
		)
		(stroke
			(width 0)
			(type default)
		)
	)
	(wire
		(pts
			(xy 255.27 50.8) (xy 255.27 52.07)
		)
		(stroke
			(width 0)
			(type default)
		)
	)
	(wire
		(pts
			(xy 185.42 101.6) (xy 185.42 104.14)
		)
		(stroke
			(width 0)
			(type default)
		)
	)
	(wire
		(pts
			(xy 275.59 190.5) (xy 275.59 194.31)
		)
		(stroke
			(width 0)
			(type default)
		)
	)
	(wire
		(pts
			(xy 334.01 50.8) (xy 335.28 50.8)
		)
		(stroke
			(width 0)
			(type default)
		)
	)
	(wire
		(pts
			(xy 162.56 43.18) (xy 162.56 44.45)
		)
		(stroke
			(width 0)
			(type default)
		)
	)
	(wire
		(pts
			(xy 91.44 214.63) (xy 92.71 214.63)
		)
		(stroke
			(width 0)
			(type default)
		)
	)
	(wire
		(pts
			(xy 316.23 124.46) (xy 336.55 124.46)
		)
		(stroke
			(width 0)
			(type default)
		)
	)
	(wire
		(pts
			(xy 140.97 40.64) (xy 140.97 35.56)
		)
		(stroke
			(width 0)
			(type default)
		)
	)
	(wire
		(pts
			(xy 115.57 232.41) (xy 115.57 227.33)
		)
		(stroke
			(width 0)
			(type default)
		)
	)
	(wire
		(pts
			(xy 275.59 182.88) (xy 275.59 185.42)
		)
		(stroke
			(width 0)
			(type default)
		)
	)
	(wire
		(pts
			(xy 16.51 179.07) (xy 16.51 180.34)
		)
		(stroke
			(width 0)
			(type default)
		)
	)
	(wire
		(pts
			(xy 271.78 50.8) (xy 271.78 58.42)
		)
		(stroke
			(width 0)
			(type default)
		)
	)
	(wire
		(pts
			(xy 215.9 158.75) (xy 209.55 158.75)
		)
		(stroke
			(width 0)
			(type default)
		)
	)
	(wire
		(pts
			(xy 114.3 172.72) (xy 140.97 172.72)
		)
		(stroke
			(width 0)
			(type default)
		)
	)
	(label "5V_PHASE"
		(at 115.57 209.55 0)
		(effects
			(font
				(size 1.27 1.27)
			)
			(justify left bottom)
		)
	)
	(label "16V_MODE2"
		(at 91.44 43.18 180)
		(effects
			(font
				(size 1.27 1.27)
			)
			(justify right bottom)
		)
	)
	(label "I2C_{SYS}.SCL"
		(at 186.69 274.32 0)
		(effects
			(font
				(size 1.27 1.27)
			)
			(justify left bottom)
		)
	)
	(label "5V_MODE2"
		(at 91.44 219.71 180)
		(effects
			(font
				(size 1.27 1.27)
			)
			(justify right bottom)
		)
	)
	(label "5V_FB"
		(at 115.57 219.71 0)
		(effects
			(font
				(size 1.27 1.27)
			)
			(justify left bottom)
		)
	)
	(label "5V_VDRV"
		(at 91.44 224.79 180)
		(effects
			(font
				(size 1.27 1.27)
			)
			(justify right bottom)
		)
	)
	(label "I2C_{SYS}.SCL"
		(at 194.31 57.15 0)
		(effects
			(font
				(size 1.27 1.27)
			)
			(justify left bottom)
		)
	)
	(label "5V_{AON}_SW"
		(at 114.3 167.64 0)
		(effects
			(font
				(size 1.27 1.27)
			)
			(justify left bottom)
		)
	)
	(label "16V_PHASE"
		(at 115.57 33.02 0)
		(effects
			(font
				(size 1.27 1.27)
			)
			(justify left bottom)
		)
	)
	(label "I2C_{SYS}.SCL"
		(at 194.31 123.19 0)
		(effects
			(font
				(size 1.27 1.27)
			)
			(justify left bottom)
		)
	)
	(label "5V_OUT"
		(at 146.05 212.09 0)
		(effects
			(font
				(size 1.27 1.27)
			)
			(justify left bottom)
		)
	)
	(label "5V_{AON}_FB"
		(at 115.57 175.26 0)
		(effects
			(font
				(size 1.27 1.27)
			)
			(justify left bottom)
		)
	)
	(label "20V_PHASE"
		(at 115.57 99.06 0)
		(effects
			(font
				(size 1.27 1.27)
			)
			(justify left bottom)
		)
	)
	(label "3V3_SW"
		(at 115.57 259.08 0)
		(effects
			(font
				(size 1.27 1.27)
			)
			(justify left bottom)
		)
	)
	(label "12V_PHASE"
		(at 335.28 35.56 0)
		(effects
			(font
				(size 1.27 1.27)
			)
			(justify left bottom)
		)
	)
	(label "I2C_{SYS}.SDA"
		(at 186.69 180.34 0)
		(effects
			(font
				(size 1.27 1.27)
			)
			(justify left bottom)
		)
	)
	(label "20V_EN"
		(at 83.82 104.14 0)
		(effects
			(font
				(size 1.27 1.27)
			)
			(justify left bottom)
		)
	)
	(label "I2C_{SYS}.SDA"
		(at 194.31 54.61 0)
		(effects
			(font
				(size 1.27 1.27)
			)
			(justify left bottom)
		)
	)
	(label "5V_{AON}_BOOT"
		(at 114.3 162.56 0)
		(effects
			(font
				(size 1.27 1.27)
			)
			(justify left bottom)
		)
	)
	(label "16V_VDRV"
		(at 91.44 48.26 180)
		(effects
			(font
				(size 1.27 1.27)
			)
			(justify right bottom)
		)
	)
	(label "3V3_VDRV"
		(at 91.44 271.78 180)
		(effects
			(font
				(size 1.27 1.27)
			)
			(justify right bottom)
		)
	)
	(label "20V_BOOT"
		(at 115.57 96.52 0)
		(effects
			(font
				(size 1.27 1.27)
			)
			(justify left bottom)
		)
	)
	(label "12V_OUT"
		(at 364.49 38.1 0)
		(effects
			(font
				(size 1.27 1.27)
			)
			(justify left bottom)
		)
	)
	(label "5V_{AON}_MODE1"
		(at 91.44 172.72 180)
		(effects
			(font
				(size 1.27 1.27)
			)
			(justify right bottom)
		)
	)
	(label "5V_VDD"
		(at 91.44 222.25 180)
		(effects
			(font
				(size 1.27 1.27)
			)
			(justify right bottom)
		)
	)
	(label "5V_{AON}_EN"
		(at 38.1 180.34 180)
		(effects
			(font
				(size 1.27 1.27)
			)
			(justify right bottom)
		)
	)
	(label "3V3_MODE1"
		(at 91.44 264.16 180)
		(effects
			(font
				(size 1.27 1.27)
			)
			(justify right bottom)
		)
	)
	(label "1V15_OUT"
		(at 337.82 182.88 0)
		(effects
			(font
				(size 1.27 1.27)
			)
			(justify left bottom)
		)
	)
	(label "3V3_OUT"
		(at 146.05 259.08 0)
		(effects
			(font
				(size 1.27 1.27)
			)
			(justify left bottom)
		)
	)
	(label "12V_MODE2"
		(at 311.15 45.72 180)
		(effects
			(font
				(size 1.27 1.27)
			)
			(justify right bottom)
		)
	)
	(label "1V15_SW"
		(at 316.23 182.88 0)
		(effects
			(font
				(size 1.27 1.27)
			)
			(justify left bottom)
		)
	)
	(label "3V3_MODE2"
		(at 91.44 266.7 180)
		(effects
			(font
				(size 1.27 1.27)
			)
			(justify right bottom)
		)
	)
	(label "I2C_{SYS}.SDA"
		(at 186.69 187.96 0)
		(effects
			(font
				(size 1.27 1.27)
			)
			(justify left bottom)
		)
	)
	(label "12V_VDRV"
		(at 311.15 50.8 180)
		(effects
			(font
				(size 1.27 1.27)
			)
			(justify right bottom)
		)
	)
	(label "12V_FB"
		(at 335.28 45.72 0)
		(effects
			(font
				(size 1.27 1.27)
			)
			(justify left bottom)
		)
	)
	(label "I2C_{SYS}.SDA"
		(at 194.31 120.65 0)
		(effects
			(font
				(size 1.27 1.27)
			)
			(justify left bottom)
		)
	)
	(label "20V_VDD"
		(at 91.44 111.76 180)
		(effects
			(font
				(size 1.27 1.27)
			)
			(justify right bottom)
		)
	)
	(label "1V8_FB"
		(at 316.23 124.46 0)
		(effects
			(font
				(size 1.27 1.27)
			)
			(justify left bottom)
		)
	)
	(label "1V8_SW"
		(at 316.23 116.84 0)
		(effects
			(font
				(size 1.27 1.27)
			)
			(justify left bottom)
		)
	)
	(label "I2C_{SYS}.SCL"
		(at 186.69 182.88 0)
		(effects
			(font
				(size 1.27 1.27)
			)
			(justify left bottom)
		)
	)
	(label "5V_{AON}_MODE2"
		(at 91.44 175.26 180)
		(effects
			(font
				(size 1.27 1.27)
			)
			(justify right bottom)
		)
	)
	(label "I2C_{SYS}.SCL"
		(at 186.69 227.33 0)
		(effects
			(font
				(size 1.27 1.27)
			)
			(justify left bottom)
		)
	)
	(label "16V_SW"
		(at 115.57 35.56 0)
		(effects
			(font
				(size 1.27 1.27)
			)
			(justify left bottom)
		)
	)
	(label "5V_MODE1"
		(at 91.44 217.17 180)
		(effects
			(font
				(size 1.27 1.27)
			)
			(justify right bottom)
		)
	)
	(label "12V_MODE1"
		(at 311.15 43.18 180)
		(effects
			(font
				(size 1.27 1.27)
			)
			(justify right bottom)
		)
	)
	(label "1V15_FB"
		(at 316.23 190.5 0)
		(effects
			(font
				(size 1.27 1.27)
			)
			(justify left bottom)
		)
	)
	(label "1V8_OUT"
		(at 337.82 116.84 0)
		(effects
			(font
				(size 1.27 1.27)
			)
			(justify left bottom)
		)
	)
	(label "5V_{AON}_PHASE"
		(at 114.3 165.1 0)
		(effects
			(font
				(size 1.27 1.27)
			)
			(justify left bottom)
		)
	)
	(label "5V_BOOT"
		(at 115.57 207.01 0)
		(effects
			(font
				(size 1.27 1.27)
			)
			(justify left bottom)
		)
	)
	(label "20V_FB"
		(at 115.57 109.22 0)
		(effects
			(font
				(size 1.27 1.27)
			)
			(justify left bottom)
		)
	)
	(label "12V_VDD"
		(at 311.15 48.26 180)
		(effects
			(font
				(size 1.27 1.27)
			)
			(justify right bottom)
		)
	)
	(label "16V_BOOT"
		(at 115.57 30.48 0)
		(effects
			(font
				(size 1.27 1.27)
			)
			(justify left bottom)
		)
	)
	(label "5V_{AON}_VDD"
		(at 91.44 177.8 180)
		(effects
			(font
				(size 1.27 1.27)
			)
			(justify right bottom)
		)
	)
	(label "5V_{AON}_EN"
		(at 78.74 170.18 0)
		(effects
			(font
				(size 1.27 1.27)
			)
			(justify left bottom)
		)
	)
	(label "16V_FB"
		(at 115.57 43.18 0)
		(effects
			(font
				(size 1.27 1.27)
			)
			(justify left bottom)
		)
	)
	(label "12V_SW"
		(at 335.28 38.1 0)
		(effects
			(font
				(size 1.27 1.27)
			)
			(justify left bottom)
		)
	)
	(label "3V3_VDD"
		(at 91.44 269.24 180)
		(effects
			(font
				(size 1.27 1.27)
			)
			(justify right bottom)
		)
	)
	(label "3V3_PHASE"
		(at 115.57 256.54 0)
		(effects
			(font
				(size 1.27 1.27)
			)
			(justify left bottom)
		)
	)
	(label "16V_VDD"
		(at 91.44 45.72 180)
		(effects
			(font
				(size 1.27 1.27)
			)
			(justify right bottom)
		)
	)
	(label "12V_BOOT"
		(at 335.28 33.02 0)
		(effects
			(font
				(size 1.27 1.27)
			)
			(justify left bottom)
		)
	)
	(label "16V_MODE1"
		(at 91.44 40.64 180)
		(effects
			(font
				(size 1.27 1.27)
			)
			(justify right bottom)
		)
	)
	(label "20V_OUT"
		(at 146.05 101.6 0)
		(effects
			(font
				(size 1.27 1.27)
			)
			(justify left bottom)
		)
	)
	(label "I2C_{SYS}.SDA"
		(at 186.69 224.79 0)
		(effects
			(font
				(size 1.27 1.27)
			)
			(justify left bottom)
		)
	)
	(label "16V_OUT"
		(at 146.05 35.56 0)
		(effects
			(font
				(size 1.27 1.27)
			)
			(justify left bottom)
		)
	)
	(label "3V3_BOOT"
		(at 115.57 254 0)
		(effects
			(font
				(size 1.27 1.27)
			)
			(justify left bottom)
		)
	)
	(label "I2C_{SYS}.SDA"
		(at 186.69 271.78 0)
		(effects
			(font
				(size 1.27 1.27)
			)
			(justify left bottom)
		)
	)
	(label "20V_SW"
		(at 115.57 101.6 0)
		(effects
			(font
				(size 1.27 1.27)
			)
			(justify left bottom)
		)
	)
	(label "20V_EN"
		(at 60.96 135.89 180)
		(effects
			(font
				(size 1.27 1.27)
			)
			(justify right bottom)
		)
	)
	(label "20V_MODE2"
		(at 91.44 109.22 180)
		(effects
			(font
				(size 1.27 1.27)
			)
			(justify right bottom)
		)
	)
	(label "20V_MODE1"
		(at 91.44 106.68 180)
		(effects
			(font
				(size 1.27 1.27)
			)
			(justify right bottom)
		)
	)
	(label "3V3_FB"
		(at 115.57 266.7 0)
		(effects
			(font
				(size 1.27 1.27)
			)
			(justify left bottom)
		)
	)
	(label "20V_VDRV"
		(at 91.44 114.3 180)
		(effects
			(font
				(size 1.27 1.27)
			)
			(justify right bottom)
		)
	)
	(label "5V_{AON}_VDRV"
		(at 91.44 180.34 180)
		(effects
			(font
				(size 1.27 1.27)
			)
			(justify right bottom)
		)
	)
	(label "5V_SW"
		(at 115.57 212.09 0)
		(effects
			(font
				(size 1.27 1.27)
			)
			(justify left bottom)
		)
	)
	(label "5V_{AON}_OUT"
		(at 144.78 167.64 0)
		(effects
			(font
				(size 1.27 1.27)
			)
			(justify left bottom)
		)
	)
	(hierarchical_label "CARRIER_PWR_ON"
		(shape input)
		(at 35.56 135.89 180)
		(effects
			(font
				(size 1.27 1.27)
			)
			(justify right)
		)
	)
	(hierarchical_label "CARRIER_PWR_ON"
		(shape input)
		(at 299.72 121.92 180)
		(effects
			(font
				(size 1.27 1.27)
			)
			(justify right)
		)
	)
	(hierarchical_label "CARRIER_PWR_ON"
		(shape input)
		(at 91.44 260.35 180)
		(effects
			(font
				(size 1.27 1.27)
			)
			(justify right)
		)
	)
	(hierarchical_label "CARRIER_PWR_ON"
		(shape input)
		(at 299.72 187.96 180)
		(effects
			(font
				(size 1.27 1.27)
			)
			(justify right)
		)
	)
	(hierarchical_label "I2C_{SYS}{I2C}"
		(shape bidirectional)
		(at 187.96 96.52 180)
		(effects
			(font
				(size 1.27 1.27)
			)
			(justify right)
		)
	)
	(hierarchical_label "~{VDDIN_PWR_BAD}"
		(shape output)
		(at 91.44 191.77 0)
		(effects
			(font
				(size 1.27 1.27)
			)
			(justify left)
		)
	)
	(hierarchical_label "~{VDDIN_PWR_BAD}"
		(shape output)
		(at 91.44 59.69 0)
		(effects
			(font
				(size 1.27 1.27)
			)
			(justify left)
		)
	)
	(hierarchical_label "I2C_{SYS}{I2C}"
		(shape bidirectional)
		(at 187.96 30.48 180)
		(effects
			(font
				(size 1.27 1.27)
			)
			(justify right)
		)
	)
	(hierarchical_label "CARRIER_PWR_ON"
		(shape input)
		(at 91.44 213.36 180)
		(effects
			(font
				(size 1.27 1.27)
			)
			(justify right)
		)
	)
	(hierarchical_label "CARRIER_PWR_ON"
		(shape input)
		(at 311.15 39.37 180)
		(effects
			(font
				(size 1.27 1.27)
			)
			(justify right)
		)
	)
	(hierarchical_label "I2C_{SYS}{I2C}"
		(shape bidirectional)
		(at 180.34 162.56 180)
		(effects
			(font
				(size 1.27 1.27)
			)
			(justify right)
		)
	)
	(hierarchical_label "I2C_{SYS}{I2C}"
		(shape bidirectional)
		(at 180.34 207.01 180)
		(effects
			(font
				(size 1.27 1.27)
			)
			(justify right)
		)
	)
	(hierarchical_label "I2C_{SYS}{I2C}"
		(shape bidirectional)
		(at 180.34 254 180)
		(effects
			(font
				(size 1.27 1.27)
			)
			(justify right)
		)
	)
	(hierarchical_label "VIN_PWR_ON"
		(shape input)
		(at 86.36 36.83 180)
		(effects
			(font
				(size 1.27 1.27)
			)
			(justify right)
		)
	)
	(rule_area
		(polyline
			(pts
				(xy 16.51 13.97) (xy 245.11 13.97) (xy 245.11 80.01) (xy 16.51 80.01)
			)
			(stroke
				(width 0)
				(type dash)
			)
			(fill
				(type none)
			)
		)
	)
	(rule_area
		(polyline
			(pts
				(xy 251.46 156.21) (xy 405.13 156.21) (xy 405.13 222.25) (xy 251.46 222.25)
			)
			(stroke
				(width 0)
				(type dash)
			)
			(fill
				(type none)
			)
		)
	)
	(rule_area
		(polyline
			(pts
				(xy 16.51 83.82) (xy 245.11 83.82) (xy 245.11 147.32) (xy 16.51 147.32)
			)
			(stroke
				(width 0)
				(type dash)
			)
			(fill
				(type none)
			)
		)
	)
	(rule_area
		(polyline
			(pts
				(xy 251.46 147.32) (xy 405.13 147.32) (xy 405.13 83.82) (xy 251.46 83.82)
			)
			(stroke
				(width 0)
				(type dash)
			)
			(fill
				(type none)
			)
		)
	)
	(netclass_flag ""
		(length 2.54)
		(shape round)
		(at 255.27 147.32 0)
		(fields_autoplaced yes)
		(effects
			(font
				(size 1.27 1.27)
			)
			(justify left bottom)
		)
		(property "Netclass" ""
			(at -63.5 142.24 0)
			(effects
				(font
					(size 1.27 1.27)
				)
			)
		)
		(property "Component Class" "DCDC_1V8"
			(at 255.9685 144.78 0)
			(effects
				(font
					(size 1.27 1.27)
					(italic yes)
				)
				(justify left)
			)
		)
	)
	(netclass_flag ""
		(length 2.54)
		(shape round)
		(at 19.05 147.32 0)
		(fields_autoplaced yes)
		(effects
			(font
				(size 1.27 1.27)
			)
			(justify left bottom)
		)
		(property "Netclass" ""
			(at -299.72 142.24 0)
			(effects
				(font
					(size 1.27 1.27)
				)
			)
		)
		(property "Component Class" "DCDC_20V"
			(at 19.7485 144.78 0)
			(effects
				(font
					(size 1.27 1.27)
					(italic yes)
				)
				(justify left)
			)
		)
	)
	(netclass_flag ""
		(length 2.54)
		(shape round)
		(at 20.32 80.01 0)
		(fields_autoplaced yes)
		(effects
			(font
				(size 1.27 1.27)
			)
			(justify left bottom)
		)
		(property "Netclass" ""
			(at -298.45 74.93 0)
			(effects
				(font
					(size 1.27 1.27)
				)
			)
		)
		(property "Component Class" "DCDC_SOM"
			(at 21.0185 77.47 0)
			(effects
				(font
					(size 1.27 1.27)
					(italic yes)
				)
				(justify left)
			)
		)
	)
	(netclass_flag ""
		(length 2.54)
		(shape round)
		(at 255.27 222.25 0)
		(fields_autoplaced yes)
		(effects
			(font
				(size 1.27 1.27)
			)
			(justify left bottom)
		)
		(property "Netclass" ""
			(at -63.5 217.17 0)
			(effects
				(font
					(size 1.27 1.27)
				)
			)
		)
		(property "Component Class" "DCDC_1V15"
			(at 255.9685 219.71 0)
			(effects
				(font
					(size 1.27 1.27)
					(italic yes)
				)
				(justify left)
			)
		)
	)
	(symbol
		(lib_id "antmicroResistors0402:R_200k_0402")
		(at 64.77 54.61 90)
		(unit 1)
		(exclude_from_sim no)
		(in_bom yes)
		(on_board yes)
		(dnp no)
		(property "Reference" "R41"
			(at 66.04 50.8 90)
			(effects
				(font
					(size 1.27 1.27)
					(thickness 0.15)
				)
				(justify right)
			)
		)
		(property "Value" "R_200k_0402"
			(at 77.47 34.29 0)
			(effects
				(font
					(size 1.27 1.27)
					(thickness 0.15)
				)
				(justify left bottom)
				(hide yes)
			)
		)
		(property "Footprint" "antmicro-footprints:R_0402_1005Metric"
			(at 80.01 34.29 0)
			(effects
				(font
					(size 1.27 1.27)
					(thickness 0.15)
				)
				(justify left bottom)
				(hide yes)
			)
		)
		(property "Datasheet" "https://www.bourns.com/docs/product-datasheets/cr.pdf"
			(at 82.55 34.29 0)
			(effects
				(font
					(size 1.27 1.27)
					(thickness 0.15)
				)
				(justify left bottom)
				(hide yes)
			)
		)
		(property "Description" "SMD Chip Resistor, 200 kohm, ± 1%, 62.5 mW, 0402 [1005 Metric], Thick Film, General Purpose"
			(at 64.77 54.61 0)
			(effects
				(font
					(size 1.27 1.27)
				)
				(hide yes)
			)
		)
		(property "MPN" "CR0402-FX-2003GLF"
			(at 85.09 34.29 0)
			(effects
				(font
					(size 1.27 1.27)
					(thickness 0.15)
				)
				(justify left bottom)
				(hide yes)
			)
		)
		(property "Manufacturer" "Bourns"
			(at 87.63 34.29 0)
			(effects
				(font
					(size 1.27 1.27)
					(thickness 0.15)
				)
				(justify left bottom)
				(hide yes)
			)
		)
		(property "License" "Apache-2.0"
			(at 90.17 34.29 0)
			(effects
				(font
					(size 1.27 1.27)
					(thickness 0.15)
				)
				(justify left bottom)
				(hide yes)
			)
		)
		(property "Author" "Antmicro"
			(at 92.71 34.29 0)
			(effects
				(font
					(size 1.27 1.27)
					(thickness 0.15)
				)
				(justify left bottom)
				(hide yes)
			)
		)
		(property "Val" "200k"
			(at 66.04 53.34 90)
			(effects
				(font
					(size 1.27 1.27)
					(thickness 0.15)
				)
				(justify right)
			)
		)
		(property "Tolerance" "1%"
			(at 74.93 34.29 0)
			(effects
				(font
					(size 1.27 1.27)
				)
				(justify left bottom)
				(hide yes)
			)
		)
		(pin "2"
		)
		(pin "1"
		)
		(instances
			(project "jetson-agx-thor-baseboard"
				(path ""
					(reference "R41")
					(unit 1)
				)
			)
		)
	)
	(symbol
		(lib_id "antmicropower:GND")
		(at 40.64 107.95 0)
		(unit 1)
		(exclude_from_sim no)
		(in_bom yes)
		(on_board yes)
		(dnp no)
		(property "Reference" "#PWR0545"
			(at 40.64 114.3 0)
			(effects
				(font
					(size 1.27 1.27)
				)
				(justify left bottom)
				(hide yes)
			)
		)
		(property "Value" "GND"
			(at 40.64 111.76 0)
			(effects
				(font
					(size 1.27 1.27)
					(thickness 0.15)
				)
			)
		)
		(property "Footprint" ""
			(at 49.53 115.57 0)
			(effects
				(font
					(size 1.27 1.27)
					(thickness 0.15)
				)
				(justify left bottom)
				(hide yes)
			)
		)
		(property "Datasheet" ""
			(at 49.53 120.65 0)
			(effects
				(font
					(size 1.27 1.27)
					(thickness 0.15)
				)
				(justify left bottom)
				(hide yes)
			)
		)
		(property "Description" ""
			(at 40.64 107.95 0)
			(effects
				(font
					(size 1.27 1.27)
				)
				(hide yes)
			)
		)
		(property "Author" "Antmicro"
			(at 49.53 115.57 0)
			(effects
				(font
					(size 1.27 1.27)
					(thickness 0.15)
				)
				(justify left bottom)
				(hide yes)
			)
		)
		(property "License" "Apache-2.0"
			(at 49.53 118.11 0)
			(effects
				(font
					(size 1.27 1.27)
					(thickness 0.15)
				)
				(justify left bottom)
				(hide yes)
			)
		)
		(pin "1"
		)
		(instances
			(project "jetson-agx-thor-baseboard"
				(path ""
					(reference "#PWR0545")
					(unit 1)
				)
			)
		)
	)
	(symbol
		(lib_id "antmicroTVSDiodes:ESDA25P35-1U1M")
		(at 233.68 40.64 270)
		(unit 1)
		(exclude_from_sim no)
		(in_bom yes)
		(on_board yes)
		(dnp no)
		(property "Reference" "D7"
			(at 234.95 41.91 90)
			(effects
				(font
					(size 1.27 1.27)
				)
				(justify left)
			)
		)
		(property "Value" "ESDA25P35-1U1M"
			(at 218.44 62.23 0)
			(effects
				(font
					(size 1.27 1.27)
					(thickness 0.15)
				)
				(justify left bottom)
				(hide yes)
			)
		)
		(property "Footprint" "antmicro-footprints:QFN-2L_1.6x1x0.55mm"
			(at 223.52 64.77 0)
			(effects
				(font
					(size 1.27 1.27)
					(thickness 0.15)
				)
				(justify left bottom)
				(hide yes)
			)
		)
		(property "Datasheet" "https://www.st.com/resource/en/datasheet/esda25p35-1u1m.pdf"
			(at 220.98 64.77 0)
			(effects
				(font
					(size 1.27 1.27)
					(thickness 0.15)
				)
				(justify left bottom)
				(hide yes)
			)
		)
		(property "Description" "Unidirectional TVS, 30 kV, QFN-2L, 22 V, 195 pF"
			(at 208.28 64.77 0)
			(effects
				(font
					(size 1.27 1.27)
				)
				(justify left bottom)
				(hide yes)
			)
		)
		(property "Manufacturer" "STMicroelectronics"
			(at 215.9 64.77 0)
			(effects
				(font
					(size 1.27 1.27)
					(thickness 0.15)
				)
				(justify left bottom)
				(hide yes)
			)
		)
		(property "MPN" "ESDA25P35-1U1M"
			(at 237.49 40.64 0)
			(effects
				(font
					(size 1.27 1.27)
					(thickness 0.15)
				)
				(justify left bottom)
			)
		)
		(property "Author" "Antmicro"
			(at 213.36 64.77 0)
			(effects
				(font
					(size 1.27 1.27)
					(thickness 0.15)
				)
				(justify left bottom)
				(hide yes)
			)
		)
		(property "License" "Apache-2.0"
			(at 210.82 64.77 0)
			(effects
				(font
					(size 1.27 1.27)
					(thickness 0.15)
				)
				(justify left bottom)
				(hide yes)
			)
		)
		(pin "1"
		)
		(pin "2"
		)
		(instances
			(project "jetson-agx-thor-baseboard"
				(path ""
					(reference "D7")
					(unit 1)
				)
			)
		)
	)
	(symbol
		(lib_id "antmicroTVSDiodes:PESD5Z5_0F")
		(at 232.41 218.44 270)
		(unit 1)
		(exclude_from_sim no)
		(in_bom yes)
		(on_board yes)
		(dnp no)
		(property "Reference" "D8"
			(at 237.236 219.964 90)
			(effects
				(font
					(size 1.27 1.27)
				)
				(justify right)
			)
		)
		(property "Value" "PESD5Z5.0F"
			(at 217.17 240.03 0)
			(effects
				(font
					(size 1.27 1.27)
					(thickness 0.15)
				)
				(justify left bottom)
				(hide yes)
			)
		)
		(property "Footprint" "antmicro-footprints:SOD-523"
			(at 227.33 233.68 0)
			(effects
				(font
					(size 1.27 1.27)
					(thickness 0.15)
				)
				(justify left bottom)
				(hide yes)
			)
		)
		(property "Datasheet" "https://assets.nexperia.com/documents/data-sheet/PESD5Z5_0.pdf"
			(at 224.79 233.68 0)
			(effects
				(font
					(size 1.27 1.27)
					(thickness 0.15)
				)
				(justify left bottom)
				(hide yes)
			)
		)
		(property "Description" "Unidirectional TVS, 30 kV,  SOD-523, 5 V, 89 pF"
			(at 212.09 233.68 0)
			(effects
				(font
					(size 1.27 1.27)
				)
				(justify left bottom)
				(hide yes)
			)
		)
		(property "Manufacturer" "Nexperia"
			(at 222.25 233.68 0)
			(effects
				(font
					(size 1.27 1.27)
					(thickness 0.15)
				)
				(justify left bottom)
				(hide yes)
			)
		)
		(property "MPN" "PESD5Z5.0F"
			(at 234.442 222.504 90)
			(effects
				(font
					(size 1.27 1.27)
					(thickness 0.15)
				)
				(justify left bottom)
			)
		)
		(property "Author" "Antmicro"
			(at 217.17 233.68 0)
			(effects
				(font
					(size 1.27 1.27)
					(thickness 0.15)
				)
				(justify left bottom)
				(hide yes)
			)
		)
		(property "License" "Apache-2.0"
			(at 214.63 233.68 0)
			(effects
				(font
					(size 1.27 1.27)
					(thickness 0.15)
				)
				(justify left bottom)
				(hide yes)
			)
		)
		(pin "1"
		)
		(pin "2"
		)
		(instances
			(project "jetson-agx-thor-baseboard"
				(path ""
					(reference "D8")
					(unit 1)
				)
			)
		)
	)
	(symbol
		(lib_id "antmicroCapacitorsmisc:C_22u_25V_0805")
		(at 21.59 271.78 90)
		(unit 1)
		(exclude_from_sim no)
		(in_bom yes)
		(on_board yes)
		(dnp no)
		(property "Reference" "C268"
			(at 22.225 267.335 90)
			(effects
				(font
					(size 1.27 1.27)
					(thickness 0.15)
				)
				(justify right)
			)
		)
		(property "Value" "C_22u_25V_0805"
			(at 31.75 251.46 0)
			(effects
				(font
					(size 1.27 1.27)
					(thickness 0.15)
				)
				(justify left bottom)
				(hide yes)
			)
		)
		(property "Footprint" "antmicro-footprints:C_0805_2012Metric"
			(at 34.29 251.46 0)
			(effects
				(font
					(size 1.27 1.27)
					(thickness 0.15)
				)
				(justify left bottom)
				(hide yes)
			)
		)
		(property "Datasheet" "https://product.samsungsem.com/mlcc/CL21A226MAYNNN.do"
			(at 36.83 251.46 0)
			(effects
				(font
					(size 1.27 1.27)
					(thickness 0.15)
				)
				(justify left bottom)
				(hide yes)
			)
		)
		(property "Description" "SMT Multilayer Ceramic Capacitor, 22uF, +/-20%, 25V, X5R, 0805 [2012 Metric]"
			(at 21.59 271.78 0)
			(effects
				(font
					(size 1.27 1.27)
				)
				(hide yes)
			)
		)
		(property "MPN" "CL21A226MAYNNNE"
			(at 39.37 251.46 0)
			(effects
				(font
					(size 1.27 1.27)
					(thickness 0.15)
				)
				(justify left bottom)
				(hide yes)
			)
		)
		(property "Manufacturer" "Samsung Electro-Mechanics"
			(at 41.91 251.46 0)
			(effects
				(font
					(size 1.27 1.27)
					(thickness 0.15)
				)
				(justify left bottom)
				(hide yes)
			)
		)
		(property "License" "Apache-2.0"
			(at 44.45 251.46 0)
			(effects
				(font
					(size 1.27 1.27)
					(thickness 0.15)
				)
				(justify left bottom)
				(hide yes)
			)
		)
		(property "Author" "Antmicro"
			(at 46.99 251.46 0)
			(effects
				(font
					(size 1.27 1.27)
					(thickness 0.15)
				)
				(justify left bottom)
				(hide yes)
			)
		)
		(property "Val" "22u"
			(at 22.225 271.145 90)
			(effects
				(font
					(size 1.27 1.27)
					(thickness 0.15)
				)
				(justify right)
			)
		)
		(property "Voltage" "25V"
			(at 22.225 273.685 90)
			(effects
				(font
					(size 1.27 1.27)
				)
				(justify right)
			)
		)
		(property "Dielectric" "X5R"
			(at 52.07 251.46 0)
			(effects
				(font
					(size 1.27 1.27)
				)
				(justify left bottom)
				(hide yes)
			)
		)
		(property "Public" "False"
			(at 54.61 251.46 0)
			(effects
				(font
					(size 1.27 1.27)
				)
				(justify left bottom)
				(hide yes)
			)
		)
		(pin "2"
		)
		(pin "1"
		)
		(instances
			(project "jetson-agx-thor-baseboard"
				(path ""
					(reference "C268")
					(unit 1)
				)
			)
		)
	)
	(symbol
		(lib_id "antmicropower:GND")
		(at 162.56 279.4 0)
		(unit 1)
		(exclude_from_sim no)
		(in_bom yes)
		(on_board yes)
		(dnp no)
		(property "Reference" "#PWR0143"
			(at 162.56 285.75 0)
			(effects
				(font
					(size 1.27 1.27)
				)
				(justify left bottom)
				(hide yes)
			)
		)
		(property "Value" "GND"
			(at 162.56 283.21 0)
			(effects
				(font
					(size 1.27 1.27)
					(thickness 0.15)
				)
			)
		)
		(property "Footprint" ""
			(at 171.45 287.02 0)
			(effects
				(font
					(size 1.27 1.27)
					(thickness 0.15)
				)
				(justify left bottom)
				(hide yes)
			)
		)
		(property "Datasheet" ""
			(at 171.45 292.1 0)
			(effects
				(font
					(size 1.27 1.27)
					(thickness 0.15)
				)
				(justify left bottom)
				(hide yes)
			)
		)
		(property "Description" ""
			(at 162.56 279.4 0)
			(effects
				(font
					(size 1.27 1.27)
				)
				(hide yes)
			)
		)
		(property "Author" "Antmicro"
			(at 171.45 287.02 0)
			(effects
				(font
					(size 1.27 1.27)
					(thickness 0.15)
				)
				(justify left bottom)
				(hide yes)
			)
		)
		(property "License" "Apache-2.0"
			(at 171.45 289.56 0)
			(effects
				(font
					(size 1.27 1.27)
					(thickness 0.15)
				)
				(justify left bottom)
				(hide yes)
			)
		)
		(pin "1"
		)
		(instances
			(project "jetson-agx-thor-baseboard"
				(path ""
					(reference "#PWR0143")
					(unit 1)
				)
			)
		)
	)
	(symbol
		(lib_id "antmicroCapacitors0402:C_100n_0402")
		(at 220.98 127 90)
		(unit 1)
		(exclude_from_sim no)
		(in_bom yes)
		(on_board yes)
		(dnp no)
		(property "Reference" "C304"
			(at 223.52 123.1835 90)
			(effects
				(font
					(size 1.27 1.27)
					(thickness 0.15)
				)
				(justify right)
			)
		)
		(property "Value" "C_100n_0402"
			(at 231.14 106.68 0)
			(effects
				(font
					(size 1.27 1.27)
					(thickness 0.15)
				)
				(justify left bottom)
				(hide yes)
			)
		)
		(property "Footprint" "antmicro-footprints:C_0402_1005Metric"
			(at 233.68 106.68 0)
			(effects
				(font
					(size 1.27 1.27)
					(thickness 0.15)
				)
				(justify left bottom)
				(hide yes)
			)
		)
		(property "Datasheet" "https://www.murata.com/products/productdetail?partno=GRM155R61H104KE14%23"
			(at 236.22 106.68 0)
			(effects
				(font
					(size 1.27 1.27)
					(thickness 0.15)
				)
				(justify left bottom)
				(hide yes)
			)
		)
		(property "Description" "SMD Multilayer Ceramic Capacitor, 0.1 µF, 50 V, 0402 [1005 Metric], ± 10%, X5R, GRM Series"
			(at 220.98 127 0)
			(effects
				(font
					(size 1.27 1.27)
				)
				(hide yes)
			)
		)
		(property "MPN" "GRM155R61H104KE14D"
			(at 238.76 106.68 0)
			(effects
				(font
					(size 1.27 1.27)
					(thickness 0.15)
				)
				(justify left bottom)
				(hide yes)
			)
		)
		(property "Manufacturer" "Murata"
			(at 241.3 106.68 0)
			(effects
				(font
					(size 1.27 1.27)
					(thickness 0.15)
				)
				(justify left bottom)
				(hide yes)
			)
		)
		(property "License" "Apache-2.0"
			(at 243.84 106.68 0)
			(effects
				(font
					(size 1.27 1.27)
					(thickness 0.15)
				)
				(justify left bottom)
				(hide yes)
			)
		)
		(property "Author" "Antmicro"
			(at 246.38 106.68 0)
			(effects
				(font
					(size 1.27 1.27)
					(thickness 0.15)
				)
				(justify left bottom)
				(hide yes)
			)
		)
		(property "Val" "100n"
			(at 223.52 125.7235 90)
			(effects
				(font
					(size 1.27 1.27)
					(thickness 0.15)
				)
				(justify right)
			)
		)
		(property "Voltage" "50V"
			(at 248.92 106.68 0)
			(effects
				(font
					(size 1.27 1.27)
				)
				(justify left bottom)
				(hide yes)
			)
		)
		(property "Dielectric" "X5R"
			(at 251.46 106.68 0)
			(effects
				(font
					(size 1.27 1.27)
				)
				(justify left bottom)
				(hide yes)
			)
		)
		(property "Public" "False"
			(at 254 106.68 0)
			(effects
				(font
					(size 1.27 1.27)
				)
				(justify left bottom)
				(hide yes)
			)
		)
		(pin "1"
		)
		(pin "2"
		)
		(instances
			(project "jetson-agx-thor-baseboard"
				(path ""
					(reference "C304")
					(unit 1)
				)
			)
		)
	)
	(symbol
		(lib_id "antmicropower:GND")
		(at 30.48 167.64 0)
		(unit 1)
		(exclude_from_sim no)
		(in_bom yes)
		(on_board yes)
		(dnp no)
		(property "Reference" "#PWR0748"
			(at 30.48 173.99 0)
			(effects
				(font
					(size 1.27 1.27)
				)
				(justify left bottom)
				(hide yes)
			)
		)
		(property "Value" "GND"
			(at 30.48 171.45 0)
			(effects
				(font
					(size 1.27 1.27)
					(thickness 0.15)
				)
			)
		)
		(property "Footprint" ""
			(at 39.37 175.26 0)
			(effects
				(font
					(size 1.27 1.27)
					(thickness 0.15)
				)
				(justify left bottom)
				(hide yes)
			)
		)
		(property "Datasheet" ""
			(at 39.37 180.34 0)
			(effects
				(font
					(size 1.27 1.27)
					(thickness 0.15)
				)
				(justify left bottom)
				(hide yes)
			)
		)
		(property "Description" ""
			(at 30.48 167.64 0)
			(effects
				(font
					(size 1.27 1.27)
				)
				(hide yes)
			)
		)
		(property "Author" "Antmicro"
			(at 39.37 175.26 0)
			(effects
				(font
					(size 1.27 1.27)
					(thickness 0.15)
				)
				(justify left bottom)
				(hide yes)
			)
		)
		(property "License" "Apache-2.0"
			(at 39.37 177.8 0)
			(effects
				(font
					(size 1.27 1.27)
					(thickness 0.15)
				)
				(justify left bottom)
				(hide yes)
			)
		)
		(pin "1"
		)
		(instances
			(project "jetson-agx-thor-baseboard"
				(path ""
					(reference "#PWR0748")
					(unit 1)
				)
			)
		)
	)
	(symbol
		(lib_id "antmicroCapacitorsmisc:C_22u_25V_0805")
		(at 176.53 175.26 90)
		(unit 1)
		(exclude_from_sim no)
		(in_bom yes)
		(on_board yes)
		(dnp no)
		(property "Reference" "C381"
			(at 178.308 170.1801 90)
			(effects
				(font
					(size 1.27 1.27)
					(thickness 0.15)
				)
				(justify right)
			)
		)
		(property "Value" "C_22u_25V_0805"
			(at 186.69 154.94 0)
			(effects
				(font
					(size 1.27 1.27)
					(thickness 0.15)
				)
				(justify left bottom)
				(hide yes)
			)
		)
		(property "Footprint" "antmicro-footprints:C_0805_2012Metric"
			(at 189.23 154.94 0)
			(effects
				(font
					(size 1.27 1.27)
					(thickness 0.15)
				)
				(justify left bottom)
				(hide yes)
			)
		)
		(property "Datasheet" "https://product.samsungsem.com/mlcc/CL21A226MAYNNN.do"
			(at 191.77 154.94 0)
			(effects
				(font
					(size 1.27 1.27)
					(thickness 0.15)
				)
				(justify left bottom)
				(hide yes)
			)
		)
		(property "Description" "SMT Multilayer Ceramic Capacitor, 22uF, +/-20%, 25V, X5R, 0805 [2012 Metric]"
			(at 209.55 154.94 0)
			(effects
				(font
					(size 1.27 1.27)
				)
				(justify left bottom)
				(hide yes)
			)
		)
		(property "MPN" "CL21A226MAYNNNE"
			(at 194.31 154.94 0)
			(effects
				(font
					(size 1.27 1.27)
					(thickness 0.15)
				)
				(justify left bottom)
				(hide yes)
			)
		)
		(property "Manufacturer" "Samsung Electro-Mechanics"
			(at 196.85 154.94 0)
			(effects
				(font
					(size 1.27 1.27)
					(thickness 0.15)
				)
				(justify left bottom)
				(hide yes)
			)
		)
		(property "License" "Apache-2.0"
			(at 199.39 154.94 0)
			(effects
				(font
					(size 1.27 1.27)
					(thickness 0.15)
				)
				(justify left bottom)
				(hide yes)
			)
		)
		(property "Author" "Antmicro"
			(at 201.93 154.94 0)
			(effects
				(font
					(size 1.27 1.27)
					(thickness 0.15)
				)
				(justify left bottom)
				(hide yes)
			)
		)
		(property "Val" "22u"
			(at 178.308 172.7201 90)
			(effects
				(font
					(size 1.27 1.27)
					(thickness 0.15)
				)
				(justify right)
			)
		)
		(property "Voltage" "25V"
			(at 178.308 175.26 90)
			(effects
				(font
					(size 1.27 1.27)
				)
				(justify right)
			)
		)
		(property "Dielectric" "X5R"
			(at 207.01 154.94 0)
			(effects
				(font
					(size 1.27 1.27)
				)
				(justify left bottom)
				(hide yes)
			)
		)
		(property "Public" "False"
			(at 209.55 154.94 0)
			(effects
				(font
					(size 1.27 1.27)
				)
				(justify left bottom)
				(hide yes)
			)
		)
		(pin "2"
		)
		(pin "1"
		)
		(instances
			(project "jetson-agx-thor-baseboard"
				(path ""
					(reference "C381")
					(unit 1)
				)
			)
		)
	)
	(symbol
		(lib_id "antmicroCapacitors0402:C_100n_0402")
		(at 346.71 127 90)
		(unit 1)
		(exclude_from_sim no)
		(in_bom yes)
		(on_board yes)
		(dnp no)
		(fields_autoplaced yes)
		(property "Reference" "C33"
			(at 349.25 123.1835 90)
			(effects
				(font
					(size 1.27 1.27)
					(thickness 0.15)
				)
				(justify right)
			)
		)
		(property "Value" "C_100n_0402"
			(at 356.87 106.68 0)
			(effects
				(font
					(size 1.27 1.27)
					(thickness 0.15)
				)
				(justify left bottom)
				(hide yes)
			)
		)
		(property "Footprint" "antmicro-footprints:C_0402_1005Metric"
			(at 359.41 106.68 0)
			(effects
				(font
					(size 1.27 1.27)
					(thickness 0.15)
				)
				(justify left bottom)
				(hide yes)
			)
		)
		(property "Datasheet" "https://www.murata.com/products/productdetail?partno=GRM155R61H104KE14%23"
			(at 361.95 106.68 0)
			(effects
				(font
					(size 1.27 1.27)
					(thickness 0.15)
				)
				(justify left bottom)
				(hide yes)
			)
		)
		(property "Description" "SMD Multilayer Ceramic Capacitor, 0.1 µF, 50 V, 0402 [1005 Metric], ± 10%, X5R, GRM Series"
			(at 346.71 127 0)
			(effects
				(font
					(size 1.27 1.27)
				)
				(hide yes)
			)
		)
		(property "MPN" "GRM155R61H104KE14D"
			(at 364.49 106.68 0)
			(effects
				(font
					(size 1.27 1.27)
					(thickness 0.15)
				)
				(justify left bottom)
				(hide yes)
			)
		)
		(property "Manufacturer" "Murata"
			(at 367.03 106.68 0)
			(effects
				(font
					(size 1.27 1.27)
					(thickness 0.15)
				)
				(justify left bottom)
				(hide yes)
			)
		)
		(property "License" "Apache-2.0"
			(at 369.57 106.68 0)
			(effects
				(font
					(size 1.27 1.27)
					(thickness 0.15)
				)
				(justify left bottom)
				(hide yes)
			)
		)
		(property "Author" "Antmicro"
			(at 372.11 106.68 0)
			(effects
				(font
					(size 1.27 1.27)
					(thickness 0.15)
				)
				(justify left bottom)
				(hide yes)
			)
		)
		(property "Val" "100n"
			(at 349.25 125.7235 90)
			(effects
				(font
					(size 1.27 1.27)
					(thickness 0.15)
				)
				(justify right)
			)
		)
		(property "Voltage" "50V"
			(at 374.65 106.68 0)
			(effects
				(font
					(size 1.27 1.27)
				)
				(justify left bottom)
				(hide yes)
			)
		)
		(property "Dielectric" "X5R"
			(at 377.19 106.68 0)
			(effects
				(font
					(size 1.27 1.27)
				)
				(justify left bottom)
				(hide yes)
			)
		)
		(pin "1"
		)
		(pin "2"
		)
		(instances
			(project "jetson-agx-thor-baseboard"
				(path ""
					(reference "C33")
					(unit 1)
				)
			)
		)
	)
	(symbol
		(lib_id "antmicroCapacitors0402:C_1u_0402")
		(at 74.93 186.69 90)
		(unit 1)
		(exclude_from_sim no)
		(in_bom yes)
		(on_board yes)
		(dnp no)
		(property "Reference" "C375"
			(at 75.565 182.245 90)
			(effects
				(font
					(size 1.27 1.27)
				)
				(justify right)
			)
		)
		(property "Value" "C_1u_0402"
			(at 85.09 166.37 0)
			(effects
				(font
					(size 1.27 1.27)
					(thickness 0.15)
				)
				(justify left bottom)
				(hide yes)
			)
		)
		(property "Footprint" "antmicro-footprints:C_0402_1005Metric"
			(at 87.63 166.37 0)
			(effects
				(font
					(size 1.27 1.27)
					(thickness 0.15)
				)
				(justify left bottom)
				(hide yes)
			)
		)
		(property "Datasheet" "https://product.tdk.com/en/search/capacitor/ceramic/mlcc/info?part_no=C1005X6S1A105K050BC"
			(at 90.17 166.37 0)
			(effects
				(font
					(size 1.27 1.27)
					(thickness 0.15)
				)
				(justify left bottom)
				(hide yes)
			)
		)
		(property "Description" "SMD Multilayer Ceramic Capacitor, 1 µF, 10 V, 0402 [1005 Metric], ± 10%, X6S, C"
			(at 74.93 186.69 0)
			(effects
				(font
					(size 1.27 1.27)
				)
				(hide yes)
			)
		)
		(property "Manufacturer" "TDK"
			(at 95.25 166.37 0)
			(effects
				(font
					(size 1.27 1.27)
					(thickness 0.15)
				)
				(justify left bottom)
				(hide yes)
			)
		)
		(property "MPN" "C1005X6S1A105K050BC"
			(at 92.71 166.37 0)
			(effects
				(font
					(size 1.27 1.27)
					(thickness 0.15)
				)
				(justify left bottom)
				(hide yes)
			)
		)
		(property "Val" "1u"
			(at 75.565 186.055 90)
			(effects
				(font
					(size 1.27 1.27)
					(thickness 0.15)
				)
				(justify right)
			)
		)
		(property "License" "Apache-2.0"
			(at 97.79 166.37 0)
			(effects
				(font
					(size 1.27 1.27)
					(thickness 0.15)
				)
				(justify left bottom)
				(hide yes)
			)
		)
		(property "Author" "Antmicro"
			(at 100.33 166.37 0)
			(effects
				(font
					(size 1.27 1.27)
					(thickness 0.15)
				)
				(justify left bottom)
				(hide yes)
			)
		)
		(property "Voltage" ""
			(at 102.87 166.37 0)
			(effects
				(font
					(size 1.27 1.27)
				)
				(justify left bottom)
				(hide yes)
			)
		)
		(property "Dielectric" ""
			(at 105.41 166.37 0)
			(effects
				(font
					(size 1.27 1.27)
				)
				(justify left bottom)
				(hide yes)
			)
		)
		(pin "1"
		)
		(pin "2"
		)
		(instances
			(project "jetson-agx-thor-baseboard"
				(path ""
					(reference "C375")
					(unit 1)
				)
			)
		)
	)
	(symbol
		(lib_id "antmicropower:GND")
		(at 383.54 49.53 0)
		(mirror y)
		(unit 1)
		(exclude_from_sim no)
		(in_bom yes)
		(on_board yes)
		(dnp no)
		(property "Reference" "#PWR069"
			(at 383.54 55.88 0)
			(effects
				(font
					(size 1.27 1.27)
				)
				(justify left bottom)
				(hide yes)
			)
		)
		(property "Value" "GND"
			(at 383.54 53.34 0)
			(effects
				(font
					(size 1.27 1.27)
					(thickness 0.15)
				)
			)
		)
		(property "Footprint" ""
			(at 374.65 57.15 0)
			(effects
				(font
					(size 1.27 1.27)
					(thickness 0.15)
				)
				(justify left bottom)
				(hide yes)
			)
		)
		(property "Datasheet" ""
			(at 374.65 62.23 0)
			(effects
				(font
					(size 1.27 1.27)
					(thickness 0.15)
				)
				(justify left bottom)
				(hide yes)
			)
		)
		(property "Description" ""
			(at 383.54 49.53 0)
			(effects
				(font
					(size 1.27 1.27)
				)
				(hide yes)
			)
		)
		(property "Author" "Antmicro"
			(at 374.65 57.15 0)
			(effects
				(font
					(size 1.27 1.27)
					(thickness 0.15)
				)
				(justify left bottom)
				(hide yes)
			)
		)
		(property "License" "Apache-2.0"
			(at 374.65 59.69 0)
			(effects
				(font
					(size 1.27 1.27)
					(thickness 0.15)
				)
				(justify left bottom)
				(hide yes)
			)
		)
		(pin "1"
		)
		(instances
			(project "jetson-agx-thor-baseboard"
				(path ""
					(reference "#PWR069")
					(unit 1)
				)
			)
		)
	)
	(symbol
		(lib_id "antmicroCapacitorsmisc:C_22u_25V_0805")
		(at 21.59 39.37 90)
		(unit 1)
		(exclude_from_sim no)
		(in_bom yes)
		(on_board yes)
		(dnp no)
		(property "Reference" "C270"
			(at 22.225 34.925 90)
			(effects
				(font
					(size 1.27 1.27)
					(thickness 0.15)
				)
				(justify right)
			)
		)
		(property "Value" "C_22u_25V_0805"
			(at 31.75 19.05 0)
			(effects
				(font
					(size 1.27 1.27)
					(thickness 0.15)
				)
				(justify left bottom)
				(hide yes)
			)
		)
		(property "Footprint" "antmicro-footprints:C_0805_2012Metric"
			(at 34.29 19.05 0)
			(effects
				(font
					(size 1.27 1.27)
					(thickness 0.15)
				)
				(justify left bottom)
				(hide yes)
			)
		)
		(property "Datasheet" "https://product.samsungsem.com/mlcc/CL21A226MAYNNN.do"
			(at 36.83 19.05 0)
			(effects
				(font
					(size 1.27 1.27)
					(thickness 0.15)
				)
				(justify left bottom)
				(hide yes)
			)
		)
		(property "Description" "SMT Multilayer Ceramic Capacitor, 22uF, +/-20%, 25V, X5R, 0805 [2012 Metric]"
			(at 21.59 39.37 0)
			(effects
				(font
					(size 1.27 1.27)
				)
				(hide yes)
			)
		)
		(property "MPN" "CL21A226MAYNNNE"
			(at 39.37 19.05 0)
			(effects
				(font
					(size 1.27 1.27)
					(thickness 0.15)
				)
				(justify left bottom)
				(hide yes)
			)
		)
		(property "Manufacturer" "Samsung Electro-Mechanics"
			(at 41.91 19.05 0)
			(effects
				(font
					(size 1.27 1.27)
					(thickness 0.15)
				)
				(justify left bottom)
				(hide yes)
			)
		)
		(property "License" "Apache-2.0"
			(at 44.45 19.05 0)
			(effects
				(font
					(size 1.27 1.27)
					(thickness 0.15)
				)
				(justify left bottom)
				(hide yes)
			)
		)
		(property "Author" "Antmicro"
			(at 46.99 19.05 0)
			(effects
				(font
					(size 1.27 1.27)
					(thickness 0.15)
				)
				(justify left bottom)
				(hide yes)
			)
		)
		(property "Val" "22u"
			(at 22.225 38.735 90)
			(effects
				(font
					(size 1.27 1.27)
					(thickness 0.15)
				)
				(justify right)
			)
		)
		(property "Voltage" "25V"
			(at 22.225 41.275 90)
			(effects
				(font
					(size 1.27 1.27)
				)
				(justify right)
			)
		)
		(property "Dielectric" "X5R"
			(at 52.07 19.05 0)
			(effects
				(font
					(size 1.27 1.27)
				)
				(justify left bottom)
				(hide yes)
			)
		)
		(property "Public" "False"
			(at 54.61 19.05 0)
			(effects
				(font
					(size 1.27 1.27)
				)
				(justify left bottom)
				(hide yes)
			)
		)
		(pin "2"
		)
		(pin "1"
		)
		(instances
			(project "jetson-agx-thor-baseboard"
				(path ""
					(reference "C270")
					(unit 1)
				)
			)
		)
	)
	(symbol
		(lib_id "antmicroFixedInductors:L_6u8_6.1A_MPS-MPL-AL5050")
		(at 354.33 38.1 0)
		(unit 1)
		(exclude_from_sim no)
		(in_bom yes)
		(on_board yes)
		(dnp no)
		(fields_autoplaced yes)
		(property "Reference" "L6"
			(at 356.87 33.02 0)
			(effects
				(font
					(size 1.27 1.27)
					(thickness 0.15)
				)
			)
		)
		(property "Value" "L_6u8_6.1A_MPS-MPL-AL5050"
			(at 368.3 40.64 0)
			(effects
				(font
					(size 1.27 1.27)
					(thickness 0.15)
				)
				(justify left bottom)
				(hide yes)
			)
		)
		(property "Footprint" "antmicro-footprints:L_MPS-MPL-AL5050"
			(at 368.3 45.72 0)
			(effects
				(font
					(size 1.27 1.27)
					(thickness 0.15)
				)
				(justify left bottom)
				(hide yes)
			)
		)
		(property "Datasheet" "https://www.monolithicpower.com/en/documentview/productdocument/index/version/2/document_type/Datasheet/lang/en/sku/MPL-AL5050-6R8/document_id/5811/"
			(at 368.3 48.26 0)
			(effects
				(font
					(size 1.27 1.27)
					(thickness 0.15)
				)
				(justify left bottom)
				(hide yes)
			)
		)
		(property "Description" "Power Inductor (SMT), 6.8 µH, 6.1 A, Shielded, 7.6 A, MPL-AL"
			(at 368.3 68.58 0)
			(effects
				(font
					(size 1.27 1.27)
				)
				(justify left bottom)
				(hide yes)
			)
		)
		(property "Val" "6u8/6.1A"
			(at 356.87 35.56 0)
			(effects
				(font
					(size 1.27 1.27)
					(thickness 0.15)
				)
			)
		)
		(property "Manufacturer" "Monolithic Power Systems"
			(at 368.3 50.8 0)
			(effects
				(font
					(size 1.27 1.27)
					(thickness 0.15)
				)
				(justify left bottom)
				(hide yes)
			)
		)
		(property "MPN" "MPL-AL5050-6R8"
			(at 368.3 53.34 0)
			(effects
				(font
					(size 1.27 1.27)
					(thickness 0.15)
				)
				(justify left bottom)
				(hide yes)
			)
		)
		(property "ISat" "7.6 A"
			(at 368.3 54.61 0)
			(effects
				(font
					(size 1.27 1.27)
				)
				(justify left)
				(hide yes)
			)
		)
		(property "IMax" "6.1 A"
			(at 368.3 58.42 0)
			(effects
				(font
					(size 1.27 1.27)
					(thickness 0.15)
				)
				(justify left bottom)
				(hide yes)
			)
		)
		(property "Size" "5.5x5.3"
			(at 368.3 60.96 0)
			(effects
				(font
					(size 1.27 1.27)
					(thickness 0.15)
				)
				(justify left bottom)
				(hide yes)
			)
		)
		(property "Author" "Antmicro"
			(at 368.3 63.5 0)
			(effects
				(font
					(size 1.27 1.27)
					(thickness 0.15)
				)
				(justify left bottom)
				(hide yes)
			)
		)
		(property "License" "Apache-2.0"
			(at 368.3 66.04 0)
			(effects
				(font
					(size 1.27 1.27)
					(thickness 0.15)
				)
				(justify left bottom)
				(hide yes)
			)
		)
		(pin "1"
		)
		(pin "2"
		)
		(instances
			(project "jetson-agx-thor-baseboard"
				(path ""
					(reference "L6")
					(unit 1)
				)
			)
		)
	)
	(symbol
		(lib_id "antmicroResistors0402:R_27R_0402")
		(at 203.2 41.91 270)
		(mirror x)
		(unit 1)
		(exclude_from_sim no)
		(in_bom yes)
		(on_board yes)
		(dnp no)
		(property "Reference" "R364"
			(at 200.66 38.0999 90)
			(effects
				(font
					(size 1.27 1.27)
				)
				(justify right)
			)
		)
		(property "Value" "R_27R_0402"
			(at 190.5 21.59 0)
			(effects
				(font
					(size 1.27 1.27)
					(thickness 0.15)
				)
				(justify left bottom)
				(hide yes)
			)
		)
		(property "Footprint" "antmicro-footprints:R_0402_1005Metric"
			(at 187.96 21.59 0)
			(effects
				(font
					(size 1.27 1.27)
					(thickness 0.15)
				)
				(justify left bottom)
				(hide yes)
			)
		)
		(property "Datasheet" "https://www.bourns.com/docs/product-datasheets/cr.pdf"
			(at 185.42 21.59 0)
			(effects
				(font
					(size 1.27 1.27)
					(thickness 0.15)
				)
				(justify left bottom)
				(hide yes)
			)
		)
		(property "Description" "SMD Chip Resistor, 27 ohm, ± 1%, 63 mW, 0402 [1005 Metric], Thick Film, General Purpose"
			(at 203.2 41.91 0)
			(effects
				(font
					(size 1.27 1.27)
				)
				(hide yes)
			)
		)
		(property "Manufacturer" "Bourns"
			(at 180.34 21.59 0)
			(effects
				(font
					(size 1.27 1.27)
					(thickness 0.15)
				)
				(justify left bottom)
				(hide yes)
			)
		)
		(property "MPN" "CR0402-FX-27R0GLF"
			(at 182.88 21.59 0)
			(effects
				(font
					(size 1.27 1.27)
					(thickness 0.15)
				)
				(justify left bottom)
				(hide yes)
			)
		)
		(property "Val" "27R"
			(at 200.66 40.64 90)
			(effects
				(font
					(size 1.27 1.27)
					(thickness 0.15)
				)
				(justify right)
			)
		)
		(property "License" "Apache-2.0"
			(at 177.8 21.59 0)
			(effects
				(font
					(size 1.27 1.27)
					(thickness 0.15)
				)
				(justify left bottom)
				(hide yes)
			)
		)
		(property "Author" "Antmicro"
			(at 175.26 21.59 0)
			(effects
				(font
					(size 1.27 1.27)
					(thickness 0.15)
				)
				(justify left bottom)
				(hide yes)
			)
		)
		(property "Tolerance" "1%"
			(at 193.04 21.59 0)
			(effects
				(font
					(size 1.27 1.27)
				)
				(justify left bottom)
				(hide yes)
			)
		)
		(pin "1"
		)
		(pin "2"
		)
		(instances
			(project "jetson-agx-thor-baseboard"
				(path ""
					(reference "R364")
					(unit 1)
				)
			)
		)
	)
	(symbol
		(lib_id "antmicroResistors0402:R_499k_0402")
		(at 55.88 231.14 90)
		(unit 1)
		(exclude_from_sim no)
		(in_bom yes)
		(on_board yes)
		(dnp no)
		(property "Reference" "R37"
			(at 57.15 227.33 90)
			(effects
				(font
					(size 1.27 1.27)
					(thickness 0.15)
				)
				(justify right)
			)
		)
		(property "Value" "R_499k_0402"
			(at 68.58 210.82 0)
			(effects
				(font
					(size 1.27 1.27)
					(thickness 0.15)
				)
				(justify left bottom)
				(hide yes)
			)
		)
		(property "Footprint" "antmicro-footprints:R_0402_1005Metric"
			(at 71.12 210.82 0)
			(effects
				(font
					(size 1.27 1.27)
					(thickness 0.15)
				)
				(justify left bottom)
				(hide yes)
			)
		)
		(property "Datasheet" "https://www.mouser.com/datasheet/2/54/cr-1858361.pdf"
			(at 73.66 210.82 0)
			(effects
				(font
					(size 1.27 1.27)
					(thickness 0.15)
				)
				(justify left bottom)
				(hide yes)
			)
		)
		(property "Description" "SMD Chip Resistor, 499 kohm, ± 1%, 63 mW, 0402 [1005 Metric], Thick Film, General Purpose"
			(at 55.88 231.14 0)
			(effects
				(font
					(size 1.27 1.27)
				)
				(hide yes)
			)
		)
		(property "MPN" "CR0402-FX-4993GLF"
			(at 76.2 210.82 0)
			(effects
				(font
					(size 1.27 1.27)
					(thickness 0.15)
				)
				(justify left bottom)
				(hide yes)
			)
		)
		(property "Manufacturer" "Bourns"
			(at 78.74 210.82 0)
			(effects
				(font
					(size 1.27 1.27)
					(thickness 0.15)
				)
				(justify left bottom)
				(hide yes)
			)
		)
		(property "License" "Apache-2.0"
			(at 81.28 210.82 0)
			(effects
				(font
					(size 1.27 1.27)
					(thickness 0.15)
				)
				(justify left bottom)
				(hide yes)
			)
		)
		(property "Author" "Antmicro"
			(at 83.82 210.82 0)
			(effects
				(font
					(size 1.27 1.27)
					(thickness 0.15)
				)
				(justify left bottom)
				(hide yes)
			)
		)
		(property "Val" "499k"
			(at 57.15 229.87 90)
			(effects
				(font
					(size 1.27 1.27)
					(thickness 0.15)
				)
				(justify right)
			)
		)
		(property "Tolerance" "1%"
			(at 66.04 210.82 0)
			(effects
				(font
					(size 1.27 1.27)
				)
				(justify left bottom)
				(hide yes)
			)
		)
		(pin "2"
		)
		(pin "1"
		)
		(instances
			(project "jetson-agx-thor-baseboard"
				(path ""
					(reference "R37")
					(unit 1)
				)
			)
		)
	)
	(symbol
		(lib_id "antmicropower:PWR_FLAG")
		(at 233.68 167.64 270)
		(unit 1)
		(exclude_from_sim no)
		(in_bom yes)
		(on_board yes)
		(dnp no)
		(property "Reference" "#FLG0115"
			(at 235.585 167.64 0)
			(effects
				(font
					(size 1.27 1.27)
				)
				(hide yes)
			)
		)
		(property "Value" "PWR_FLAG"
			(at 237.236 170.18 90)
			(effects
				(font
					(size 1.27 1.27)
				)
			)
		)
		(property "Footprint" ""
			(at 233.68 167.64 0)
			(effects
				(font
					(size 1.27 1.27)
				)
				(hide yes)
			)
		)
		(property "Datasheet" ""
			(at 233.68 167.64 0)
			(effects
				(font
					(size 1.27 1.27)
				)
				(hide yes)
			)
		)
		(property "Description" ""
			(at 233.68 167.64 0)
			(effects
				(font
					(size 1.27 1.27)
				)
				(hide yes)
			)
		)
		(pin "1"
		)
		(instances
			(project "jetson-agx-thor-baseboard"
				(path ""
					(reference "#FLG0115")
					(unit 1)
				)
			)
		)
	)
	(symbol
		(lib_id "antmicroResistors0402:R_2k37_0402")
		(at 16.51 186.69 270)
		(mirror x)
		(unit 1)
		(exclude_from_sim no)
		(in_bom yes)
		(on_board yes)
		(dnp no)
		(property "Reference" "R251"
			(at 17.78 182.88 90)
			(effects
				(font
					(size 1.27 1.27)
					(thickness 0.15)
				)
				(justify left)
			)
		)
		(property "Value" "R_2k37_0402"
			(at 3.81 166.37 0)
			(effects
				(font
					(size 1.27 1.27)
					(thickness 0.15)
				)
				(justify left bottom)
				(hide yes)
			)
		)
		(property "Footprint" "antmicro-footprints:R_0402_1005Metric"
			(at 1.27 166.37 0)
			(effects
				(font
					(size 1.27 1.27)
					(thickness 0.15)
				)
				(justify left bottom)
				(hide yes)
			)
		)
		(property "Datasheet" "https://www.bourns.com/docs/product-datasheets/cr.pdf"
			(at -1.27 166.37 0)
			(effects
				(font
					(size 1.27 1.27)
					(thickness 0.15)
				)
				(justify left bottom)
				(hide yes)
			)
		)
		(property "Description" "SMD Chip Resistor"
			(at -13.97 166.37 0)
			(effects
				(font
					(size 1.27 1.27)
				)
				(justify left bottom)
				(hide yes)
			)
		)
		(property "MPN" "CR0402-FX-2371GLF"
			(at -3.81 166.37 0)
			(effects
				(font
					(size 1.27 1.27)
					(thickness 0.15)
				)
				(justify left bottom)
				(hide yes)
			)
		)
		(property "Manufacturer" "Bourns"
			(at -6.35 166.37 0)
			(effects
				(font
					(size 1.27 1.27)
					(thickness 0.15)
				)
				(justify left bottom)
				(hide yes)
			)
		)
		(property "License" "Apache-2.0"
			(at -8.89 166.37 0)
			(effects
				(font
					(size 1.27 1.27)
					(thickness 0.15)
				)
				(justify left bottom)
				(hide yes)
			)
		)
		(property "Author" "Antmicro"
			(at -11.43 166.37 0)
			(effects
				(font
					(size 1.27 1.27)
					(thickness 0.15)
				)
				(justify left bottom)
				(hide yes)
			)
		)
		(property "Val" "2k37"
			(at 17.78 185.42 90)
			(effects
				(font
					(size 1.27 1.27)
					(thickness 0.15)
				)
				(justify left)
			)
		)
		(property "Tolerance" "1%"
			(at 6.35 166.37 0)
			(effects
				(font
					(size 1.27 1.27)
				)
				(justify left bottom)
				(hide yes)
			)
		)
		(pin "2"
		)
		(pin "1"
		)
		(instances
			(project "jetson-agx-thor-baseboard"
				(path ""
					(reference "R251")
					(unit 1)
				)
			)
		)
	)
	(symbol
		(lib_id "antmicroCapacitorsmisc:C_22u_25V_0805")
		(at 154.94 43.18 90)
		(unit 1)
		(exclude_from_sim no)
		(in_bom yes)
		(on_board yes)
		(dnp no)
		(property "Reference" "C247"
			(at 156.464 38.1001 90)
			(effects
				(font
					(size 1.27 1.27)
					(thickness 0.15)
				)
				(justify right)
			)
		)
		(property "Value" "C_22u_25V_0805"
			(at 165.1 22.86 0)
			(effects
				(font
					(size 1.27 1.27)
					(thickness 0.15)
				)
				(justify left bottom)
				(hide yes)
			)
		)
		(property "Footprint" "antmicro-footprints:C_0805_2012Metric"
			(at 167.64 22.86 0)
			(effects
				(font
					(size 1.27 1.27)
					(thickness 0.15)
				)
				(justify left bottom)
				(hide yes)
			)
		)
		(property "Datasheet" "https://product.samsungsem.com/mlcc/CL21A226MAYNNN.do"
			(at 170.18 22.86 0)
			(effects
				(font
					(size 1.27 1.27)
					(thickness 0.15)
				)
				(justify left bottom)
				(hide yes)
			)
		)
		(property "Description" "SMT Multilayer Ceramic Capacitor, 22uF, +/-20%, 25V, X5R, 0805 [2012 Metric]"
			(at 187.96 22.86 0)
			(effects
				(font
					(size 1.27 1.27)
				)
				(justify left bottom)
				(hide yes)
			)
		)
		(property "MPN" "CL21A226MAYNNNE"
			(at 172.72 22.86 0)
			(effects
				(font
					(size 1.27 1.27)
					(thickness 0.15)
				)
				(justify left bottom)
				(hide yes)
			)
		)
		(property "Manufacturer" "Samsung Electro-Mechanics"
			(at 175.26 22.86 0)
			(effects
				(font
					(size 1.27 1.27)
					(thickness 0.15)
				)
				(justify left bottom)
				(hide yes)
			)
		)
		(property "License" "Apache-2.0"
			(at 177.8 22.86 0)
			(effects
				(font
					(size 1.27 1.27)
					(thickness 0.15)
				)
				(justify left bottom)
				(hide yes)
			)
		)
		(property "Author" "Antmicro"
			(at 180.34 22.86 0)
			(effects
				(font
					(size 1.27 1.27)
					(thickness 0.15)
				)
				(justify left bottom)
				(hide yes)
			)
		)
		(property "Val" "22u"
			(at 156.464 40.6401 90)
			(effects
				(font
					(size 1.27 1.27)
					(thickness 0.15)
				)
				(justify right)
			)
		)
		(property "Voltage" "25V"
			(at 156.464 43.18 90)
			(effects
				(font
					(size 1.27 1.27)
				)
				(justify right)
			)
		)
		(property "Dielectric" "X5R"
			(at 185.42 22.86 0)
			(effects
				(font
					(size 1.27 1.27)
				)
				(justify left bottom)
				(hide yes)
			)
		)
		(property "Public" "False"
			(at 187.96 22.86 0)
			(effects
				(font
					(size 1.27 1.27)
				)
				(justify left bottom)
				(hide yes)
			)
		)
		(pin "2"
		)
		(pin "1"
		)
		(instances
			(project "jetson-agx-thor-baseboard"
				(path ""
					(reference "C247")
					(unit 1)
				)
			)
		)
	)
	(symbol
		(lib_id "antmicroCapacitorsmisc:C_22u_25V_0805")
		(at 27.94 39.37 90)
		(unit 1)
		(exclude_from_sim no)
		(in_bom yes)
		(on_board yes)
		(dnp no)
		(property "Reference" "C275"
			(at 28.575 34.925 90)
			(effects
				(font
					(size 1.27 1.27)
					(thickness 0.15)
				)
				(justify right)
			)
		)
		(property "Value" "C_22u_25V_0805"
			(at 38.1 19.05 0)
			(effects
				(font
					(size 1.27 1.27)
					(thickness 0.15)
				)
				(justify left bottom)
				(hide yes)
			)
		)
		(property "Footprint" "antmicro-footprints:C_0805_2012Metric"
			(at 40.64 19.05 0)
			(effects
				(font
					(size 1.27 1.27)
					(thickness 0.15)
				)
				(justify left bottom)
				(hide yes)
			)
		)
		(property "Datasheet" "https://product.samsungsem.com/mlcc/CL21A226MAYNNN.do"
			(at 43.18 19.05 0)
			(effects
				(font
					(size 1.27 1.27)
					(thickness 0.15)
				)
				(justify left bottom)
				(hide yes)
			)
		)
		(property "Description" "SMT Multilayer Ceramic Capacitor, 22uF, +/-20%, 25V, X5R, 0805 [2012 Metric]"
			(at 27.94 39.37 0)
			(effects
				(font
					(size 1.27 1.27)
				)
				(hide yes)
			)
		)
		(property "MPN" "CL21A226MAYNNNE"
			(at 45.72 19.05 0)
			(effects
				(font
					(size 1.27 1.27)
					(thickness 0.15)
				)
				(justify left bottom)
				(hide yes)
			)
		)
		(property "Manufacturer" "Samsung Electro-Mechanics"
			(at 48.26 19.05 0)
			(effects
				(font
					(size 1.27 1.27)
					(thickness 0.15)
				)
				(justify left bottom)
				(hide yes)
			)
		)
		(property "License" "Apache-2.0"
			(at 50.8 19.05 0)
			(effects
				(font
					(size 1.27 1.27)
					(thickness 0.15)
				)
				(justify left bottom)
				(hide yes)
			)
		)
		(property "Author" "Antmicro"
			(at 53.34 19.05 0)
			(effects
				(font
					(size 1.27 1.27)
					(thickness 0.15)
				)
				(justify left bottom)
				(hide yes)
			)
		)
		(property "Val" "22u"
			(at 28.575 38.735 90)
			(effects
				(font
					(size 1.27 1.27)
					(thickness 0.15)
				)
				(justify right)
			)
		)
		(property "Voltage" "25V"
			(at 28.575 41.275 90)
			(effects
				(font
					(size 1.27 1.27)
				)
				(justify right)
			)
		)
		(property "Dielectric" "X5R"
			(at 58.42 19.05 0)
			(effects
				(font
					(size 1.27 1.27)
				)
				(justify left bottom)
				(hide yes)
			)
		)
		(property "Public" "False"
			(at 60.96 19.05 0)
			(effects
				(font
					(size 1.27 1.27)
				)
				(justify left bottom)
				(hide yes)
			)
		)
		(pin "1"
		)
		(pin "2"
		)
		(instances
			(project "jetson-agx-thor-baseboard"
				(path ""
					(reference "C275")
					(unit 1)
				)
			)
		)
	)
	(symbol
		(lib_id "antmicroResistors0402:R_27R_0402")
		(at 215.9 165.1 90)
		(unit 1)
		(exclude_from_sim no)
		(in_bom yes)
		(on_board yes)
		(dnp no)
		(property "Reference" "R367"
			(at 216.916 161.2899 90)
			(effects
				(font
					(size 1.27 1.27)
				)
				(justify right)
			)
		)
		(property "Value" "R_27R_0402"
			(at 228.6 144.78 0)
			(effects
				(font
					(size 1.27 1.27)
					(thickness 0.15)
				)
				(justify left bottom)
				(hide yes)
			)
		)
		(property "Footprint" "antmicro-footprints:R_0402_1005Metric"
			(at 231.14 144.78 0)
			(effects
				(font
					(size 1.27 1.27)
					(thickness 0.15)
				)
				(justify left bottom)
				(hide yes)
			)
		)
		(property "Datasheet" "https://www.bourns.com/docs/product-datasheets/cr.pdf"
			(at 233.68 144.78 0)
			(effects
				(font
					(size 1.27 1.27)
					(thickness 0.15)
				)
				(justify left bottom)
				(hide yes)
			)
		)
		(property "Description" "SMD Chip Resistor, 27 ohm, ± 1%, 63 mW, 0402 [1005 Metric], Thick Film, General Purpose"
			(at 215.9 165.1 0)
			(effects
				(font
					(size 1.27 1.27)
				)
				(hide yes)
			)
		)
		(property "Manufacturer" "Bourns"
			(at 238.76 144.78 0)
			(effects
				(font
					(size 1.27 1.27)
					(thickness 0.15)
				)
				(justify left bottom)
				(hide yes)
			)
		)
		(property "MPN" "CR0402-FX-27R0GLF"
			(at 236.22 144.78 0)
			(effects
				(font
					(size 1.27 1.27)
					(thickness 0.15)
				)
				(justify left bottom)
				(hide yes)
			)
		)
		(property "Val" "27R"
			(at 216.916 163.83 90)
			(effects
				(font
					(size 1.27 1.27)
					(thickness 0.15)
				)
				(justify right)
			)
		)
		(property "License" "Apache-2.0"
			(at 241.3 144.78 0)
			(effects
				(font
					(size 1.27 1.27)
					(thickness 0.15)
				)
				(justify left bottom)
				(hide yes)
			)
		)
		(property "Author" "Antmicro"
			(at 243.84 144.78 0)
			(effects
				(font
					(size 1.27 1.27)
					(thickness 0.15)
				)
				(justify left bottom)
				(hide yes)
			)
		)
		(property "Tolerance" "1%"
			(at 226.06 144.78 0)
			(effects
				(font
					(size 1.27 1.27)
				)
				(justify left bottom)
				(hide yes)
			)
		)
		(pin "1"
		)
		(pin "2"
		)
		(instances
			(project "jetson-agx-thor-baseboard"
				(path ""
					(reference "R367")
					(unit 1)
				)
			)
		)
	)
	(symbol
		(lib_id "antmicropower:GND")
		(at 74.93 121.92 0)
		(unit 1)
		(exclude_from_sim no)
		(in_bom yes)
		(on_board yes)
		(dnp no)
		(property "Reference" "#PWR0549"
			(at 74.93 128.27 0)
			(effects
				(font
					(size 1.27 1.27)
				)
				(justify left bottom)
				(hide yes)
			)
		)
		(property "Value" "GND"
			(at 74.93 125.73 0)
			(effects
				(font
					(size 1.27 1.27)
					(thickness 0.15)
				)
			)
		)
		(property "Footprint" ""
			(at 83.82 129.54 0)
			(effects
				(font
					(size 1.27 1.27)
					(thickness 0.15)
				)
				(justify left bottom)
				(hide yes)
			)
		)
		(property "Datasheet" ""
			(at 83.82 134.62 0)
			(effects
				(font
					(size 1.27 1.27)
					(thickness 0.15)
				)
				(justify left bottom)
				(hide yes)
			)
		)
		(property "Description" ""
			(at 74.93 121.92 0)
			(effects
				(font
					(size 1.27 1.27)
				)
				(hide yes)
			)
		)
		(property "Author" "Antmicro"
			(at 83.82 129.54 0)
			(effects
				(font
					(size 1.27 1.27)
					(thickness 0.15)
				)
				(justify left bottom)
				(hide yes)
			)
		)
		(property "License" "Apache-2.0"
			(at 83.82 132.08 0)
			(effects
				(font
					(size 1.27 1.27)
					(thickness 0.15)
				)
				(justify left bottom)
				(hide yes)
			)
		)
		(pin "1"
		)
		(instances
			(project "jetson-agx-thor-baseboard"
				(path ""
					(reference "#PWR0549")
					(unit 1)
				)
			)
		)
	)
	(symbol
		(lib_id "antmicropower:GND")
		(at 232.41 279.4 0)
		(unit 1)
		(exclude_from_sim no)
		(in_bom yes)
		(on_board yes)
		(dnp no)
		(property "Reference" "#PWR0154"
			(at 232.41 285.75 0)
			(effects
				(font
					(size 1.27 1.27)
				)
				(justify left bottom)
				(hide yes)
			)
		)
		(property "Value" "GND"
			(at 232.41 283.21 0)
			(effects
				(font
					(size 1.27 1.27)
					(thickness 0.15)
				)
			)
		)
		(property "Footprint" ""
			(at 241.3 287.02 0)
			(effects
				(font
					(size 1.27 1.27)
					(thickness 0.15)
				)
				(justify left bottom)
				(hide yes)
			)
		)
		(property "Datasheet" ""
			(at 241.3 292.1 0)
			(effects
				(font
					(size 1.27 1.27)
					(thickness 0.15)
				)
				(justify left bottom)
				(hide yes)
			)
		)
		(property "Description" ""
			(at 232.41 279.4 0)
			(effects
				(font
					(size 1.27 1.27)
				)
				(hide yes)
			)
		)
		(property "Author" "Antmicro"
			(at 241.3 287.02 0)
			(effects
				(font
					(size 1.27 1.27)
					(thickness 0.15)
				)
				(justify left bottom)
				(hide yes)
			)
		)
		(property "License" "Apache-2.0"
			(at 241.3 289.56 0)
			(effects
				(font
					(size 1.27 1.27)
					(thickness 0.15)
				)
				(justify left bottom)
				(hide yes)
			)
		)
		(pin "1"
		)
		(instances
			(project "jetson-agx-thor-baseboard"
				(path ""
					(reference "#PWR0154")
					(unit 1)
				)
			)
		)
	)
	(symbol
		(lib_id "antmicropower:GND")
		(at 266.7 194.31 0)
		(unit 1)
		(exclude_from_sim no)
		(in_bom yes)
		(on_board yes)
		(dnp no)
		(property "Reference" "#PWR050"
			(at 275.59 196.85 0)
			(effects
				(font
					(size 1.27 1.27)
					(thickness 0.15)
				)
				(justify left bottom)
				(hide yes)
			)
		)
		(property "Value" "GND"
			(at 266.7 198.12 0)
			(effects
				(font
					(size 1.27 1.27)
					(thickness 0.15)
				)
			)
		)
		(property "Footprint" ""
			(at 275.59 201.93 0)
			(effects
				(font
					(size 1.27 1.27)
					(thickness 0.15)
				)
				(justify left bottom)
				(hide yes)
			)
		)
		(property "Datasheet" ""
			(at 275.59 207.01 0)
			(effects
				(font
					(size 1.27 1.27)
					(thickness 0.15)
				)
				(justify left bottom)
				(hide yes)
			)
		)
		(property "Description" ""
			(at 266.7 194.31 0)
			(effects
				(font
					(size 1.27 1.27)
				)
				(hide yes)
			)
		)
		(property "Author" "Antmicro"
			(at 275.59 201.93 0)
			(effects
				(font
					(size 1.27 1.27)
					(thickness 0.15)
				)
				(justify left bottom)
				(hide yes)
			)
		)
		(property "License" "Apache-2.0"
			(at 275.59 204.47 0)
			(effects
				(font
					(size 1.27 1.27)
					(thickness 0.15)
				)
				(justify left bottom)
				(hide yes)
			)
		)
		(pin "1"
		)
		(instances
			(project "jetson-agx-thor-baseboard"
				(path ""
					(reference "#PWR050")
					(unit 1)
				)
			)
		)
	)
	(symbol
		(lib_id "antmicroCapacitorsmisc:C_22u_25V_0805")
		(at 383.54 48.26 90)
		(unit 1)
		(exclude_from_sim no)
		(in_bom yes)
		(on_board yes)
		(dnp no)
		(property "Reference" "C222"
			(at 386.08 43.1735 90)
			(effects
				(font
					(size 1.27 1.27)
				)
				(justify right)
			)
		)
		(property "Value" "C_22u_25V_0805"
			(at 393.7 27.94 0)
			(effects
				(font
					(size 1.27 1.27)
					(thickness 0.15)
				)
				(justify left bottom)
				(hide yes)
			)
		)
		(property "Footprint" "antmicro-footprints:C_0805_2012Metric"
			(at 396.24 27.94 0)
			(effects
				(font
					(size 1.27 1.27)
					(thickness 0.15)
				)
				(justify left bottom)
				(hide yes)
			)
		)
		(property "Datasheet" "https://product.samsungsem.com/mlcc/CL21A226MAYNNN.do"
			(at 398.78 27.94 0)
			(effects
				(font
					(size 1.27 1.27)
					(thickness 0.15)
				)
				(justify left bottom)
				(hide yes)
			)
		)
		(property "Description" "SMT Multilayer Ceramic Capacitor, 22uF, +/-20%, 25V, X5R, 0805 [2012 Metric]"
			(at 383.54 48.26 0)
			(effects
				(font
					(size 1.27 1.27)
				)
				(hide yes)
			)
		)
		(property "Manufacturer" "Samsung Electro-Mechanics"
			(at 403.86 27.94 0)
			(effects
				(font
					(size 1.27 1.27)
					(thickness 0.15)
				)
				(justify left bottom)
				(hide yes)
			)
		)
		(property "MPN" "CL21A226MAYNNNE"
			(at 401.32 27.94 0)
			(effects
				(font
					(size 1.27 1.27)
					(thickness 0.15)
				)
				(justify left bottom)
				(hide yes)
			)
		)
		(property "Val" "22u"
			(at 386.08 45.7136 90)
			(effects
				(font
					(size 1.27 1.27)
					(thickness 0.15)
				)
				(justify right)
			)
		)
		(property "License" "Apache-2.0"
			(at 406.4 27.94 0)
			(effects
				(font
					(size 1.27 1.27)
					(thickness 0.15)
				)
				(justify left bottom)
				(hide yes)
			)
		)
		(property "Author" "Antmicro"
			(at 408.94 27.94 0)
			(effects
				(font
					(size 1.27 1.27)
					(thickness 0.15)
				)
				(justify left bottom)
				(hide yes)
			)
		)
		(property "Voltage" "25V"
			(at 386.08 48.2535 90)
			(effects
				(font
					(size 1.27 1.27)
				)
				(justify right)
			)
		)
		(property "Dielectric" "X5R"
			(at 414.02 27.94 0)
			(effects
				(font
					(size 1.27 1.27)
				)
				(justify left bottom)
				(hide yes)
			)
		)
		(property "Public" "False"
			(at 416.56 27.94 0)
			(effects
				(font
					(size 1.27 1.27)
				)
				(justify left bottom)
				(hide yes)
			)
		)
		(pin "1"
		)
		(pin "2"
		)
		(instances
			(project "jetson-agx-thor-baseboard"
				(path ""
					(reference "C222")
					(unit 1)
				)
			)
		)
	)
	(symbol
		(lib_id "antmicroCapacitors0402:C_1u_0402")
		(at 294.64 57.15 90)
		(unit 1)
		(exclude_from_sim no)
		(in_bom yes)
		(on_board yes)
		(dnp no)
		(property "Reference" "C54"
			(at 295.275 52.705 90)
			(effects
				(font
					(size 1.27 1.27)
				)
				(justify right)
			)
		)
		(property "Value" "C_1u_0402"
			(at 304.8 36.83 0)
			(effects
				(font
					(size 1.27 1.27)
					(thickness 0.15)
				)
				(justify left bottom)
				(hide yes)
			)
		)
		(property "Footprint" "antmicro-footprints:C_0402_1005Metric"
			(at 307.34 36.83 0)
			(effects
				(font
					(size 1.27 1.27)
					(thickness 0.15)
				)
				(justify left bottom)
				(hide yes)
			)
		)
		(property "Datasheet" "https://product.tdk.com/en/search/capacitor/ceramic/mlcc/info?part_no=C1005X6S1A105K050BC"
			(at 309.88 36.83 0)
			(effects
				(font
					(size 1.27 1.27)
					(thickness 0.15)
				)
				(justify left bottom)
				(hide yes)
			)
		)
		(property "Description" "SMD Multilayer Ceramic Capacitor, 1 µF, 10 V, 0402 [1005 Metric], ± 10%, X6S, C"
			(at 294.64 57.15 0)
			(effects
				(font
					(size 1.27 1.27)
				)
				(hide yes)
			)
		)
		(property "Manufacturer" "TDK"
			(at 314.96 36.83 0)
			(effects
				(font
					(size 1.27 1.27)
					(thickness 0.15)
				)
				(justify left bottom)
				(hide yes)
			)
		)
		(property "MPN" "C1005X6S1A105K050BC"
			(at 312.42 36.83 0)
			(effects
				(font
					(size 1.27 1.27)
					(thickness 0.15)
				)
				(justify left bottom)
				(hide yes)
			)
		)
		(property "Val" "1u"
			(at 295.275 56.515 90)
			(effects
				(font
					(size 1.27 1.27)
					(thickness 0.15)
				)
				(justify right)
			)
		)
		(property "License" "Apache-2.0"
			(at 317.5 36.83 0)
			(effects
				(font
					(size 1.27 1.27)
					(thickness 0.15)
				)
				(justify left bottom)
				(hide yes)
			)
		)
		(property "Author" "Antmicro"
			(at 320.04 36.83 0)
			(effects
				(font
					(size 1.27 1.27)
					(thickness 0.15)
				)
				(justify left bottom)
				(hide yes)
			)
		)
		(property "Voltage" ""
			(at 322.58 36.83 0)
			(effects
				(font
					(size 1.27 1.27)
				)
				(justify left bottom)
				(hide yes)
			)
		)
		(property "Dielectric" ""
			(at 325.12 36.83 0)
			(effects
				(font
					(size 1.27 1.27)
				)
				(justify left bottom)
				(hide yes)
			)
		)
		(pin "1"
		)
		(pin "2"
		)
		(instances
			(project "jetson-agx-thor-baseboard"
				(path ""
					(reference "C54")
					(unit 1)
				)
			)
		)
	)
	(symbol
		(lib_id "antmicroResistors0402:R_499k_0402")
		(at 278.13 57.15 90)
		(unit 1)
		(exclude_from_sim no)
		(in_bom yes)
		(on_board yes)
		(dnp no)
		(property "Reference" "R13"
			(at 279.4 53.34 90)
			(effects
				(font
					(size 1.27 1.27)
					(thickness 0.15)
				)
				(justify right)
			)
		)
		(property "Value" "R_499k_0402"
			(at 290.83 36.83 0)
			(effects
				(font
					(size 1.27 1.27)
					(thickness 0.15)
				)
				(justify left bottom)
				(hide yes)
			)
		)
		(property "Footprint" "antmicro-footprints:R_0402_1005Metric"
			(at 293.37 36.83 0)
			(effects
				(font
					(size 1.27 1.27)
					(thickness 0.15)
				)
				(justify left bottom)
				(hide yes)
			)
		)
		(property "Datasheet" "https://www.mouser.com/datasheet/2/54/cr-1858361.pdf"
			(at 295.91 36.83 0)
			(effects
				(font
					(size 1.27 1.27)
					(thickness 0.15)
				)
				(justify left bottom)
				(hide yes)
			)
		)
		(property "Description" "SMD Chip Resistor, 499 kohm, ± 1%, 63 mW, 0402 [1005 Metric], Thick Film, General Purpose"
			(at 278.13 57.15 0)
			(effects
				(font
					(size 1.27 1.27)
				)
				(hide yes)
			)
		)
		(property "MPN" "CR0402-FX-4993GLF"
			(at 298.45 36.83 0)
			(effects
				(font
					(size 1.27 1.27)
					(thickness 0.15)
				)
				(justify left bottom)
				(hide yes)
			)
		)
		(property "Manufacturer" "Bourns"
			(at 300.99 36.83 0)
			(effects
				(font
					(size 1.27 1.27)
					(thickness 0.15)
				)
				(justify left bottom)
				(hide yes)
			)
		)
		(property "License" "Apache-2.0"
			(at 303.53 36.83 0)
			(effects
				(font
					(size 1.27 1.27)
					(thickness 0.15)
				)
				(justify left bottom)
				(hide yes)
			)
		)
		(property "Author" "Antmicro"
			(at 306.07 36.83 0)
			(effects
				(font
					(size 1.27 1.27)
					(thickness 0.15)
				)
				(justify left bottom)
				(hide yes)
			)
		)
		(property "Val" "499k"
			(at 279.4 55.88 90)
			(effects
				(font
					(size 1.27 1.27)
					(thickness 0.15)
				)
				(justify right)
			)
		)
		(property "Tolerance" "1%"
			(at 288.29 36.83 0)
			(effects
				(font
					(size 1.27 1.27)
				)
				(justify left bottom)
				(hide yes)
			)
		)
		(pin "2"
		)
		(pin "1"
		)
		(instances
			(project "jetson-agx-thor-baseboard"
				(path ""
					(reference "R13")
					(unit 1)
				)
			)
		)
	)
	(symbol
		(lib_id "antmicroCapacitorsmisc:C_22u_25V_0805")
		(at 36.83 165.1 90)
		(unit 1)
		(exclude_from_sim no)
		(in_bom yes)
		(on_board yes)
		(dnp no)
		(property "Reference" "C372"
			(at 37.465 160.655 90)
			(effects
				(font
					(size 1.27 1.27)
					(thickness 0.15)
				)
				(justify right)
			)
		)
		(property "Value" "C_22u_25V_0805"
			(at 46.99 144.78 0)
			(effects
				(font
					(size 1.27 1.27)
					(thickness 0.15)
				)
				(justify left bottom)
				(hide yes)
			)
		)
		(property "Footprint" "antmicro-footprints:C_0805_2012Metric"
			(at 49.53 144.78 0)
			(effects
				(font
					(size 1.27 1.27)
					(thickness 0.15)
				)
				(justify left bottom)
				(hide yes)
			)
		)
		(property "Datasheet" "https://product.samsungsem.com/mlcc/CL21A226MAYNNN.do"
			(at 52.07 144.78 0)
			(effects
				(font
					(size 1.27 1.27)
					(thickness 0.15)
				)
				(justify left bottom)
				(hide yes)
			)
		)
		(property "Description" "SMT Multilayer Ceramic Capacitor, 22uF, +/-20%, 25V, X5R, 0805 [2012 Metric]"
			(at 36.83 165.1 0)
			(effects
				(font
					(size 1.27 1.27)
				)
				(hide yes)
			)
		)
		(property "MPN" "CL21A226MAYNNNE"
			(at 54.61 144.78 0)
			(effects
				(font
					(size 1.27 1.27)
					(thickness 0.15)
				)
				(justify left bottom)
				(hide yes)
			)
		)
		(property "Manufacturer" "Samsung Electro-Mechanics"
			(at 57.15 144.78 0)
			(effects
				(font
					(size 1.27 1.27)
					(thickness 0.15)
				)
				(justify left bottom)
				(hide yes)
			)
		)
		(property "License" "Apache-2.0"
			(at 59.69 144.78 0)
			(effects
				(font
					(size 1.27 1.27)
					(thickness 0.15)
				)
				(justify left bottom)
				(hide yes)
			)
		)
		(property "Author" "Antmicro"
			(at 62.23 144.78 0)
			(effects
				(font
					(size 1.27 1.27)
					(thickness 0.15)
				)
				(justify left bottom)
				(hide yes)
			)
		)
		(property "Val" "22u"
			(at 37.465 164.465 90)
			(effects
				(font
					(size 1.27 1.27)
					(thickness 0.15)
				)
				(justify right)
			)
		)
		(property "Voltage" "25V"
			(at 37.465 167.005 90)
			(effects
				(font
					(size 1.27 1.27)
				)
				(justify right)
			)
		)
		(property "Dielectric" "X5R"
			(at 67.31 144.78 0)
			(effects
				(font
					(size 1.27 1.27)
				)
				(justify left bottom)
				(hide yes)
			)
		)
		(property "Public" "False"
			(at 69.85 144.78 0)
			(effects
				(font
					(size 1.27 1.27)
				)
				(justify left bottom)
				(hide yes)
			)
		)
		(pin "2"
		)
		(pin "1"
		)
		(instances
			(project "jetson-agx-thor-baseboard"
				(path ""
					(reference "C372")
					(unit 1)
				)
			)
		)
	)
	(symbol
		(lib_id "antmicroCapacitors0402:C_100n_0402")
		(at 215.9 186.69 90)
		(unit 1)
		(exclude_from_sim no)
		(in_bom yes)
		(on_board yes)
		(dnp no)
		(property "Reference" "C387"
			(at 218.44 182.8735 90)
			(effects
				(font
					(size 1.27 1.27)
					(thickness 0.15)
				)
				(justify right)
			)
		)
		(property "Value" "C_100n_0402"
			(at 226.06 166.37 0)
			(effects
				(font
					(size 1.27 1.27)
					(thickness 0.15)
				)
				(justify left bottom)
				(hide yes)
			)
		)
		(property "Footprint" "antmicro-footprints:C_0402_1005Metric"
			(at 228.6 166.37 0)
			(effects
				(font
					(size 1.27 1.27)
					(thickness 0.15)
				)
				(justify left bottom)
				(hide yes)
			)
		)
		(property "Datasheet" "https://www.murata.com/products/productdetail?partno=GRM155R61H104KE14%23"
			(at 231.14 166.37 0)
			(effects
				(font
					(size 1.27 1.27)
					(thickness 0.15)
				)
				(justify left bottom)
				(hide yes)
			)
		)
		(property "Description" "SMD Multilayer Ceramic Capacitor, 0.1 µF, 50 V, 0402 [1005 Metric], ± 10%, X5R, GRM Series"
			(at 215.9 186.69 0)
			(effects
				(font
					(size 1.27 1.27)
				)
				(hide yes)
			)
		)
		(property "MPN" "GRM155R61H104KE14D"
			(at 233.68 166.37 0)
			(effects
				(font
					(size 1.27 1.27)
					(thickness 0.15)
				)
				(justify left bottom)
				(hide yes)
			)
		)
		(property "Manufacturer" "Murata"
			(at 236.22 166.37 0)
			(effects
				(font
					(size 1.27 1.27)
					(thickness 0.15)
				)
				(justify left bottom)
				(hide yes)
			)
		)
		(property "License" "Apache-2.0"
			(at 238.76 166.37 0)
			(effects
				(font
					(size 1.27 1.27)
					(thickness 0.15)
				)
				(justify left bottom)
				(hide yes)
			)
		)
		(property "Author" "Antmicro"
			(at 241.3 166.37 0)
			(effects
				(font
					(size 1.27 1.27)
					(thickness 0.15)
				)
				(justify left bottom)
				(hide yes)
			)
		)
		(property "Val" "100n"
			(at 218.44 185.4135 90)
			(effects
				(font
					(size 1.27 1.27)
					(thickness 0.15)
				)
				(justify right)
			)
		)
		(property "Voltage" "50V"
			(at 243.84 166.37 0)
			(effects
				(font
					(size 1.27 1.27)
				)
				(justify left bottom)
				(hide yes)
			)
		)
		(property "Dielectric" "X5R"
			(at 246.38 166.37 0)
			(effects
				(font
					(size 1.27 1.27)
				)
				(justify left bottom)
				(hide yes)
			)
		)
		(property "Public" "False"
			(at 248.92 166.37 0)
			(effects
				(font
					(size 1.27 1.27)
				)
				(justify left bottom)
				(hide yes)
			)
		)
		(pin "1"
		)
		(pin "2"
		)
		(instances
			(project "jetson-agx-thor-baseboard"
				(path ""
					(reference "C387")
					(unit 1)
				)
			)
		)
	)
	(symbol
		(lib_id "antmicropower:+1V8")
		(at 374.65 115.57 0)
		(unit 1)
		(exclude_from_sim no)
		(in_bom yes)
		(on_board yes)
		(dnp no)
		(property "Reference" "#PWR0627"
			(at 389.89 118.11 0)
			(effects
				(font
					(size 1.27 1.27)
					(thickness 0.15)
				)
				(justify left bottom)
				(hide yes)
			)
		)
		(property "Value" "+1V8"
			(at 374.65 111.76 0)
			(effects
				(font
					(size 1.27 1.27)
					(thickness 0.15)
				)
			)
		)
		(property "Footprint" ""
			(at 389.89 123.19 0)
			(effects
				(font
					(size 1.27 1.27)
					(thickness 0.15)
				)
				(justify left bottom)
				(hide yes)
			)
		)
		(property "Datasheet" ""
			(at 389.89 125.73 0)
			(effects
				(font
					(size 1.27 1.27)
					(thickness 0.15)
				)
				(justify left bottom)
				(hide yes)
			)
		)
		(property "Description" ""
			(at 374.65 115.57 0)
			(effects
				(font
					(size 1.27 1.27)
				)
				(hide yes)
			)
		)
		(property "Author" "Antmicro"
			(at 389.89 120.65 0)
			(effects
				(font
					(size 1.27 1.27)
					(thickness 0.15)
				)
				(justify left bottom)
				(hide yes)
			)
		)
		(property "License" "Apache-2.0"
			(at 389.89 123.19 0)
			(effects
				(font
					(size 1.27 1.27)
					(thickness 0.15)
				)
				(justify left bottom)
				(hide yes)
			)
		)
		(pin "1"
		)
		(instances
			(project "jetson-agx-thor-baseboard"
				(path ""
					(reference "#PWR0627")
					(unit 1)
				)
			)
		)
	)
	(symbol
		(lib_id "antmicroResistors0402:R_200k_0402")
		(at 64.77 120.65 90)
		(unit 1)
		(exclude_from_sim no)
		(in_bom yes)
		(on_board yes)
		(dnp no)
		(property "Reference" "R30"
			(at 66.04 116.84 90)
			(effects
				(font
					(size 1.27 1.27)
					(thickness 0.15)
				)
				(justify right)
			)
		)
		(property "Value" "R_200k_0402"
			(at 77.47 100.33 0)
			(effects
				(font
					(size 1.27 1.27)
					(thickness 0.15)
				)
				(justify left bottom)
				(hide yes)
			)
		)
		(property "Footprint" "antmicro-footprints:R_0402_1005Metric"
			(at 80.01 100.33 0)
			(effects
				(font
					(size 1.27 1.27)
					(thickness 0.15)
				)
				(justify left bottom)
				(hide yes)
			)
		)
		(property "Datasheet" "https://www.bourns.com/docs/product-datasheets/cr.pdf"
			(at 82.55 100.33 0)
			(effects
				(font
					(size 1.27 1.27)
					(thickness 0.15)
				)
				(justify left bottom)
				(hide yes)
			)
		)
		(property "Description" "SMD Chip Resistor, 200 kohm, ± 1%, 62.5 mW, 0402 [1005 Metric], Thick Film, General Purpose"
			(at 64.77 120.65 0)
			(effects
				(font
					(size 1.27 1.27)
				)
				(hide yes)
			)
		)
		(property "MPN" "CR0402-FX-2003GLF"
			(at 85.09 100.33 0)
			(effects
				(font
					(size 1.27 1.27)
					(thickness 0.15)
				)
				(justify left bottom)
				(hide yes)
			)
		)
		(property "Manufacturer" "Bourns"
			(at 87.63 100.33 0)
			(effects
				(font
					(size 1.27 1.27)
					(thickness 0.15)
				)
				(justify left bottom)
				(hide yes)
			)
		)
		(property "License" "Apache-2.0"
			(at 90.17 100.33 0)
			(effects
				(font
					(size 1.27 1.27)
					(thickness 0.15)
				)
				(justify left bottom)
				(hide yes)
			)
		)
		(property "Author" "Antmicro"
			(at 92.71 100.33 0)
			(effects
				(font
					(size 1.27 1.27)
					(thickness 0.15)
				)
				(justify left bottom)
				(hide yes)
			)
		)
		(property "Val" "200k"
			(at 66.04 119.38 90)
			(effects
				(font
					(size 1.27 1.27)
					(thickness 0.15)
				)
				(justify right)
			)
		)
		(property "Tolerance" "1%"
			(at 74.93 100.33 0)
			(effects
				(font
					(size 1.27 1.27)
				)
				(justify left bottom)
				(hide yes)
			)
		)
		(pin "2"
		)
		(pin "1"
		)
		(instances
			(project "jetson-agx-thor-baseboard"
				(path ""
					(reference "R30")
					(unit 1)
				)
			)
		)
	)
	(symbol
		(lib_id "antmicropower:GND")
		(at 154.94 232.41 0)
		(unit 1)
		(exclude_from_sim no)
		(in_bom yes)
		(on_board yes)
		(dnp no)
		(property "Reference" "#PWR0136"
			(at 154.94 238.76 0)
			(effects
				(font
					(size 1.27 1.27)
				)
				(justify left bottom)
				(hide yes)
			)
		)
		(property "Value" "GND"
			(at 154.94 236.22 0)
			(effects
				(font
					(size 1.27 1.27)
					(thickness 0.15)
				)
			)
		)
		(property "Footprint" ""
			(at 163.83 240.03 0)
			(effects
				(font
					(size 1.27 1.27)
					(thickness 0.15)
				)
				(justify left bottom)
				(hide yes)
			)
		)
		(property "Datasheet" ""
			(at 163.83 245.11 0)
			(effects
				(font
					(size 1.27 1.27)
					(thickness 0.15)
				)
				(justify left bottom)
				(hide yes)
			)
		)
		(property "Description" ""
			(at 154.94 232.41 0)
			(effects
				(font
					(size 1.27 1.27)
				)
				(hide yes)
			)
		)
		(property "Author" "Antmicro"
			(at 163.83 240.03 0)
			(effects
				(font
					(size 1.27 1.27)
					(thickness 0.15)
				)
				(justify left bottom)
				(hide yes)
			)
		)
		(property "License" "Apache-2.0"
			(at 163.83 242.57 0)
			(effects
				(font
					(size 1.27 1.27)
					(thickness 0.15)
				)
				(justify left bottom)
				(hide yes)
			)
		)
		(pin "1"
		)
		(instances
			(project "jetson-agx-thor-baseboard"
				(path ""
					(reference "#PWR0136")
					(unit 1)
				)
			)
		)
	)
	(symbol
		(lib_id "antmicroResistors0402:R_11k_0402")
		(at 336.55 189.23 90)
		(unit 1)
		(exclude_from_sim no)
		(in_bom yes)
		(on_board yes)
		(dnp no)
		(fields_autoplaced yes)
		(property "Reference" "R9"
			(at 339.09 185.42 90)
			(effects
				(font
					(size 1.27 1.27)
					(thickness 0.15)
				)
				(justify right)
			)
		)
		(property "Value" "R_11k_0402"
			(at 349.25 168.91 0)
			(effects
				(font
					(size 1.27 1.27)
					(thickness 0.15)
				)
				(justify left bottom)
				(hide yes)
			)
		)
		(property "Footprint" "antmicro-footprints:R_0402_1005Metric"
			(at 351.79 168.91 0)
			(effects
				(font
					(size 1.27 1.27)
					(thickness 0.15)
				)
				(justify left bottom)
				(hide yes)
			)
		)
		(property "Datasheet" "https://www.bourns.com/docs/product-datasheets/cr.pdf"
			(at 354.33 168.91 0)
			(effects
				(font
					(size 1.27 1.27)
					(thickness 0.15)
				)
				(justify left bottom)
				(hide yes)
			)
		)
		(property "Description" "SMD Chip Resistor, 11 kohm, ± 1%, 62.5 mW, 0402 [1005 Metric], Thick Film, General Purpose"
			(at 336.55 189.23 0)
			(effects
				(font
					(size 1.27 1.27)
				)
				(hide yes)
			)
		)
		(property "MPN" "CR0402-FX-1102GLF"
			(at 356.87 168.91 0)
			(effects
				(font
					(size 1.27 1.27)
					(thickness 0.15)
				)
				(justify left bottom)
				(hide yes)
			)
		)
		(property "Manufacturer" "Bourns"
			(at 359.41 168.91 0)
			(effects
				(font
					(size 1.27 1.27)
					(thickness 0.15)
				)
				(justify left bottom)
				(hide yes)
			)
		)
		(property "License" "Apache-2.0"
			(at 361.95 168.91 0)
			(effects
				(font
					(size 1.27 1.27)
					(thickness 0.15)
				)
				(justify left bottom)
				(hide yes)
			)
		)
		(property "Author" "Antmicro"
			(at 364.49 168.91 0)
			(effects
				(font
					(size 1.27 1.27)
					(thickness 0.15)
				)
				(justify left bottom)
				(hide yes)
			)
		)
		(property "Val" "11k"
			(at 339.09 187.96 90)
			(effects
				(font
					(size 1.27 1.27)
					(thickness 0.15)
				)
				(justify right)
			)
		)
		(property "Tolerance" "1%"
			(at 346.71 168.91 0)
			(effects
				(font
					(size 1.27 1.27)
				)
				(justify left bottom)
				(hide yes)
			)
		)
		(pin "1"
		)
		(pin "2"
		)
		(instances
			(project "jetson-agx-thor-baseboard"
				(path ""
					(reference "R9")
					(unit 1)
				)
			)
		)
	)
	(symbol
		(lib_id "antmicroResistors0402:R_200k_0402")
		(at 64.77 231.14 90)
		(unit 1)
		(exclude_from_sim no)
		(in_bom yes)
		(on_board yes)
		(dnp no)
		(property "Reference" "R42"
			(at 66.04 227.33 90)
			(effects
				(font
					(size 1.27 1.27)
					(thickness 0.15)
				)
				(justify right)
			)
		)
		(property "Value" "R_200k_0402"
			(at 77.47 210.82 0)
			(effects
				(font
					(size 1.27 1.27)
					(thickness 0.15)
				)
				(justify left bottom)
				(hide yes)
			)
		)
		(property "Footprint" "antmicro-footprints:R_0402_1005Metric"
			(at 80.01 210.82 0)
			(effects
				(font
					(size 1.27 1.27)
					(thickness 0.15)
				)
				(justify left bottom)
				(hide yes)
			)
		)
		(property "Datasheet" "https://www.bourns.com/docs/product-datasheets/cr.pdf"
			(at 82.55 210.82 0)
			(effects
				(font
					(size 1.27 1.27)
					(thickness 0.15)
				)
				(justify left bottom)
				(hide yes)
			)
		)
		(property "Description" "SMD Chip Resistor, 200 kohm, ± 1%, 62.5 mW, 0402 [1005 Metric], Thick Film, General Purpose"
			(at 64.77 231.14 0)
			(effects
				(font
					(size 1.27 1.27)
				)
				(hide yes)
			)
		)
		(property "MPN" "CR0402-FX-2003GLF"
			(at 85.09 210.82 0)
			(effects
				(font
					(size 1.27 1.27)
					(thickness 0.15)
				)
				(justify left bottom)
				(hide yes)
			)
		)
		(property "Manufacturer" "Bourns"
			(at 87.63 210.82 0)
			(effects
				(font
					(size 1.27 1.27)
					(thickness 0.15)
				)
				(justify left bottom)
				(hide yes)
			)
		)
		(property "License" "Apache-2.0"
			(at 90.17 210.82 0)
			(effects
				(font
					(size 1.27 1.27)
					(thickness 0.15)
				)
				(justify left bottom)
				(hide yes)
			)
		)
		(property "Author" "Antmicro"
			(at 92.71 210.82 0)
			(effects
				(font
					(size 1.27 1.27)
					(thickness 0.15)
				)
				(justify left bottom)
				(hide yes)
			)
		)
		(property "Val" "200k"
			(at 66.04 229.87 90)
			(effects
				(font
					(size 1.27 1.27)
					(thickness 0.15)
				)
				(justify right)
			)
		)
		(property "Tolerance" "1%"
			(at 74.93 210.82 0)
			(effects
				(font
					(size 1.27 1.27)
				)
				(justify left bottom)
				(hide yes)
			)
		)
		(pin "2"
		)
		(pin "1"
		)
		(instances
			(project "jetson-agx-thor-baseboard"
				(path ""
					(reference "R42")
					(unit 1)
				)
			)
		)
	)
	(symbol
		(lib_id "antmicroFixedInductors:L_1u8_6.8A_WE-MAPI-4020")
		(at 326.39 116.84 0)
		(unit 1)
		(exclude_from_sim no)
		(in_bom yes)
		(on_board yes)
		(dnp no)
		(fields_autoplaced yes)
		(property "Reference" "L7"
			(at 328.93 111.76 0)
			(effects
				(font
					(size 1.27 1.27)
					(thickness 0.15)
				)
			)
		)
		(property "Value" "L_1u8_6.8A_WE-MAPI-4020"
			(at 340.36 119.38 0)
			(effects
				(font
					(size 1.27 1.27)
					(thickness 0.15)
				)
				(justify left bottom)
				(hide yes)
			)
		)
		(property "Footprint" "antmicro-footprints:L_WE-MAPI-4020"
			(at 340.36 124.46 0)
			(effects
				(font
					(size 1.27 1.27)
					(thickness 0.15)
				)
				(justify left bottom)
				(hide yes)
			)
		)
		(property "Datasheet" "https://www.we-online.com/components/products/datasheet/74438356018.pdf"
			(at 340.36 127 0)
			(effects
				(font
					(size 1.27 1.27)
					(thickness 0.15)
				)
				(justify left bottom)
				(hide yes)
			)
		)
		(property "Description" "Power Inductors - SMD WE-MAPI 1.8uH 4.6A DCR=30mOhms AEC-Q200"
			(at 326.39 116.84 0)
			(effects
				(font
					(size 1.27 1.27)
				)
				(hide yes)
			)
		)
		(property "Val" "1u8/6.8A"
			(at 328.93 114.3 0)
			(effects
				(font
					(size 1.27 1.27)
					(thickness 0.15)
				)
			)
		)
		(property "Manufacturer" "Würth Elektronik"
			(at 340.36 129.54 0)
			(effects
				(font
					(size 1.27 1.27)
					(thickness 0.15)
				)
				(justify left bottom)
				(hide yes)
			)
		)
		(property "MPN" "74438356018"
			(at 340.36 132.08 0)
			(effects
				(font
					(size 1.27 1.27)
					(thickness 0.15)
				)
				(justify left bottom)
				(hide yes)
			)
		)
		(property "ISat" "6.5 A"
			(at 340.36 133.35 0)
			(effects
				(font
					(size 1.27 1.27)
				)
				(justify left)
				(hide yes)
			)
		)
		(property "IMax" "6.8 A"
			(at 340.36 137.16 0)
			(effects
				(font
					(size 1.27 1.27)
					(thickness 0.15)
				)
				(justify left bottom)
				(hide yes)
			)
		)
		(property "Size" "4.1x4.1mm"
			(at 340.36 139.7 0)
			(effects
				(font
					(size 1.27 1.27)
					(thickness 0.15)
				)
				(justify left bottom)
				(hide yes)
			)
		)
		(property "Author" "Antmicro"
			(at 340.36 142.24 0)
			(effects
				(font
					(size 1.27 1.27)
					(thickness 0.15)
				)
				(justify left bottom)
				(hide yes)
			)
		)
		(property "License" "Apache-2.0"
			(at 340.36 144.78 0)
			(effects
				(font
					(size 1.27 1.27)
					(thickness 0.15)
				)
				(justify left bottom)
				(hide yes)
			)
		)
		(pin "2"
		)
		(pin "1"
		)
		(instances
			(project "jetson-agx-thor-baseboard"
				(path ""
					(reference "L7")
					(unit 1)
				)
			)
		)
	)
	(symbol
		(lib_id "antmicropower:GND")
		(at 336.55 196.85 0)
		(unit 1)
		(exclude_from_sim no)
		(in_bom yes)
		(on_board yes)
		(dnp no)
		(property "Reference" "#PWR054"
			(at 345.44 199.39 0)
			(effects
				(font
					(size 1.27 1.27)
					(thickness 0.15)
				)
				(justify left bottom)
				(hide yes)
			)
		)
		(property "Value" "GND"
			(at 336.55 200.66 0)
			(effects
				(font
					(size 1.27 1.27)
					(thickness 0.15)
				)
			)
		)
		(property "Footprint" ""
			(at 345.44 204.47 0)
			(effects
				(font
					(size 1.27 1.27)
					(thickness 0.15)
				)
				(justify left bottom)
				(hide yes)
			)
		)
		(property "Datasheet" ""
			(at 345.44 209.55 0)
			(effects
				(font
					(size 1.27 1.27)
					(thickness 0.15)
				)
				(justify left bottom)
				(hide yes)
			)
		)
		(property "Description" ""
			(at 336.55 196.85 0)
			(effects
				(font
					(size 1.27 1.27)
				)
				(hide yes)
			)
		)
		(property "Author" "Antmicro"
			(at 345.44 204.47 0)
			(effects
				(font
					(size 1.27 1.27)
					(thickness 0.15)
				)
				(justify left bottom)
				(hide yes)
			)
		)
		(property "License" "Apache-2.0"
			(at 345.44 207.01 0)
			(effects
				(font
					(size 1.27 1.27)
					(thickness 0.15)
				)
				(justify left bottom)
				(hide yes)
			)
		)
		(pin "1"
		)
		(instances
			(project "jetson-agx-thor-baseboard"
				(path ""
					(reference "#PWR054")
					(unit 1)
				)
			)
		)
	)
	(symbol
		(lib_id "antmicropower:GND")
		(at 170.18 44.45 0)
		(unit 1)
		(exclude_from_sim no)
		(in_bom yes)
		(on_board yes)
		(dnp no)
		(property "Reference" "#PWR0536"
			(at 170.18 50.8 0)
			(effects
				(font
					(size 1.27 1.27)
				)
				(justify left bottom)
				(hide yes)
			)
		)
		(property "Value" "GND"
			(at 170.18 48.26 0)
			(effects
				(font
					(size 1.27 1.27)
					(thickness 0.15)
				)
			)
		)
		(property "Footprint" ""
			(at 179.07 52.07 0)
			(effects
				(font
					(size 1.27 1.27)
					(thickness 0.15)
				)
				(justify left bottom)
				(hide yes)
			)
		)
		(property "Datasheet" ""
			(at 179.07 57.15 0)
			(effects
				(font
					(size 1.27 1.27)
					(thickness 0.15)
				)
				(justify left bottom)
				(hide yes)
			)
		)
		(property "Description" ""
			(at 170.18 44.45 0)
			(effects
				(font
					(size 1.27 1.27)
				)
				(hide yes)
			)
		)
		(property "Author" "Antmicro"
			(at 179.07 52.07 0)
			(effects
				(font
					(size 1.27 1.27)
					(thickness 0.15)
				)
				(justify left bottom)
				(hide yes)
			)
		)
		(property "License" "Apache-2.0"
			(at 179.07 54.61 0)
			(effects
				(font
					(size 1.27 1.27)
					(thickness 0.15)
				)
				(justify left bottom)
				(hide yes)
			)
		)
		(pin "1"
		)
		(instances
			(project "jetson-agx-thor-baseboard"
				(path ""
					(reference "#PWR0536")
					(unit 1)
				)
			)
		)
	)
	(symbol
		(lib_id "antmicroCapacitorsmisc:C_22u_25V_0805")
		(at 177.8 109.22 90)
		(unit 1)
		(exclude_from_sim no)
		(in_bom yes)
		(on_board yes)
		(dnp no)
		(property "Reference" "C295"
			(at 179.578 104.1401 90)
			(effects
				(font
					(size 1.27 1.27)
					(thickness 0.15)
				)
				(justify right)
			)
		)
		(property "Value" "C_22u_25V_0805"
			(at 187.96 88.9 0)
			(effects
				(font
					(size 1.27 1.27)
					(thickness 0.15)
				)
				(justify left bottom)
				(hide yes)
			)
		)
		(property "Footprint" "antmicro-footprints:C_0805_2012Metric"
			(at 190.5 88.9 0)
			(effects
				(font
					(size 1.27 1.27)
					(thickness 0.15)
				)
				(justify left bottom)
				(hide yes)
			)
		)
		(property "Datasheet" "https://product.samsungsem.com/mlcc/CL21A226MAYNNN.do"
			(at 193.04 88.9 0)
			(effects
				(font
					(size 1.27 1.27)
					(thickness 0.15)
				)
				(justify left bottom)
				(hide yes)
			)
		)
		(property "Description" "SMT Multilayer Ceramic Capacitor, 22uF, +/-20%, 25V, X5R, 0805 [2012 Metric]"
			(at 210.82 88.9 0)
			(effects
				(font
					(size 1.27 1.27)
				)
				(justify left bottom)
				(hide yes)
			)
		)
		(property "MPN" "CL21A226MAYNNNE"
			(at 195.58 88.9 0)
			(effects
				(font
					(size 1.27 1.27)
					(thickness 0.15)
				)
				(justify left bottom)
				(hide yes)
			)
		)
		(property "Manufacturer" "Samsung Electro-Mechanics"
			(at 198.12 88.9 0)
			(effects
				(font
					(size 1.27 1.27)
					(thickness 0.15)
				)
				(justify left bottom)
				(hide yes)
			)
		)
		(property "License" "Apache-2.0"
			(at 200.66 88.9 0)
			(effects
				(font
					(size 1.27 1.27)
					(thickness 0.15)
				)
				(justify left bottom)
				(hide yes)
			)
		)
		(property "Author" "Antmicro"
			(at 203.2 88.9 0)
			(effects
				(font
					(size 1.27 1.27)
					(thickness 0.15)
				)
				(justify left bottom)
				(hide yes)
			)
		)
		(property "Val" "22u"
			(at 179.578 106.6801 90)
			(effects
				(font
					(size 1.27 1.27)
					(thickness 0.15)
				)
				(justify right)
			)
		)
		(property "Voltage" "25V"
			(at 179.578 109.22 90)
			(effects
				(font
					(size 1.27 1.27)
				)
				(justify right)
			)
		)
		(property "Dielectric" "X5R"
			(at 208.28 88.9 0)
			(effects
				(font
					(size 1.27 1.27)
				)
				(justify left bottom)
				(hide yes)
			)
		)
		(property "Public" "False"
			(at 210.82 88.9 0)
			(effects
				(font
					(size 1.27 1.27)
				)
				(justify left bottom)
				(hide yes)
			)
		)
		(pin "2"
		)
		(pin "1"
		)
		(instances
			(project "jetson-agx-thor-baseboard"
				(path ""
					(reference "C295")
					(unit 1)
				)
			)
		)
	)
	(symbol
		(lib_id "antmicroCapacitors0603:C_22u_16V_0603")
		(at 365.76 193.04 90)
		(unit 1)
		(exclude_from_sim no)
		(in_bom yes)
		(on_board yes)
		(dnp no)
		(fields_autoplaced yes)
		(property "Reference" "C310"
			(at 368.3 189.2235 90)
			(effects
				(font
					(size 1.27 1.27)
					(thickness 0.15)
				)
				(justify right)
			)
		)
		(property "Value" "C_22u_16V_0603"
			(at 375.92 172.72 0)
			(effects
				(font
					(size 1.27 1.27)
					(thickness 0.15)
				)
				(justify left bottom)
				(hide yes)
			)
		)
		(property "Footprint" "antmicro-footprints:C_0603_1608Metric_EIA"
			(at 378.46 172.72 0)
			(effects
				(font
					(size 1.27 1.27)
					(thickness 0.15)
				)
				(justify left bottom)
				(hide yes)
			)
		)
		(property "Datasheet" "https://product.samsungsem.com/mlcc/CL10A226MO7JZN.do"
			(at 381 172.72 0)
			(effects
				(font
					(size 1.27 1.27)
					(thickness 0.15)
				)
				(justify left bottom)
				(hide yes)
			)
		)
		(property "Description" "SMD Multilayer Ceramic Capacitor"
			(at 365.76 193.04 0)
			(effects
				(font
					(size 1.27 1.27)
				)
				(hide yes)
			)
		)
		(property "MPN" "CL10A226MO7JZNC"
			(at 383.54 172.72 0)
			(effects
				(font
					(size 1.27 1.27)
					(thickness 0.15)
				)
				(justify left bottom)
				(hide yes)
			)
		)
		(property "Manufacturer" "Samsung Electro-Mechanics"
			(at 386.08 172.72 0)
			(effects
				(font
					(size 1.27 1.27)
					(thickness 0.15)
				)
				(justify left bottom)
				(hide yes)
			)
		)
		(property "License" "Apache-2.0"
			(at 388.62 172.72 0)
			(effects
				(font
					(size 1.27 1.27)
					(thickness 0.15)
				)
				(justify left bottom)
				(hide yes)
			)
		)
		(property "Author" "Antmicro"
			(at 391.16 172.72 0)
			(effects
				(font
					(size 1.27 1.27)
					(thickness 0.15)
				)
				(justify left bottom)
				(hide yes)
			)
		)
		(property "Val" "22u"
			(at 368.3 191.7635 90)
			(effects
				(font
					(size 1.27 1.27)
					(thickness 0.15)
				)
				(justify right)
			)
		)
		(property "Voltage" "16V"
			(at 393.7 172.72 0)
			(effects
				(font
					(size 1.27 1.27)
				)
				(justify left bottom)
				(hide yes)
			)
		)
		(property "Dielectric" ""
			(at 396.24 172.72 0)
			(effects
				(font
					(size 1.27 1.27)
				)
				(justify left bottom)
				(hide yes)
			)
		)
		(pin "1"
		)
		(pin "2"
		)
		(instances
			(project "jetson-agx-thor-baseboard"
				(path ""
					(reference "C310")
					(unit 1)
				)
			)
		)
	)
	(symbol
		(lib_id "antmicropower:GND")
		(at 27.94 41.91 0)
		(unit 1)
		(exclude_from_sim no)
		(in_bom yes)
		(on_board yes)
		(dnp no)
		(property "Reference" "#PWR0583"
			(at 27.94 48.26 0)
			(effects
				(font
					(size 1.27 1.27)
				)
				(justify left bottom)
				(hide yes)
			)
		)
		(property "Value" "GND"
			(at 27.94 45.72 0)
			(effects
				(font
					(size 1.27 1.27)
					(thickness 0.15)
				)
			)
		)
		(property "Footprint" ""
			(at 36.83 49.53 0)
			(effects
				(font
					(size 1.27 1.27)
					(thickness 0.15)
				)
				(justify left bottom)
				(hide yes)
			)
		)
		(property "Datasheet" ""
			(at 36.83 54.61 0)
			(effects
				(font
					(size 1.27 1.27)
					(thickness 0.15)
				)
				(justify left bottom)
				(hide yes)
			)
		)
		(property "Description" ""
			(at 27.94 41.91 0)
			(effects
				(font
					(size 1.27 1.27)
				)
				(hide yes)
			)
		)
		(property "Author" "Antmicro"
			(at 36.83 49.53 0)
			(effects
				(font
					(size 1.27 1.27)
					(thickness 0.15)
				)
				(justify left bottom)
				(hide yes)
			)
		)
		(property "License" "Apache-2.0"
			(at 36.83 52.07 0)
			(effects
				(font
					(size 1.27 1.27)
					(thickness 0.15)
				)
				(justify left bottom)
				(hide yes)
			)
		)
		(pin "1"
		)
		(instances
			(project "jetson-agx-thor-baseboard"
				(path ""
					(reference "#PWR0583")
					(unit 1)
				)
			)
		)
	)
	(symbol
		(lib_id "antmicroResistors0402:R_27R_0402")
		(at 220.98 107.95 90)
		(unit 1)
		(exclude_from_sim no)
		(in_bom yes)
		(on_board yes)
		(dnp no)
		(fields_autoplaced yes)
		(property "Reference" "R371"
			(at 223.52 104.1399 90)
			(effects
				(font
					(size 1.27 1.27)
				)
				(justify right)
			)
		)
		(property "Value" "R_27R_0402"
			(at 233.68 87.63 0)
			(effects
				(font
					(size 1.27 1.27)
					(thickness 0.15)
				)
				(justify left bottom)
				(hide yes)
			)
		)
		(property "Footprint" "antmicro-footprints:R_0402_1005Metric"
			(at 236.22 87.63 0)
			(effects
				(font
					(size 1.27 1.27)
					(thickness 0.15)
				)
				(justify left bottom)
				(hide yes)
			)
		)
		(property "Datasheet" "https://www.bourns.com/docs/product-datasheets/cr.pdf"
			(at 238.76 87.63 0)
			(effects
				(font
					(size 1.27 1.27)
					(thickness 0.15)
				)
				(justify left bottom)
				(hide yes)
			)
		)
		(property "Description" "SMD Chip Resistor, 27 ohm, ± 1%, 63 mW, 0402 [1005 Metric], Thick Film, General Purpose"
			(at 220.98 107.95 0)
			(effects
				(font
					(size 1.27 1.27)
				)
				(hide yes)
			)
		)
		(property "Manufacturer" "Bourns"
			(at 243.84 87.63 0)
			(effects
				(font
					(size 1.27 1.27)
					(thickness 0.15)
				)
				(justify left bottom)
				(hide yes)
			)
		)
		(property "MPN" "CR0402-FX-27R0GLF"
			(at 241.3 87.63 0)
			(effects
				(font
					(size 1.27 1.27)
					(thickness 0.15)
				)
				(justify left bottom)
				(hide yes)
			)
		)
		(property "Val" "27R"
			(at 223.52 106.68 90)
			(effects
				(font
					(size 1.27 1.27)
					(thickness 0.15)
				)
				(justify right)
			)
		)
		(property "License" "Apache-2.0"
			(at 246.38 87.63 0)
			(effects
				(font
					(size 1.27 1.27)
					(thickness 0.15)
				)
				(justify left bottom)
				(hide yes)
			)
		)
		(property "Author" "Antmicro"
			(at 248.92 87.63 0)
			(effects
				(font
					(size 1.27 1.27)
					(thickness 0.15)
				)
				(justify left bottom)
				(hide yes)
			)
		)
		(property "Tolerance" "1%"
			(at 231.14 87.63 0)
			(effects
				(font
					(size 1.27 1.27)
				)
				(justify left bottom)
				(hide yes)
			)
		)
		(pin "1"
		)
		(pin "2"
		)
		(instances
			(project "jetson-agx-thor-baseboard"
				(path ""
					(reference "R371")
					(unit 1)
				)
			)
		)
	)
	(symbol
		(lib_id "antmicroCapacitorsmisc:C_22u_25V_0805")
		(at 255.27 57.15 90)
		(unit 1)
		(exclude_from_sim no)
		(in_bom yes)
		(on_board yes)
		(dnp no)
		(property "Reference" "C308"
			(at 257.302 52.07 90)
			(effects
				(font
					(size 1.27 1.27)
				)
				(justify right)
			)
		)
		(property "Value" "C_22u_25V_0805"
			(at 265.43 36.83 0)
			(effects
				(font
					(size 1.27 1.27)
					(thickness 0.15)
				)
				(justify left bottom)
				(hide yes)
			)
		)
		(property "Footprint" "antmicro-footprints:C_0805_2012Metric"
			(at 267.97 36.83 0)
			(effects
				(font
					(size 1.27 1.27)
					(thickness 0.15)
				)
				(justify left bottom)
				(hide yes)
			)
		)
		(property "Datasheet" "https://product.samsungsem.com/mlcc/CL21A226MAYNNN.do"
			(at 270.51 36.83 0)
			(effects
				(font
					(size 1.27 1.27)
					(thickness 0.15)
				)
				(justify left bottom)
				(hide yes)
			)
		)
		(property "Description" "SMT Multilayer Ceramic Capacitor, 22uF, +/-20%, 25V, X5R, 0805 [2012 Metric]"
			(at 255.27 57.15 0)
			(effects
				(font
					(size 1.27 1.27)
				)
				(hide yes)
			)
		)
		(property "Manufacturer" "Samsung Electro-Mechanics"
			(at 275.59 36.83 0)
			(effects
				(font
					(size 1.27 1.27)
					(thickness 0.15)
				)
				(justify left bottom)
				(hide yes)
			)
		)
		(property "MPN" "CL21A226MAYNNNE"
			(at 273.05 36.83 0)
			(effects
				(font
					(size 1.27 1.27)
					(thickness 0.15)
				)
				(justify left bottom)
				(hide yes)
			)
		)
		(property "Val" "22u"
			(at 257.302 54.6101 90)
			(effects
				(font
					(size 1.27 1.27)
					(thickness 0.15)
				)
				(justify right)
			)
		)
		(property "License" "Apache-2.0"
			(at 278.13 36.83 0)
			(effects
				(font
					(size 1.27 1.27)
					(thickness 0.15)
				)
				(justify left bottom)
				(hide yes)
			)
		)
		(property "Author" "Antmicro"
			(at 280.67 36.83 0)
			(effects
				(font
					(size 1.27 1.27)
					(thickness 0.15)
				)
				(justify left bottom)
				(hide yes)
			)
		)
		(property "Voltage" "25V"
			(at 257.302 57.15 90)
			(effects
				(font
					(size 1.27 1.27)
				)
				(justify right)
			)
		)
		(property "Dielectric" "X5R"
			(at 285.75 36.83 0)
			(effects
				(font
					(size 1.27 1.27)
				)
				(justify left bottom)
				(hide yes)
			)
		)
		(property "Public" "False"
			(at 288.29 36.83 0)
			(effects
				(font
					(size 1.27 1.27)
				)
				(justify left bottom)
				(hide yes)
			)
		)
		(pin "1"
		)
		(pin "2"
		)
		(instances
			(project "jetson-agx-thor-baseboard"
				(path ""
					(reference "C308")
					(unit 1)
				)
			)
		)
	)
	(symbol
		(lib_id "antmicroTVSDiodes:ESDA25P35-1U1M")
		(at 397.51 46.99 90)
		(mirror x)
		(unit 1)
		(exclude_from_sim no)
		(in_bom yes)
		(on_board yes)
		(dnp no)
		(property "Reference" "D13"
			(at 396.24 48.26 90)
			(effects
				(font
					(size 1.27 1.27)
				)
				(justify left)
			)
		)
		(property "Value" "ESDA25P35-1U1M"
			(at 412.75 68.58 0)
			(effects
				(font
					(size 1.27 1.27)
					(thickness 0.15)
				)
				(justify left bottom)
				(hide yes)
			)
		)
		(property "Footprint" "antmicro-footprints:QFN-2L_1.6x1x0.55mm"
			(at 407.67 71.12 0)
			(effects
				(font
					(size 1.27 1.27)
					(thickness 0.15)
				)
				(justify left bottom)
				(hide yes)
			)
		)
		(property "Datasheet" "https://www.st.com/resource/en/datasheet/esda25p35-1u1m.pdf"
			(at 410.21 71.12 0)
			(effects
				(font
					(size 1.27 1.27)
					(thickness 0.15)
				)
				(justify left bottom)
				(hide yes)
			)
		)
		(property "Description" "Unidirectional TVS, 30 kV, QFN-2L, 22 V, 195 pF"
			(at 422.91 71.12 0)
			(effects
				(font
					(size 1.27 1.27)
				)
				(justify left bottom)
				(hide yes)
			)
		)
		(property "Manufacturer" "STMicroelectronics"
			(at 415.29 71.12 0)
			(effects
				(font
					(size 1.27 1.27)
					(thickness 0.15)
				)
				(justify left bottom)
				(hide yes)
			)
		)
		(property "MPN" "ESDA25P35-1U1M"
			(at 401.32 46.99 0)
			(effects
				(font
					(size 1.27 1.27)
					(thickness 0.15)
				)
				(justify left bottom)
			)
		)
		(property "Author" "Antmicro"
			(at 417.83 71.12 0)
			(effects
				(font
					(size 1.27 1.27)
					(thickness 0.15)
				)
				(justify left bottom)
				(hide yes)
			)
		)
		(property "License" "Apache-2.0"
			(at 420.37 71.12 0)
			(effects
				(font
					(size 1.27 1.27)
					(thickness 0.15)
				)
				(justify left bottom)
				(hide yes)
			)
		)
		(pin "1"
		)
		(pin "2"
		)
		(instances
			(project "jetson-agx-thor-baseboard"
				(path ""
					(reference "D13")
					(unit 1)
				)
			)
		)
	)
	(symbol
		(lib_id "antmicropower:PWR_FLAG")
		(at 237.49 35.56 270)
		(unit 1)
		(exclude_from_sim no)
		(in_bom yes)
		(on_board yes)
		(dnp no)
		(property "Reference" "#FLG03"
			(at 239.395 35.56 0)
			(effects
				(font
					(size 1.27 1.27)
				)
				(hide yes)
			)
		)
		(property "Value" "PWR_FLAG"
			(at 239.522 33.02 90)
			(effects
				(font
					(size 1.27 1.27)
				)
			)
		)
		(property "Footprint" ""
			(at 237.49 35.56 0)
			(effects
				(font
					(size 1.27 1.27)
				)
				(hide yes)
			)
		)
		(property "Datasheet" ""
			(at 237.49 35.56 0)
			(effects
				(font
					(size 1.27 1.27)
				)
				(hide yes)
			)
		)
		(property "Description" ""
			(at 237.49 35.56 0)
			(effects
				(font
					(size 1.27 1.27)
				)
				(hide yes)
			)
		)
		(pin "1"
		)
		(instances
			(project "jetson-agx-thor-baseboard"
				(path ""
					(reference "#FLG03")
					(unit 1)
				)
			)
		)
	)
	(symbol
		(lib_id "antmicropower:GND")
		(at 303.53 58.42 0)
		(unit 1)
		(exclude_from_sim no)
		(in_bom yes)
		(on_board yes)
		(dnp no)
		(property "Reference" "#PWR066"
			(at 303.53 64.77 0)
			(effects
				(font
					(size 1.27 1.27)
				)
				(justify left bottom)
				(hide yes)
			)
		)
		(property "Value" "GND"
			(at 303.53 62.23 0)
			(effects
				(font
					(size 1.27 1.27)
					(thickness 0.15)
				)
			)
		)
		(property "Footprint" ""
			(at 312.42 66.04 0)
			(effects
				(font
					(size 1.27 1.27)
					(thickness 0.15)
				)
				(justify left bottom)
				(hide yes)
			)
		)
		(property "Datasheet" ""
			(at 312.42 71.12 0)
			(effects
				(font
					(size 1.27 1.27)
					(thickness 0.15)
				)
				(justify left bottom)
				(hide yes)
			)
		)
		(property "Description" ""
			(at 303.53 58.42 0)
			(effects
				(font
					(size 1.27 1.27)
				)
				(hide yes)
			)
		)
		(property "Author" "Antmicro"
			(at 312.42 66.04 0)
			(effects
				(font
					(size 1.27 1.27)
					(thickness 0.15)
				)
				(justify left bottom)
				(hide yes)
			)
		)
		(property "License" "Apache-2.0"
			(at 312.42 68.58 0)
			(effects
				(font
					(size 1.27 1.27)
					(thickness 0.15)
				)
				(justify left bottom)
				(hide yes)
			)
		)
		(pin "1"
		)
		(instances
			(project "jetson-agx-thor-baseboard"
				(path ""
					(reference "#PWR066")
					(unit 1)
				)
			)
		)
	)
	(symbol
		(lib_id "antmicropower:GND")
		(at 200.66 132.08 0)
		(unit 1)
		(exclude_from_sim no)
		(in_bom yes)
		(on_board yes)
		(dnp no)
		(property "Reference" "#PWR0566"
			(at 209.55 134.62 0)
			(effects
				(font
					(size 1.27 1.27)
					(thickness 0.15)
				)
				(justify left bottom)
				(hide yes)
			)
		)
		(property "Value" "GND"
			(at 200.66 135.89 0)
			(effects
				(font
					(size 1.27 1.27)
					(thickness 0.15)
				)
			)
		)
		(property "Footprint" ""
			(at 209.55 139.7 0)
			(effects
				(font
					(size 1.27 1.27)
					(thickness 0.15)
				)
				(justify left bottom)
				(hide yes)
			)
		)
		(property "Datasheet" ""
			(at 209.55 144.78 0)
			(effects
				(font
					(size 1.27 1.27)
					(thickness 0.15)
				)
				(justify left bottom)
				(hide yes)
			)
		)
		(property "Description" ""
			(at 200.66 132.08 0)
			(effects
				(font
					(size 1.27 1.27)
				)
				(hide yes)
			)
		)
		(property "Author" "Antmicro"
			(at 209.55 139.7 0)
			(effects
				(font
					(size 1.27 1.27)
					(thickness 0.15)
				)
				(justify left bottom)
				(hide yes)
			)
		)
		(property "License" "Apache-2.0"
			(at 209.55 142.24 0)
			(effects
				(font
					(size 1.27 1.27)
					(thickness 0.15)
				)
				(justify left bottom)
				(hide yes)
			)
		)
		(pin "1"
		)
		(instances
			(project "jetson-agx-thor-baseboard"
				(path ""
					(reference "#PWR0566")
					(unit 1)
				)
			)
		)
	)
	(symbol
		(lib_id "antmicroResistors0402:R_499k_0402")
		(at 55.88 39.37 90)
		(unit 1)
		(exclude_from_sim no)
		(in_bom no)
		(on_board yes)
		(dnp yes)
		(property "Reference" "R26"
			(at 57.15 35.56 90)
			(effects
				(font
					(size 1.27 1.27)
					(thickness 0.15)
				)
				(justify right)
			)
		)
		(property "Value" "R_499k_0402"
			(at 68.58 19.05 0)
			(effects
				(font
					(size 1.27 1.27)
					(thickness 0.15)
				)
				(justify left bottom)
				(hide yes)
			)
		)
		(property "Footprint" "antmicro-footprints:R_0402_1005Metric"
			(at 71.12 19.05 0)
			(effects
				(font
					(size 1.27 1.27)
					(thickness 0.15)
				)
				(justify left bottom)
				(hide yes)
			)
		)
		(property "Datasheet" "https://www.mouser.com/datasheet/2/54/cr-1858361.pdf"
			(at 73.66 19.05 0)
			(effects
				(font
					(size 1.27 1.27)
					(thickness 0.15)
				)
				(justify left bottom)
				(hide yes)
			)
		)
		(property "Description" "SMD Chip Resistor, 499 kohm, ± 1%, 63 mW, 0402 [1005 Metric], Thick Film, General Purpose"
			(at 55.88 39.37 0)
			(effects
				(font
					(size 1.27 1.27)
				)
				(hide yes)
			)
		)
		(property "MPN" "CR0402-FX-4993GLF"
			(at 76.2 19.05 0)
			(effects
				(font
					(size 1.27 1.27)
					(thickness 0.15)
				)
				(justify left bottom)
				(hide yes)
			)
		)
		(property "Manufacturer" "Bourns"
			(at 78.74 19.05 0)
			(effects
				(font
					(size 1.27 1.27)
					(thickness 0.15)
				)
				(justify left bottom)
				(hide yes)
			)
		)
		(property "License" "Apache-2.0"
			(at 81.28 19.05 0)
			(effects
				(font
					(size 1.27 1.27)
					(thickness 0.15)
				)
				(justify left bottom)
				(hide yes)
			)
		)
		(property "Author" "Antmicro"
			(at 83.82 19.05 0)
			(effects
				(font
					(size 1.27 1.27)
					(thickness 0.15)
				)
				(justify left bottom)
				(hide yes)
			)
		)
		(property "Val" "499k"
			(at 57.15 38.1 90)
			(effects
				(font
					(size 1.27 1.27)
					(thickness 0.15)
				)
				(justify right)
			)
		)
		(property "Tolerance" "1%"
			(at 66.04 19.05 0)
			(effects
				(font
					(size 1.27 1.27)
				)
				(justify left bottom)
				(hide yes)
			)
		)
		(pin "2"
		)
		(pin "1"
		)
		(instances
			(project "jetson-agx-thor-baseboard"
				(path ""
					(reference "R26")
					(unit 1)
				)
			)
		)
	)
	(symbol
		(lib_id "antmicroResistors0402:R_30k_0402")
		(at 336.55 123.19 90)
		(unit 1)
		(exclude_from_sim no)
		(in_bom yes)
		(on_board yes)
		(dnp no)
		(fields_autoplaced yes)
		(property "Reference" "R317"
			(at 339.09 119.38 90)
			(effects
				(font
					(size 1.27 1.27)
					(thickness 0.15)
				)
				(justify right)
			)
		)
		(property "Value" "R_30k_0402"
			(at 349.25 102.87 0)
			(effects
				(font
					(size 1.27 1.27)
					(thickness 0.15)
				)
				(justify left bottom)
				(hide yes)
			)
		)
		(property "Footprint" "antmicro-footprints:R_0402_1005Metric"
			(at 351.79 102.87 0)
			(effects
				(font
					(size 1.27 1.27)
					(thickness 0.15)
				)
				(justify left bottom)
				(hide yes)
			)
		)
		(property "Datasheet" "https://www.bourns.com/docs/product-datasheets/cr.pdf"
			(at 354.33 102.87 0)
			(effects
				(font
					(size 1.27 1.27)
					(thickness 0.15)
				)
				(justify left bottom)
				(hide yes)
			)
		)
		(property "Description" "SMD Chip Resistor, 30 kohm, ± 1%, 63 mW, 0402 [1005 Metric], Thick Film, General Purpose"
			(at 336.55 123.19 0)
			(effects
				(font
					(size 1.27 1.27)
				)
				(hide yes)
			)
		)
		(property "MPN" "CR0402-FX-3002GLF"
			(at 356.87 102.87 0)
			(effects
				(font
					(size 1.27 1.27)
					(thickness 0.15)
				)
				(justify left bottom)
				(hide yes)
			)
		)
		(property "Manufacturer" "Bourns"
			(at 359.41 102.87 0)
			(effects
				(font
					(size 1.27 1.27)
					(thickness 0.15)
				)
				(justify left bottom)
				(hide yes)
			)
		)
		(property "License" "Apache-2.0"
			(at 361.95 102.87 0)
			(effects
				(font
					(size 1.27 1.27)
					(thickness 0.15)
				)
				(justify left bottom)
				(hide yes)
			)
		)
		(property "Author" "Antmicro"
			(at 364.49 102.87 0)
			(effects
				(font
					(size 1.27 1.27)
					(thickness 0.15)
				)
				(justify left bottom)
				(hide yes)
			)
		)
		(property "Val" "30k"
			(at 339.09 121.92 90)
			(effects
				(font
					(size 1.27 1.27)
					(thickness 0.15)
				)
				(justify right)
			)
		)
		(property "Tolerance" "1%"
			(at 346.71 102.87 0)
			(effects
				(font
					(size 1.27 1.27)
				)
				(justify left bottom)
				(hide yes)
			)
		)
		(pin "1"
		)
		(pin "2"
		)
		(instances
			(project "jetson-agx-thor-baseboard"
				(path ""
					(reference "R317")
					(unit 1)
				)
			)
		)
	)
	(symbol
		(lib_id "antmicroCapacitors0603:C_22u_16V_0603")
		(at 365.76 127 90)
		(unit 1)
		(exclude_from_sim no)
		(in_bom yes)
		(on_board yes)
		(dnp no)
		(fields_autoplaced yes)
		(property "Reference" "C37"
			(at 368.3 123.1835 90)
			(effects
				(font
					(size 1.27 1.27)
					(thickness 0.15)
				)
				(justify right)
			)
		)
		(property "Value" "C_22u_16V_0603"
			(at 375.92 106.68 0)
			(effects
				(font
					(size 1.27 1.27)
					(thickness 0.15)
				)
				(justify left bottom)
				(hide yes)
			)
		)
		(property "Footprint" "antmicro-footprints:C_0603_1608Metric_EIA"
			(at 378.46 106.68 0)
			(effects
				(font
					(size 1.27 1.27)
					(thickness 0.15)
				)
				(justify left bottom)
				(hide yes)
			)
		)
		(property "Datasheet" "https://product.samsungsem.com/mlcc/CL10A226MO7JZN.do"
			(at 381 106.68 0)
			(effects
				(font
					(size 1.27 1.27)
					(thickness 0.15)
				)
				(justify left bottom)
				(hide yes)
			)
		)
		(property "Description" "SMD Multilayer Ceramic Capacitor"
			(at 365.76 127 0)
			(effects
				(font
					(size 1.27 1.27)
				)
				(hide yes)
			)
		)
		(property "MPN" "CL10A226MO7JZNC"
			(at 383.54 106.68 0)
			(effects
				(font
					(size 1.27 1.27)
					(thickness 0.15)
				)
				(justify left bottom)
				(hide yes)
			)
		)
		(property "Manufacturer" "Samsung Electro-Mechanics"
			(at 386.08 106.68 0)
			(effects
				(font
					(size 1.27 1.27)
					(thickness 0.15)
				)
				(justify left bottom)
				(hide yes)
			)
		)
		(property "License" "Apache-2.0"
			(at 388.62 106.68 0)
			(effects
				(font
					(size 1.27 1.27)
					(thickness 0.15)
				)
				(justify left bottom)
				(hide yes)
			)
		)
		(property "Author" "Antmicro"
			(at 391.16 106.68 0)
			(effects
				(font
					(size 1.27 1.27)
					(thickness 0.15)
				)
				(justify left bottom)
				(hide yes)
			)
		)
		(property "Val" "22u"
			(at 368.3 125.7235 90)
			(effects
				(font
					(size 1.27 1.27)
					(thickness 0.15)
				)
				(justify right)
			)
		)
		(property "Voltage" "16V"
			(at 393.7 106.68 0)
			(effects
				(font
					(size 1.27 1.27)
				)
				(justify left bottom)
				(hide yes)
			)
		)
		(property "Dielectric" ""
			(at 396.24 106.68 0)
			(effects
				(font
					(size 1.27 1.27)
				)
				(justify left bottom)
				(hide yes)
			)
		)
		(pin "1"
		)
		(pin "2"
		)
		(instances
			(project "jetson-agx-thor-baseboard"
				(path ""
					(reference "C37")
					(unit 1)
				)
			)
		)
	)
	(symbol
		(lib_id "antmicropower:PWR_FLAG")
		(at 233.68 259.08 270)
		(unit 1)
		(exclude_from_sim no)
		(in_bom yes)
		(on_board yes)
		(dnp no)
		(property "Reference" "#FLG05"
			(at 235.585 259.08 0)
			(effects
				(font
					(size 1.27 1.27)
				)
				(hide yes)
			)
		)
		(property "Value" "PWR_FLAG"
			(at 241.808 259.08 90)
			(effects
				(font
					(size 1.27 1.27)
				)
			)
		)
		(property "Footprint" ""
			(at 233.68 259.08 0)
			(effects
				(font
					(size 1.27 1.27)
				)
				(hide yes)
			)
		)
		(property "Datasheet" ""
			(at 233.68 259.08 0)
			(effects
				(font
					(size 1.27 1.27)
				)
				(hide yes)
			)
		)
		(property "Description" ""
			(at 233.68 259.08 0)
			(effects
				(font
					(size 1.27 1.27)
				)
				(hide yes)
			)
		)
		(pin "1"
		)
		(instances
			(project "jetson-agx-thor-baseboard"
				(path ""
					(reference "#FLG05")
					(unit 1)
				)
			)
		)
	)
	(symbol
		(lib_id "antmicroTVSDiodes:PESD5Z5_0F")
		(at 232.41 176.53 270)
		(unit 1)
		(exclude_from_sim no)
		(in_bom yes)
		(on_board yes)
		(dnp no)
		(property "Reference" "D62"
			(at 237.236 178.054 90)
			(effects
				(font
					(size 1.27 1.27)
				)
				(justify right)
			)
		)
		(property "Value" "PESD5Z5.0F"
			(at 217.17 198.12 0)
			(effects
				(font
					(size 1.27 1.27)
					(thickness 0.15)
				)
				(justify left bottom)
				(hide yes)
			)
		)
		(property "Footprint" "antmicro-footprints:SOD-523"
			(at 227.33 191.77 0)
			(effects
				(font
					(size 1.27 1.27)
					(thickness 0.15)
				)
				(justify left bottom)
				(hide yes)
			)
		)
		(property "Datasheet" "https://assets.nexperia.com/documents/data-sheet/PESD5Z5_0.pdf"
			(at 224.79 191.77 0)
			(effects
				(font
					(size 1.27 1.27)
					(thickness 0.15)
				)
				(justify left bottom)
				(hide yes)
			)
		)
		(property "Description" "Unidirectional TVS, 30 kV,  SOD-523, 5 V, 89 pF"
			(at 212.09 191.77 0)
			(effects
				(font
					(size 1.27 1.27)
				)
				(justify left bottom)
				(hide yes)
			)
		)
		(property "Manufacturer" "Nexperia"
			(at 222.25 191.77 0)
			(effects
				(font
					(size 1.27 1.27)
					(thickness 0.15)
				)
				(justify left bottom)
				(hide yes)
			)
		)
		(property "MPN" "PESD5Z5.0F"
			(at 233.426 180.594 90)
			(effects
				(font
					(size 1.27 1.27)
					(thickness 0.15)
				)
				(justify left bottom)
			)
		)
		(property "Author" "Antmicro"
			(at 217.17 191.77 0)
			(effects
				(font
					(size 1.27 1.27)
					(thickness 0.15)
				)
				(justify left bottom)
				(hide yes)
			)
		)
		(property "License" "Apache-2.0"
			(at 214.63 191.77 0)
			(effects
				(font
					(size 1.27 1.27)
					(thickness 0.15)
				)
				(justify left bottom)
				(hide yes)
			)
		)
		(pin "1"
		)
		(pin "2"
		)
		(instances
			(project "jetson-agx-thor-baseboard"
				(path ""
					(reference "D62")
					(unit 1)
				)
			)
		)
	)
	(symbol
		(lib_id "antmicropower:GND")
		(at 43.18 167.64 0)
		(unit 1)
		(exclude_from_sim no)
		(in_bom yes)
		(on_board yes)
		(dnp no)
		(property "Reference" "#PWR0745"
			(at 43.18 173.99 0)
			(effects
				(font
					(size 1.27 1.27)
				)
				(justify left bottom)
				(hide yes)
			)
		)
		(property "Value" "GND"
			(at 43.18 171.45 0)
			(effects
				(font
					(size 1.27 1.27)
					(thickness 0.15)
				)
			)
		)
		(property "Footprint" ""
			(at 52.07 175.26 0)
			(effects
				(font
					(size 1.27 1.27)
					(thickness 0.15)
				)
				(justify left bottom)
				(hide yes)
			)
		)
		(property "Datasheet" ""
			(at 52.07 180.34 0)
			(effects
				(font
					(size 1.27 1.27)
					(thickness 0.15)
				)
				(justify left bottom)
				(hide yes)
			)
		)
		(property "Description" ""
			(at 43.18 167.64 0)
			(effects
				(font
					(size 1.27 1.27)
				)
				(hide yes)
			)
		)
		(property "Author" "Antmicro"
			(at 52.07 175.26 0)
			(effects
				(font
					(size 1.27 1.27)
					(thickness 0.15)
				)
				(justify left bottom)
				(hide yes)
			)
		)
		(property "License" "Apache-2.0"
			(at 52.07 177.8 0)
			(effects
				(font
					(size 1.27 1.27)
					(thickness 0.15)
				)
				(justify left bottom)
				(hide yes)
			)
		)
		(pin "1"
		)
		(instances
			(project "jetson-agx-thor-baseboard"
				(path ""
					(reference "#PWR0745")
					(unit 1)
				)
			)
		)
	)
	(symbol
		(lib_id "antmicropower:GND")
		(at 21.59 107.95 0)
		(unit 1)
		(exclude_from_sim no)
		(in_bom yes)
		(on_board yes)
		(dnp no)
		(property "Reference" "#PWR0602"
			(at 21.59 114.3 0)
			(effects
				(font
					(size 1.27 1.27)
				)
				(justify left bottom)
				(hide yes)
			)
		)
		(property "Value" "GND"
			(at 21.59 111.76 0)
			(effects
				(font
					(size 1.27 1.27)
					(thickness 0.15)
				)
			)
		)
		(property "Footprint" ""
			(at 30.48 115.57 0)
			(effects
				(font
					(size 1.27 1.27)
					(thickness 0.15)
				)
				(justify left bottom)
				(hide yes)
			)
		)
		(property "Datasheet" ""
			(at 30.48 120.65 0)
			(effects
				(font
					(size 1.27 1.27)
					(thickness 0.15)
				)
				(justify left bottom)
				(hide yes)
			)
		)
		(property "Description" ""
			(at 21.59 107.95 0)
			(effects
				(font
					(size 1.27 1.27)
				)
				(hide yes)
			)
		)
		(property "Author" "Antmicro"
			(at 30.48 115.57 0)
			(effects
				(font
					(size 1.27 1.27)
					(thickness 0.15)
				)
				(justify left bottom)
				(hide yes)
			)
		)
		(property "License" "Apache-2.0"
			(at 30.48 118.11 0)
			(effects
				(font
					(size 1.27 1.27)
					(thickness 0.15)
				)
				(justify left bottom)
				(hide yes)
			)
		)
		(pin "1"
		)
		(instances
			(project "jetson-agx-thor-baseboard"
				(path ""
					(reference "#PWR0602")
					(unit 1)
				)
			)
		)
	)
	(symbol
		(lib_id "antmicropower:PWR_FLAG")
		(at 375.92 116.84 270)
		(mirror x)
		(unit 1)
		(exclude_from_sim no)
		(in_bom yes)
		(on_board yes)
		(dnp no)
		(property "Reference" "#FLG024"
			(at 377.825 116.84 0)
			(effects
				(font
					(size 1.27 1.27)
				)
				(hide yes)
			)
		)
		(property "Value" "PWR_FLAG"
			(at 379.73 117.094 90)
			(effects
				(font
					(size 1.27 1.27)
				)
				(justify left)
			)
		)
		(property "Footprint" ""
			(at 375.92 116.84 0)
			(effects
				(font
					(size 1.27 1.27)
				)
				(hide yes)
			)
		)
		(property "Datasheet" ""
			(at 375.92 116.84 0)
			(effects
				(font
					(size 1.27 1.27)
				)
				(hide yes)
			)
		)
		(property "Description" ""
			(at 375.92 116.84 0)
			(effects
				(font
					(size 1.27 1.27)
				)
				(hide yes)
			)
		)
		(pin "1"
		)
		(instances
			(project "jetson-agx-thor-baseboard"
				(path ""
					(reference "#FLG024")
					(unit 1)
				)
			)
		)
	)
	(symbol
		(lib_id "antmicroCapacitors0603:C_22u_16V_0603")
		(at 154.94 226.06 90)
		(unit 1)
		(exclude_from_sim no)
		(in_bom yes)
		(on_board yes)
		(dnp no)
		(property "Reference" "C63"
			(at 155.575 221.615 90)
			(effects
				(font
					(size 1.27 1.27)
				)
				(justify right)
			)
		)
		(property "Value" "C_22u_16V_0603"
			(at 165.1 205.74 0)
			(effects
				(font
					(size 1.27 1.27)
					(thickness 0.15)
				)
				(justify left bottom)
				(hide yes)
			)
		)
		(property "Footprint" "antmicro-footprints:C_0603_1608Metric_EIA"
			(at 167.64 205.74 0)
			(effects
				(font
					(size 1.27 1.27)
					(thickness 0.15)
				)
				(justify left bottom)
				(hide yes)
			)
		)
		(property "Datasheet" "https://product.samsungsem.com/mlcc/CL10A226MO7JZN.do"
			(at 170.18 205.74 0)
			(effects
				(font
					(size 1.27 1.27)
					(thickness 0.15)
				)
				(justify left bottom)
				(hide yes)
			)
		)
		(property "Description" "SMD Multilayer Ceramic Capacitor"
			(at 154.94 226.06 0)
			(effects
				(font
					(size 1.27 1.27)
				)
				(hide yes)
			)
		)
		(property "Manufacturer" "Samsung Electro-Mechanics"
			(at 175.26 205.74 0)
			(effects
				(font
					(size 1.27 1.27)
					(thickness 0.15)
				)
				(justify left bottom)
				(hide yes)
			)
		)
		(property "MPN" "CL10A226MO7JZNC"
			(at 172.72 205.74 0)
			(effects
				(font
					(size 1.27 1.27)
					(thickness 0.15)
				)
				(justify left bottom)
				(hide yes)
			)
		)
		(property "Val" "22u"
			(at 155.575 225.425 90)
			(effects
				(font
					(size 1.27 1.27)
					(thickness 0.15)
				)
				(justify right)
			)
		)
		(property "License" "Apache-2.0"
			(at 177.8 205.74 0)
			(effects
				(font
					(size 1.27 1.27)
					(thickness 0.15)
				)
				(justify left bottom)
				(hide yes)
			)
		)
		(property "Author" "Antmicro"
			(at 180.34 205.74 0)
			(effects
				(font
					(size 1.27 1.27)
					(thickness 0.15)
				)
				(justify left bottom)
				(hide yes)
			)
		)
		(property "Voltage" "16V"
			(at 182.88 205.74 0)
			(effects
				(font
					(size 1.27 1.27)
				)
				(justify left bottom)
				(hide yes)
			)
		)
		(property "Dielectric" ""
			(at 185.42 205.74 0)
			(effects
				(font
					(size 1.27 1.27)
				)
				(justify left bottom)
				(hide yes)
			)
		)
		(pin "1"
		)
		(pin "2"
		)
		(instances
			(project "jetson-agx-thor-baseboard"
				(path ""
					(reference "C63")
					(unit 1)
				)
			)
		)
	)
	(symbol
		(lib_id "antmicroCapacitors0603:C_22u_16V_0603")
		(at 266.7 124.46 90)
		(unit 1)
		(exclude_from_sim no)
		(in_bom yes)
		(on_board yes)
		(dnp no)
		(fields_autoplaced yes)
		(property "Reference" "C31"
			(at 269.24 119.3735 90)
			(effects
				(font
					(size 1.27 1.27)
					(thickness 0.15)
				)
				(justify right)
			)
		)
		(property "Value" "C_22u_16V_0603"
			(at 276.86 104.14 0)
			(effects
				(font
					(size 1.27 1.27)
					(thickness 0.15)
				)
				(justify left bottom)
				(hide yes)
			)
		)
		(property "Footprint" "antmicro-footprints:C_0603_1608Metric_EIA"
			(at 279.4 104.14 0)
			(effects
				(font
					(size 1.27 1.27)
					(thickness 0.15)
				)
				(justify left bottom)
				(hide yes)
			)
		)
		(property "Datasheet" "https://product.samsungsem.com/mlcc/CL10A226MO7JZN.do"
			(at 281.94 104.14 0)
			(effects
				(font
					(size 1.27 1.27)
					(thickness 0.15)
				)
				(justify left bottom)
				(hide yes)
			)
		)
		(property "Description" "SMD Multilayer Ceramic Capacitor"
			(at 266.7 124.46 0)
			(effects
				(font
					(size 1.27 1.27)
				)
				(hide yes)
			)
		)
		(property "MPN" "CL10A226MO7JZNC"
			(at 284.48 104.14 0)
			(effects
				(font
					(size 1.27 1.27)
					(thickness 0.15)
				)
				(justify left bottom)
				(hide yes)
			)
		)
		(property "Manufacturer" "Samsung Electro-Mechanics"
			(at 287.02 104.14 0)
			(effects
				(font
					(size 1.27 1.27)
					(thickness 0.15)
				)
				(justify left bottom)
				(hide yes)
			)
		)
		(property "License" "Apache-2.0"
			(at 289.56 104.14 0)
			(effects
				(font
					(size 1.27 1.27)
					(thickness 0.15)
				)
				(justify left bottom)
				(hide yes)
			)
		)
		(property "Author" "Antmicro"
			(at 292.1 104.14 0)
			(effects
				(font
					(size 1.27 1.27)
					(thickness 0.15)
				)
				(justify left bottom)
				(hide yes)
			)
		)
		(property "Val" "22u"
			(at 269.24 121.9135 90)
			(effects
				(font
					(size 1.27 1.27)
					(thickness 0.15)
				)
				(justify right)
			)
		)
		(property "Voltage" "16V"
			(at 269.24 124.4535 90)
			(effects
				(font
					(size 1.27 1.27)
				)
				(justify right)
				(hide yes)
			)
		)
		(property "Dielectric" ""
			(at 297.18 104.14 0)
			(effects
				(font
					(size 1.27 1.27)
				)
				(justify left bottom)
				(hide yes)
			)
		)
		(property "Public" "False"
			(at 299.72 104.14 0)
			(effects
				(font
					(size 1.27 1.27)
				)
				(justify left bottom)
				(hide yes)
			)
		)
		(pin "2"
		)
		(pin "1"
		)
		(instances
			(project "jetson-agx-thor-baseboard"
				(path ""
					(reference "C31")
					(unit 1)
				)
			)
		)
	)
	(symbol
		(lib_id "antmicropower:GND")
		(at 177.8 59.69 0)
		(unit 1)
		(exclude_from_sim no)
		(in_bom yes)
		(on_board yes)
		(dnp no)
		(property "Reference" "#PWR0543"
			(at 177.8 66.04 0)
			(effects
				(font
					(size 1.27 1.27)
				)
				(justify left bottom)
				(hide yes)
			)
		)
		(property "Value" "GND"
			(at 177.8 63.5 0)
			(effects
				(font
					(size 1.27 1.27)
					(thickness 0.15)
				)
			)
		)
		(property "Footprint" ""
			(at 186.69 67.31 0)
			(effects
				(font
					(size 1.27 1.27)
					(thickness 0.15)
				)
				(justify left bottom)
				(hide yes)
			)
		)
		(property "Datasheet" ""
			(at 186.69 72.39 0)
			(effects
				(font
					(size 1.27 1.27)
					(thickness 0.15)
				)
				(justify left bottom)
				(hide yes)
			)
		)
		(property "Description" ""
			(at 177.8 59.69 0)
			(effects
				(font
					(size 1.27 1.27)
				)
				(hide yes)
			)
		)
		(property "Author" "Antmicro"
			(at 186.69 67.31 0)
			(effects
				(font
					(size 1.27 1.27)
					(thickness 0.15)
				)
				(justify left bottom)
				(hide yes)
			)
		)
		(property "License" "Apache-2.0"
			(at 186.69 69.85 0)
			(effects
				(font
					(size 1.27 1.27)
					(thickness 0.15)
				)
				(justify left bottom)
				(hide yes)
			)
		)
		(pin "1"
		)
		(instances
			(project "jetson-agx-thor-baseboard"
				(path ""
					(reference "#PWR0543")
					(unit 1)
				)
			)
		)
	)
	(symbol
		(lib_id "antmicroResistors0402:R_100k_0402")
		(at 66.04 186.69 90)
		(unit 1)
		(exclude_from_sim no)
		(in_bom yes)
		(on_board yes)
		(dnp no)
		(property "Reference" "R311"
			(at 67.31 182.88 90)
			(effects
				(font
					(size 1.27 1.27)
					(thickness 0.15)
				)
				(justify right)
			)
		)
		(property "Value" "R_100k_0402"
			(at 78.74 166.37 0)
			(effects
				(font
					(size 1.27 1.27)
					(thickness 0.15)
				)
				(justify left bottom)
				(hide yes)
			)
		)
		(property "Footprint" "antmicro-footprints:R_0402_1005Metric"
			(at 81.28 166.37 0)
			(effects
				(font
					(size 1.27 1.27)
					(thickness 0.15)
				)
				(justify left bottom)
				(hide yes)
			)
		)
		(property "Datasheet" "https://www.bourns.com/docs/product-datasheets/cr.pdf"
			(at 83.82 166.37 0)
			(effects
				(font
					(size 1.27 1.27)
					(thickness 0.15)
				)
				(justify left bottom)
				(hide yes)
			)
		)
		(property "Description" "SMD Chip Resistor, 100 kohm, ± 1%, 62.5 mW, 0402 [1005 Metric], Thick Film, General Purpose"
			(at 96.52 166.37 0)
			(effects
				(font
					(size 1.27 1.27)
				)
				(justify left bottom)
				(hide yes)
			)
		)
		(property "MPN" "CR0402-FX-1003GLF"
			(at 86.36 166.37 0)
			(effects
				(font
					(size 1.27 1.27)
					(thickness 0.15)
				)
				(justify left bottom)
				(hide yes)
			)
		)
		(property "Manufacturer" "Bourns"
			(at 88.9 166.37 0)
			(effects
				(font
					(size 1.27 1.27)
					(thickness 0.15)
				)
				(justify left bottom)
				(hide yes)
			)
		)
		(property "License" "Apache-2.0"
			(at 91.44 166.37 0)
			(effects
				(font
					(size 1.27 1.27)
					(thickness 0.15)
				)
				(justify left bottom)
				(hide yes)
			)
		)
		(property "Author" "Antmicro"
			(at 93.98 166.37 0)
			(effects
				(font
					(size 1.27 1.27)
					(thickness 0.15)
				)
				(justify left bottom)
				(hide yes)
			)
		)
		(property "Val" "100k"
			(at 67.31 185.42 90)
			(effects
				(font
					(size 1.27 1.27)
					(thickness 0.15)
				)
				(justify right)
			)
		)
		(property "Tolerance" "1%"
			(at 76.2 166.37 0)
			(effects
				(font
					(size 1.27 1.27)
				)
				(justify left bottom)
				(hide yes)
			)
		)
		(pin "2"
		)
		(pin "1"
		)
		(instances
			(project "jetson-agx-thor-baseboard"
				(path ""
					(reference "R311")
					(unit 1)
				)
			)
		)
	)
	(symbol
		(lib_id "antmicroCapacitorsmisc:C_22u_25V_0805")
		(at 34.29 224.79 90)
		(unit 1)
		(exclude_from_sim no)
		(in_bom yes)
		(on_board yes)
		(dnp no)
		(property "Reference" "C42"
			(at 34.925 220.345 90)
			(effects
				(font
					(size 1.27 1.27)
					(thickness 0.15)
				)
				(justify right)
			)
		)
		(property "Value" "C_22u_25V_0805"
			(at 44.45 204.47 0)
			(effects
				(font
					(size 1.27 1.27)
					(thickness 0.15)
				)
				(justify left bottom)
				(hide yes)
			)
		)
		(property "Footprint" "antmicro-footprints:C_0805_2012Metric"
			(at 46.99 204.47 0)
			(effects
				(font
					(size 1.27 1.27)
					(thickness 0.15)
				)
				(justify left bottom)
				(hide yes)
			)
		)
		(property "Datasheet" "https://product.samsungsem.com/mlcc/CL21A226MAYNNN.do"
			(at 49.53 204.47 0)
			(effects
				(font
					(size 1.27 1.27)
					(thickness 0.15)
				)
				(justify left bottom)
				(hide yes)
			)
		)
		(property "Description" "SMT Multilayer Ceramic Capacitor, 22uF, +/-20%, 25V, X5R, 0805 [2012 Metric]"
			(at 34.29 224.79 0)
			(effects
				(font
					(size 1.27 1.27)
				)
				(hide yes)
			)
		)
		(property "MPN" "CL21A226MAYNNNE"
			(at 52.07 204.47 0)
			(effects
				(font
					(size 1.27 1.27)
					(thickness 0.15)
				)
				(justify left bottom)
				(hide yes)
			)
		)
		(property "Manufacturer" "Samsung Electro-Mechanics"
			(at 54.61 204.47 0)
			(effects
				(font
					(size 1.27 1.27)
					(thickness 0.15)
				)
				(justify left bottom)
				(hide yes)
			)
		)
		(property "License" "Apache-2.0"
			(at 57.15 204.47 0)
			(effects
				(font
					(size 1.27 1.27)
					(thickness 0.15)
				)
				(justify left bottom)
				(hide yes)
			)
		)
		(property "Author" "Antmicro"
			(at 59.69 204.47 0)
			(effects
				(font
					(size 1.27 1.27)
					(thickness 0.15)
				)
				(justify left bottom)
				(hide yes)
			)
		)
		(property "Val" "22u"
			(at 34.925 224.155 90)
			(effects
				(font
					(size 1.27 1.27)
					(thickness 0.15)
				)
				(justify right)
			)
		)
		(property "Voltage" "25V"
			(at 34.925 226.695 90)
			(effects
				(font
					(size 1.27 1.27)
				)
				(justify right)
			)
		)
		(property "Dielectric" "X5R"
			(at 64.77 204.47 0)
			(effects
				(font
					(size 1.27 1.27)
				)
				(justify left bottom)
				(hide yes)
			)
		)
		(property "Public" "False"
			(at 67.31 204.47 0)
			(effects
				(font
					(size 1.27 1.27)
				)
				(justify left bottom)
				(hide yes)
			)
		)
		(pin "2"
		)
		(pin "1"
		)
		(instances
			(project "jetson-agx-thor-baseboard"
				(path ""
					(reference "C42")
					(unit 1)
				)
			)
		)
	)
	(symbol
		(lib_id "antmicropower:GND")
		(at 21.59 279.4 0)
		(unit 1)
		(exclude_from_sim no)
		(in_bom yes)
		(on_board yes)
		(dnp no)
		(property "Reference" "#PWR0606"
			(at 21.59 285.75 0)
			(effects
				(font
					(size 1.27 1.27)
				)
				(justify left bottom)
				(hide yes)
			)
		)
		(property "Value" "GND"
			(at 21.59 283.21 0)
			(effects
				(font
					(size 1.27 1.27)
					(thickness 0.15)
				)
			)
		)
		(property "Footprint" ""
			(at 30.48 287.02 0)
			(effects
				(font
					(size 1.27 1.27)
					(thickness 0.15)
				)
				(justify left bottom)
				(hide yes)
			)
		)
		(property "Datasheet" ""
			(at 30.48 292.1 0)
			(effects
				(font
					(size 1.27 1.27)
					(thickness 0.15)
				)
				(justify left bottom)
				(hide yes)
			)
		)
		(property "Description" ""
			(at 21.59 279.4 0)
			(effects
				(font
					(size 1.27 1.27)
				)
				(hide yes)
			)
		)
		(property "Author" "Antmicro"
			(at 30.48 287.02 0)
			(effects
				(font
					(size 1.27 1.27)
					(thickness 0.15)
				)
				(justify left bottom)
				(hide yes)
			)
		)
		(property "License" "Apache-2.0"
			(at 30.48 289.56 0)
			(effects
				(font
					(size 1.27 1.27)
					(thickness 0.15)
				)
				(justify left bottom)
				(hide yes)
			)
		)
		(pin "1"
		)
		(instances
			(project "jetson-agx-thor-baseboard"
				(path ""
					(reference "#PWR0606")
					(unit 1)
				)
			)
		)
	)
	(symbol
		(lib_id "antmicropower:GND")
		(at 154.94 74.93 0)
		(unit 1)
		(exclude_from_sim no)
		(in_bom yes)
		(on_board yes)
		(dnp no)
		(property "Reference" "#PWR0593"
			(at 154.94 81.28 0)
			(effects
				(font
					(size 1.27 1.27)
				)
				(justify left bottom)
				(hide yes)
			)
		)
		(property "Value" "GND"
			(at 154.94 78.74 0)
			(effects
				(font
					(size 1.27 1.27)
					(thickness 0.15)
				)
			)
		)
		(property "Footprint" ""
			(at 163.83 82.55 0)
			(effects
				(font
					(size 1.27 1.27)
					(thickness 0.15)
				)
				(justify left bottom)
				(hide yes)
			)
		)
		(property "Datasheet" ""
			(at 163.83 87.63 0)
			(effects
				(font
					(size 1.27 1.27)
					(thickness 0.15)
				)
				(justify left bottom)
				(hide yes)
			)
		)
		(property "Description" ""
			(at 154.94 74.93 0)
			(effects
				(font
					(size 1.27 1.27)
				)
				(hide yes)
			)
		)
		(property "Author" "Antmicro"
			(at 163.83 82.55 0)
			(effects
				(font
					(size 1.27 1.27)
					(thickness 0.15)
				)
				(justify left bottom)
				(hide yes)
			)
		)
		(property "License" "Apache-2.0"
			(at 163.83 85.09 0)
			(effects
				(font
					(size 1.27 1.27)
					(thickness 0.15)
				)
				(justify left bottom)
				(hide yes)
			)
		)
		(pin "1"
		)
		(instances
			(project "jetson-agx-thor-baseboard"
				(path ""
					(reference "#PWR0593")
					(unit 1)
				)
			)
		)
	)
	(symbol
		(lib_id "antmicroDCDCConverters:SIC437AED-T1-GE3")
		(at 92.71 96.52 0)
		(unit 1)
		(exclude_from_sim no)
		(in_bom yes)
		(on_board yes)
		(dnp no)
		(property "Reference" "U65"
			(at 103.505 90.17 0)
			(effects
				(font
					(size 1.27 1.27)
					(thickness 0.15)
				)
			)
		)
		(property "Value" "SIC437AED-T1-GE3"
			(at 125.73 104.14 0)
			(effects
				(font
					(size 1.27 1.27)
					(thickness 0.15)
				)
				(justify left bottom)
				(hide yes)
			)
		)
		(property "Footprint" "antmicro-footprints:MLP44-24L_4x4x0.75mm"
			(at 125.73 106.68 0)
			(effects
				(font
					(size 1.27 1.27)
					(thickness 0.15)
				)
				(justify left bottom)
				(hide yes)
			)
		)
		(property "Datasheet" "https://www.vishay.com/docs/75921/sic437.pdf"
			(at 125.73 109.22 0)
			(effects
				(font
					(size 1.27 1.27)
					(thickness 0.15)
				)
				(justify left bottom)
				(hide yes)
			)
		)
		(property "Description" "DC/DC Buck Step Down Regulator Adjustable, 4.5-28V In, 0.6V to 20V/12A Out, 1MHz, PowerPAK MLP44-24"
			(at 125.73 119.38 0)
			(effects
				(font
					(size 1.27 1.27)
				)
				(justify left bottom)
				(hide yes)
			)
		)
		(property "Manufacturer" "Vishay"
			(at 125.73 111.76 0)
			(effects
				(font
					(size 1.27 1.27)
					(thickness 0.15)
				)
				(justify left bottom)
				(hide yes)
			)
		)
		(property "MPN" "SIC437AED-T1-GE3"
			(at 103.505 92.71 0)
			(effects
				(font
					(size 1.27 1.27)
					(thickness 0.15)
				)
			)
		)
		(property "Author" "Antmicro"
			(at 125.73 114.3 0)
			(effects
				(font
					(size 1.27 1.27)
					(thickness 0.15)
				)
				(justify left bottom)
				(hide yes)
			)
		)
		(property "License" "Apache-2.0"
			(at 125.73 116.84 0)
			(effects
				(font
					(size 1.27 1.27)
					(thickness 0.15)
				)
				(justify left bottom)
				(hide yes)
			)
		)
		(pin "7"
		)
		(pin "16"
		)
		(pin "18"
		)
		(pin "8"
		)
		(pin "15"
		)
		(pin "14"
		)
		(pin "20"
		)
		(pin "2"
		)
		(pin "12"
		)
		(pin "22"
		)
		(pin "11"
		)
		(pin "26"
		)
		(pin "10"
		)
		(pin "19"
		)
		(pin "5"
		)
		(pin "4"
		)
		(pin "17"
		)
		(pin "6"
		)
		(pin "3"
		)
		(pin "1"
		)
		(pin "13"
		)
		(pin "23"
		)
		(pin "25"
		)
		(pin "21"
		)
		(pin "24"
		)
		(pin "9"
		)
		(pin "27"
		)
		(pin "28"
		)
		(instances
			(project "jetson-agx-thor-baseboard"
				(path ""
					(reference "U65")
					(unit 1)
				)
			)
		)
	)
	(symbol
		(lib_id "antmicropower:GND")
		(at 48.26 279.4 0)
		(unit 1)
		(exclude_from_sim no)
		(in_bom yes)
		(on_board yes)
		(dnp no)
		(property "Reference" "#PWR0100"
			(at 48.26 285.75 0)
			(effects
				(font
					(size 1.27 1.27)
				)
				(justify left bottom)
				(hide yes)
			)
		)
		(property "Value" "GND"
			(at 48.26 283.21 0)
			(effects
				(font
					(size 1.27 1.27)
					(thickness 0.15)
				)
			)
		)
		(property "Footprint" ""
			(at 57.15 287.02 0)
			(effects
				(font
					(size 1.27 1.27)
					(thickness 0.15)
				)
				(justify left bottom)
				(hide yes)
			)
		)
		(property "Datasheet" ""
			(at 57.15 292.1 0)
			(effects
				(font
					(size 1.27 1.27)
					(thickness 0.15)
				)
				(justify left bottom)
				(hide yes)
			)
		)
		(property "Description" ""
			(at 48.26 279.4 0)
			(effects
				(font
					(size 1.27 1.27)
				)
				(hide yes)
			)
		)
		(property "Author" "Antmicro"
			(at 57.15 287.02 0)
			(effects
				(font
					(size 1.27 1.27)
					(thickness 0.15)
				)
				(justify left bottom)
				(hide yes)
			)
		)
		(property "License" "Apache-2.0"
			(at 57.15 289.56 0)
			(effects
				(font
					(size 1.27 1.27)
					(thickness 0.15)
				)
				(justify left bottom)
				(hide yes)
			)
		)
		(pin "1"
		)
		(instances
			(project "jetson-agx-thor-baseboard"
				(path ""
					(reference "#PWR0100")
					(unit 1)
				)
			)
		)
	)
	(symbol
		(lib_id "antmicroCapacitors0603:C_22u_16V_0603")
		(at 162.56 226.06 90)
		(unit 1)
		(exclude_from_sim no)
		(in_bom yes)
		(on_board yes)
		(dnp no)
		(property "Reference" "C66"
			(at 163.195 221.615 90)
			(effects
				(font
					(size 1.27 1.27)
				)
				(justify right)
			)
		)
		(property "Value" "C_22u_16V_0603"
			(at 172.72 205.74 0)
			(effects
				(font
					(size 1.27 1.27)
					(thickness 0.15)
				)
				(justify left bottom)
				(hide yes)
			)
		)
		(property "Footprint" "antmicro-footprints:C_0603_1608Metric_EIA"
			(at 175.26 205.74 0)
			(effects
				(font
					(size 1.27 1.27)
					(thickness 0.15)
				)
				(justify left bottom)
				(hide yes)
			)
		)
		(property "Datasheet" "https://product.samsungsem.com/mlcc/CL10A226MO7JZN.do"
			(at 177.8 205.74 0)
			(effects
				(font
					(size 1.27 1.27)
					(thickness 0.15)
				)
				(justify left bottom)
				(hide yes)
			)
		)
		(property "Description" "SMD Multilayer Ceramic Capacitor"
			(at 162.56 226.06 0)
			(effects
				(font
					(size 1.27 1.27)
				)
				(hide yes)
			)
		)
		(property "Manufacturer" "Samsung Electro-Mechanics"
			(at 182.88 205.74 0)
			(effects
				(font
					(size 1.27 1.27)
					(thickness 0.15)
				)
				(justify left bottom)
				(hide yes)
			)
		)
		(property "MPN" "CL10A226MO7JZNC"
			(at 180.34 205.74 0)
			(effects
				(font
					(size 1.27 1.27)
					(thickness 0.15)
				)
				(justify left bottom)
				(hide yes)
			)
		)
		(property "Val" "22u"
			(at 163.195 225.425 90)
			(effects
				(font
					(size 1.27 1.27)
					(thickness 0.15)
				)
				(justify right)
			)
		)
		(property "License" "Apache-2.0"
			(at 185.42 205.74 0)
			(effects
				(font
					(size 1.27 1.27)
					(thickness 0.15)
				)
				(justify left bottom)
				(hide yes)
			)
		)
		(property "Author" "Antmicro"
			(at 187.96 205.74 0)
			(effects
				(font
					(size 1.27 1.27)
					(thickness 0.15)
				)
				(justify left bottom)
				(hide yes)
			)
		)
		(property "Voltage" "16V"
			(at 190.5 205.74 0)
			(effects
				(font
					(size 1.27 1.27)
				)
				(justify left bottom)
				(hide yes)
			)
		)
		(property "Dielectric" ""
			(at 193.04 205.74 0)
			(effects
				(font
					(size 1.27 1.27)
				)
				(justify left bottom)
				(hide yes)
			)
		)
		(pin "1"
		)
		(pin "2"
		)
		(instances
			(project "jetson-agx-thor-baseboard"
				(path ""
					(reference "C66")
					(unit 1)
				)
			)
		)
	)
	(symbol
		(lib_id "antmicropower:GND")
		(at 27.94 279.4 0)
		(unit 1)
		(exclude_from_sim no)
		(in_bom yes)
		(on_board yes)
		(dnp no)
		(property "Reference" "#PWR0607"
			(at 27.94 285.75 0)
			(effects
				(font
					(size 1.27 1.27)
				)
				(justify left bottom)
				(hide yes)
			)
		)
		(property "Value" "GND"
			(at 27.94 283.21 0)
			(effects
				(font
					(size 1.27 1.27)
					(thickness 0.15)
				)
			)
		)
		(property "Footprint" ""
			(at 36.83 287.02 0)
			(effects
				(font
					(size 1.27 1.27)
					(thickness 0.15)
				)
				(justify left bottom)
				(hide yes)
			)
		)
		(property "Datasheet" ""
			(at 36.83 292.1 0)
			(effects
				(font
					(size 1.27 1.27)
					(thickness 0.15)
				)
				(justify left bottom)
				(hide yes)
			)
		)
		(property "Description" ""
			(at 27.94 279.4 0)
			(effects
				(font
					(size 1.27 1.27)
				)
				(hide yes)
			)
		)
		(property "Author" "Antmicro"
			(at 36.83 287.02 0)
			(effects
				(font
					(size 1.27 1.27)
					(thickness 0.15)
				)
				(justify left bottom)
				(hide yes)
			)
		)
		(property "License" "Apache-2.0"
			(at 36.83 289.56 0)
			(effects
				(font
					(size 1.27 1.27)
					(thickness 0.15)
				)
				(justify left bottom)
				(hide yes)
			)
		)
		(pin "1"
		)
		(instances
			(project "jetson-agx-thor-baseboard"
				(path ""
					(reference "#PWR0607")
					(unit 1)
				)
			)
		)
	)
	(symbol
		(lib_id "antmicroCapacitorsmisc:C_22u_25V_0805")
		(at 185.42 73.66 90)
		(unit 1)
		(exclude_from_sim no)
		(in_bom yes)
		(on_board yes)
		(dnp no)
		(property "Reference" "C300"
			(at 186.944 68.5801 90)
			(effects
				(font
					(size 1.27 1.27)
					(thickness 0.15)
				)
				(justify right)
			)
		)
		(property "Value" "C_22u_25V_0805"
			(at 195.58 53.34 0)
			(effects
				(font
					(size 1.27 1.27)
					(thickness 0.15)
				)
				(justify left bottom)
				(hide yes)
			)
		)
		(property "Footprint" "antmicro-footprints:C_0805_2012Metric"
			(at 198.12 53.34 0)
			(effects
				(font
					(size 1.27 1.27)
					(thickness 0.15)
				)
				(justify left bottom)
				(hide yes)
			)
		)
		(property "Datasheet" "https://product.samsungsem.com/mlcc/CL21A226MAYNNN.do"
			(at 200.66 53.34 0)
			(effects
				(font
					(size 1.27 1.27)
					(thickness 0.15)
				)
				(justify left bottom)
				(hide yes)
			)
		)
		(property "Description" "SMT Multilayer Ceramic Capacitor, 22uF, +/-20%, 25V, X5R, 0805 [2012 Metric]"
			(at 218.44 53.34 0)
			(effects
				(font
					(size 1.27 1.27)
				)
				(justify left bottom)
				(hide yes)
			)
		)
		(property "MPN" "CL21A226MAYNNNE"
			(at 203.2 53.34 0)
			(effects
				(font
					(size 1.27 1.27)
					(thickness 0.15)
				)
				(justify left bottom)
				(hide yes)
			)
		)
		(property "Manufacturer" "Samsung Electro-Mechanics"
			(at 205.74 53.34 0)
			(effects
				(font
					(size 1.27 1.27)
					(thickness 0.15)
				)
				(justify left bottom)
				(hide yes)
			)
		)
		(property "License" "Apache-2.0"
			(at 208.28 53.34 0)
			(effects
				(font
					(size 1.27 1.27)
					(thickness 0.15)
				)
				(justify left bottom)
				(hide yes)
			)
		)
		(property "Author" "Antmicro"
			(at 210.82 53.34 0)
			(effects
				(font
					(size 1.27 1.27)
					(thickness 0.15)
				)
				(justify left bottom)
				(hide yes)
			)
		)
		(property "Val" "22u"
			(at 186.944 71.1201 90)
			(effects
				(font
					(size 1.27 1.27)
					(thickness 0.15)
				)
				(justify right)
			)
		)
		(property "Voltage" "25V"
			(at 186.944 73.66 90)
			(effects
				(font
					(size 1.27 1.27)
				)
				(justify right)
			)
		)
		(property "Dielectric" "X5R"
			(at 215.9 53.34 0)
			(effects
				(font
					(size 1.27 1.27)
				)
				(justify left bottom)
				(hide yes)
			)
		)
		(property "Public" "False"
			(at 218.44 53.34 0)
			(effects
				(font
					(size 1.27 1.27)
				)
				(justify left bottom)
				(hide yes)
			)
		)
		(pin "2"
		)
		(pin "1"
		)
		(instances
			(project "jetson-agx-thor-baseboard"
				(path ""
					(reference "C300")
					(unit 1)
				)
			)
		)
	)
	(symbol
		(lib_id "antmicroCapacitors0402:C_4u7_25V_0402")
		(at 83.82 54.61 90)
		(unit 1)
		(exclude_from_sim no)
		(in_bom yes)
		(on_board yes)
		(dnp no)
		(property "Reference" "C245"
			(at 84.455 50.165 90)
			(effects
				(font
					(size 1.27 1.27)
					(thickness 0.15)
				)
				(justify right)
			)
		)
		(property "Value" "C_4u7_25V_0402"
			(at 93.98 34.29 0)
			(effects
				(font
					(size 1.27 1.27)
					(thickness 0.15)
				)
				(justify left bottom)
				(hide yes)
			)
		)
		(property "Footprint" "antmicro-footprints:C_0402_1005Metric"
			(at 96.52 34.29 0)
			(effects
				(font
					(size 1.27 1.27)
					(thickness 0.15)
				)
				(justify left bottom)
				(hide yes)
			)
		)
		(property "Datasheet" "https://www.murata.com/products/productdetail?partno=GRM155C61E475ME15%23"
			(at 99.06 34.29 0)
			(effects
				(font
					(size 1.27 1.27)
					(thickness 0.15)
				)
				(justify left bottom)
				(hide yes)
			)
		)
		(property "Description" "SMD Multilayer Ceramic Capacitor"
			(at 83.82 54.61 0)
			(effects
				(font
					(size 1.27 1.27)
				)
				(hide yes)
			)
		)
		(property "MPN" "GRM155C61E475ME15J"
			(at 101.6 34.29 0)
			(effects
				(font
					(size 1.27 1.27)
					(thickness 0.15)
				)
				(justify left bottom)
				(hide yes)
			)
		)
		(property "Manufacturer" "Murata"
			(at 104.14 34.29 0)
			(effects
				(font
					(size 1.27 1.27)
					(thickness 0.15)
				)
				(justify left bottom)
				(hide yes)
			)
		)
		(property "License" "Apache-2.0"
			(at 106.68 34.29 0)
			(effects
				(font
					(size 1.27 1.27)
					(thickness 0.15)
				)
				(justify left bottom)
				(hide yes)
			)
		)
		(property "Author" "Antmicro"
			(at 109.22 34.29 0)
			(effects
				(font
					(size 1.27 1.27)
					(thickness 0.15)
				)
				(justify left bottom)
				(hide yes)
			)
		)
		(property "Val" "4u7"
			(at 84.455 53.975 90)
			(effects
				(font
					(size 1.27 1.27)
					(thickness 0.15)
				)
				(justify right)
			)
		)
		(property "Voltage" "25V"
			(at 111.76 34.29 0)
			(effects
				(font
					(size 1.27 1.27)
				)
				(justify left bottom)
				(hide yes)
			)
		)
		(property "Dielectric" "X5S"
			(at 114.3 34.29 0)
			(effects
				(font
					(size 1.27 1.27)
				)
				(justify left bottom)
				(hide yes)
			)
		)
		(pin "2"
		)
		(pin "1"
		)
		(instances
			(project "jetson-agx-thor-baseboard"
				(path ""
					(reference "C245")
					(unit 1)
				)
			)
		)
	)
	(symbol
		(lib_id "antmicropower:GND")
		(at 198.12 234.95 0)
		(unit 1)
		(exclude_from_sim no)
		(in_bom yes)
		(on_board yes)
		(dnp no)
		(property "Reference" "#PWR0525"
			(at 207.01 237.49 0)
			(effects
				(font
					(size 1.27 1.27)
					(thickness 0.15)
				)
				(justify left bottom)
				(hide yes)
			)
		)
		(property "Value" "GND"
			(at 194.818 236.728 0)
			(effects
				(font
					(size 1.27 1.27)
					(thickness 0.15)
				)
			)
		)
		(property "Footprint" ""
			(at 207.01 242.57 0)
			(effects
				(font
					(size 1.27 1.27)
					(thickness 0.15)
				)
				(justify left bottom)
				(hide yes)
			)
		)
		(property "Datasheet" ""
			(at 207.01 247.65 0)
			(effects
				(font
					(size 1.27 1.27)
					(thickness 0.15)
				)
				(justify left bottom)
				(hide yes)
			)
		)
		(property "Description" ""
			(at 198.12 234.95 0)
			(effects
				(font
					(size 1.27 1.27)
				)
				(hide yes)
			)
		)
		(property "Author" "Antmicro"
			(at 207.01 242.57 0)
			(effects
				(font
					(size 1.27 1.27)
					(thickness 0.15)
				)
				(justify left bottom)
				(hide yes)
			)
		)
		(property "License" "Apache-2.0"
			(at 207.01 245.11 0)
			(effects
				(font
					(size 1.27 1.27)
					(thickness 0.15)
				)
				(justify left bottom)
				(hide yes)
			)
		)
		(pin "1"
		)
		(instances
			(project "jetson-agx-thor-baseboard"
				(path ""
					(reference "#PWR0525")
					(unit 1)
				)
			)
		)
	)
	(symbol
		(lib_id "antmicroResistors0402:R_499k_0402")
		(at 55.88 215.9 90)
		(unit 1)
		(exclude_from_sim no)
		(in_bom no)
		(on_board yes)
		(dnp yes)
		(property "Reference" "R36"
			(at 57.15 212.09 90)
			(effects
				(font
					(size 1.27 1.27)
					(thickness 0.15)
				)
				(justify right)
			)
		)
		(property "Value" "R_499k_0402"
			(at 68.58 195.58 0)
			(effects
				(font
					(size 1.27 1.27)
					(thickness 0.15)
				)
				(justify left bottom)
				(hide yes)
			)
		)
		(property "Footprint" "antmicro-footprints:R_0402_1005Metric"
			(at 71.12 195.58 0)
			(effects
				(font
					(size 1.27 1.27)
					(thickness 0.15)
				)
				(justify left bottom)
				(hide yes)
			)
		)
		(property "Datasheet" "https://www.mouser.com/datasheet/2/54/cr-1858361.pdf"
			(at 73.66 195.58 0)
			(effects
				(font
					(size 1.27 1.27)
					(thickness 0.15)
				)
				(justify left bottom)
				(hide yes)
			)
		)
		(property "Description" "SMD Chip Resistor, 499 kohm, ± 1%, 63 mW, 0402 [1005 Metric], Thick Film, General Purpose"
			(at 55.88 215.9 0)
			(effects
				(font
					(size 1.27 1.27)
				)
				(hide yes)
			)
		)
		(property "MPN" "CR0402-FX-4993GLF"
			(at 76.2 195.58 0)
			(effects
				(font
					(size 1.27 1.27)
					(thickness 0.15)
				)
				(justify left bottom)
				(hide yes)
			)
		)
		(property "Manufacturer" "Bourns"
			(at 78.74 195.58 0)
			(effects
				(font
					(size 1.27 1.27)
					(thickness 0.15)
				)
				(justify left bottom)
				(hide yes)
			)
		)
		(property "License" "Apache-2.0"
			(at 81.28 195.58 0)
			(effects
				(font
					(size 1.27 1.27)
					(thickness 0.15)
				)
				(justify left bottom)
				(hide yes)
			)
		)
		(property "Author" "Antmicro"
			(at 83.82 195.58 0)
			(effects
				(font
					(size 1.27 1.27)
					(thickness 0.15)
				)
				(justify left bottom)
				(hide yes)
			)
		)
		(property "Val" "499k"
			(at 57.15 214.63 90)
			(effects
				(font
					(size 1.27 1.27)
					(thickness 0.15)
				)
				(justify right)
			)
		)
		(property "Tolerance" "1%"
			(at 66.04 195.58 0)
			(effects
				(font
					(size 1.27 1.27)
				)
				(justify left bottom)
				(hide yes)
			)
		)
		(pin "2"
		)
		(pin "1"
		)
		(instances
			(project "jetson-agx-thor-baseboard"
				(path ""
					(reference "R36")
					(unit 1)
				)
			)
		)
	)
	(symbol
		(lib_id "antmicropower:GND")
		(at 232.41 232.41 0)
		(unit 1)
		(exclude_from_sim no)
		(in_bom yes)
		(on_board yes)
		(dnp no)
		(property "Reference" "#PWR0153"
			(at 232.41 238.76 0)
			(effects
				(font
					(size 1.27 1.27)
				)
				(justify left bottom)
				(hide yes)
			)
		)
		(property "Value" "GND"
			(at 232.41 236.22 0)
			(effects
				(font
					(size 1.27 1.27)
					(thickness 0.15)
				)
			)
		)
		(property "Footprint" ""
			(at 241.3 240.03 0)
			(effects
				(font
					(size 1.27 1.27)
					(thickness 0.15)
				)
				(justify left bottom)
				(hide yes)
			)
		)
		(property "Datasheet" ""
			(at 241.3 245.11 0)
			(effects
				(font
					(size 1.27 1.27)
					(thickness 0.15)
				)
				(justify left bottom)
				(hide yes)
			)
		)
		(property "Description" ""
			(at 232.41 232.41 0)
			(effects
				(font
					(size 1.27 1.27)
				)
				(hide yes)
			)
		)
		(property "Author" "Antmicro"
			(at 241.3 240.03 0)
			(effects
				(font
					(size 1.27 1.27)
					(thickness 0.15)
				)
				(justify left bottom)
				(hide yes)
			)
		)
		(property "License" "Apache-2.0"
			(at 241.3 242.57 0)
			(effects
				(font
					(size 1.27 1.27)
					(thickness 0.15)
				)
				(justify left bottom)
				(hide yes)
			)
		)
		(pin "1"
		)
		(instances
			(project "jetson-agx-thor-baseboard"
				(path ""
					(reference "#PWR0153")
					(unit 1)
				)
			)
		)
	)
	(symbol
		(lib_id "antmicroDCDCConverters:TPS564247DRLR")
		(at 300.99 116.84 0)
		(unit 1)
		(exclude_from_sim no)
		(in_bom yes)
		(on_board yes)
		(dnp no)
		(fields_autoplaced yes)
		(property "Reference" "U7"
			(at 308.61 110.49 0)
			(effects
				(font
					(size 1.27 1.27)
				)
			)
		)
		(property "Value" "TPS564247DRLR"
			(at 300.99 116.84 0)
			(effects
				(font
					(size 1.27 1.27)
				)
				(hide yes)
			)
		)
		(property "Footprint" "antmicro-footprints:SOT-563"
			(at 300.99 116.84 0)
			(effects
				(font
					(size 1.27 1.27)
				)
				(hide yes)
			)
		)
		(property "Datasheet" "https://www.ti.com/lit/ds/symlink/tps564247.pdf?ts=1713526387938&ref_url=https%253A%252F%252Fwww.mouser.pl%252F"
			(at 300.99 116.84 0)
			(effects
				(font
					(size 1.27 1.27)
				)
				(hide yes)
			)
		)
		(property "Description" "Switching Voltage Regulators 3-V to 16-V input voltage, 4-A FCCM mode, synchronous buck converter in SOT-563 package 6-SOT-5X3 -40 to 125"
			(at 300.99 116.84 0)
			(effects
				(font
					(size 1.27 1.27)
				)
				(hide yes)
			)
		)
		(property "MPN" "TPS564247DRLR"
			(at 308.61 113.03 0)
			(effects
				(font
					(size 1.27 1.27)
				)
			)
		)
		(property "Author" "Antmicro"
			(at 331.47 137.16 0)
			(effects
				(font
					(size 1.27 1.27)
					(thickness 0.15)
				)
				(justify left bottom)
				(hide yes)
			)
		)
		(property "License" "Apache-2.0"
			(at 331.47 139.7 0)
			(effects
				(font
					(size 1.27 1.27)
					(thickness 0.15)
				)
				(justify left bottom)
				(hide yes)
			)
		)
		(property "Manufacturer" "Texas Instruments"
			(at 331.47 134.62 0)
			(effects
				(font
					(size 1.27 1.27)
					(thickness 0.15)
				)
				(justify left bottom)
				(hide yes)
			)
		)
		(pin "1"
		)
		(pin "6"
		)
		(pin "2"
		)
		(pin "3"
		)
		(pin "5"
		)
		(pin "4"
		)
		(instances
			(project "jetson-agx-thor-baseboard"
				(path ""
					(reference "U7")
					(unit 1)
				)
			)
		)
	)
	(symbol
		(lib_id "antmicroResistors0402:R_255k_0402")
		(at 143.51 41.91 90)
		(unit 1)
		(exclude_from_sim no)
		(in_bom yes)
		(on_board yes)
		(dnp no)
		(fields_autoplaced yes)
		(property "Reference" "R69"
			(at 146.05 38.1 90)
			(effects
				(font
					(size 1.27 1.27)
					(thickness 0.15)
				)
				(justify right)
			)
		)
		(property "Value" "R_255k_0402"
			(at 156.21 21.59 0)
			(effects
				(font
					(size 1.27 1.27)
					(thickness 0.15)
				)
				(justify left bottom)
				(hide yes)
			)
		)
		(property "Footprint" "antmicro-footprints:R_0402_1005Metric"
			(at 158.75 21.59 0)
			(effects
				(font
					(size 1.27 1.27)
					(thickness 0.15)
				)
				(justify left bottom)
				(hide yes)
			)
		)
		(property "Datasheet" "https://www.bourns.com/docs/product-datasheets/cr.pdf"
			(at 161.29 21.59 0)
			(effects
				(font
					(size 1.27 1.27)
					(thickness 0.15)
				)
				(justify left bottom)
				(hide yes)
			)
		)
		(property "Description" "SMD Chip Resistor, 255 kohm, ± 1%, 100 mW, 0402 [1005 Metric], Thick Film, Precision"
			(at 173.99 21.59 0)
			(effects
				(font
					(size 1.27 1.27)
				)
				(justify left bottom)
				(hide yes)
			)
		)
		(property "MPN" "CR0402-FX-2553GLF"
			(at 163.83 21.59 0)
			(effects
				(font
					(size 1.27 1.27)
					(thickness 0.15)
				)
				(justify left bottom)
				(hide yes)
			)
		)
		(property "Manufacturer" "Bourns"
			(at 166.37 21.59 0)
			(effects
				(font
					(size 1.27 1.27)
					(thickness 0.15)
				)
				(justify left bottom)
				(hide yes)
			)
		)
		(property "License" "Apache-2.0"
			(at 168.91 21.59 0)
			(effects
				(font
					(size 1.27 1.27)
					(thickness 0.15)
				)
				(justify left bottom)
				(hide yes)
			)
		)
		(property "Author" "Antmicro"
			(at 171.45 21.59 0)
			(effects
				(font
					(size 1.27 1.27)
					(thickness 0.15)
				)
				(justify left bottom)
				(hide yes)
			)
		)
		(property "Val" "255k"
			(at 146.05 40.64 90)
			(effects
				(font
					(size 1.27 1.27)
					(thickness 0.15)
				)
				(justify right)
			)
		)
		(property "Tolerance" "1%"
			(at 153.67 21.59 0)
			(effects
				(font
					(size 1.27 1.27)
				)
				(justify left bottom)
				(hide yes)
			)
		)
		(pin "1"
		)
		(pin "2"
		)
		(instances
			(project "jetson-agx-thor-baseboard"
				(path ""
					(reference "R69")
					(unit 1)
				)
			)
		)
	)
	(symbol
		(lib_id "antmicroCapacitorsmisc:C_22u_25V_0805")
		(at 185.42 43.18 90)
		(unit 1)
		(exclude_from_sim no)
		(in_bom yes)
		(on_board yes)
		(dnp no)
		(property "Reference" "C298"
			(at 186.944 38.1001 90)
			(effects
				(font
					(size 1.27 1.27)
					(thickness 0.15)
				)
				(justify right)
			)
		)
		(property "Value" "C_22u_25V_0805"
			(at 195.58 22.86 0)
			(effects
				(font
					(size 1.27 1.27)
					(thickness 0.15)
				)
				(justify left bottom)
				(hide yes)
			)
		)
		(property "Footprint" "antmicro-footprints:C_0805_2012Metric"
			(at 198.12 22.86 0)
			(effects
				(font
					(size 1.27 1.27)
					(thickness 0.15)
				)
				(justify left bottom)
				(hide yes)
			)
		)
		(property "Datasheet" "https://product.samsungsem.com/mlcc/CL21A226MAYNNN.do"
			(at 200.66 22.86 0)
			(effects
				(font
					(size 1.27 1.27)
					(thickness 0.15)
				)
				(justify left bottom)
				(hide yes)
			)
		)
		(property "Description" "SMT Multilayer Ceramic Capacitor, 22uF, +/-20%, 25V, X5R, 0805 [2012 Metric]"
			(at 218.44 22.86 0)
			(effects
				(font
					(size 1.27 1.27)
				)
				(justify left bottom)
				(hide yes)
			)
		)
		(property "MPN" "CL21A226MAYNNNE"
			(at 203.2 22.86 0)
			(effects
				(font
					(size 1.27 1.27)
					(thickness 0.15)
				)
				(justify left bottom)
				(hide yes)
			)
		)
		(property "Manufacturer" "Samsung Electro-Mechanics"
			(at 205.74 22.86 0)
			(effects
				(font
					(size 1.27 1.27)
					(thickness 0.15)
				)
				(justify left bottom)
				(hide yes)
			)
		)
		(property "License" "Apache-2.0"
			(at 208.28 22.86 0)
			(effects
				(font
					(size 1.27 1.27)
					(thickness 0.15)
				)
				(justify left bottom)
				(hide yes)
			)
		)
		(property "Author" "Antmicro"
			(at 210.82 22.86 0)
			(effects
				(font
					(size 1.27 1.27)
					(thickness 0.15)
				)
				(justify left bottom)
				(hide yes)
			)
		)
		(property "Val" "22u"
			(at 186.944 40.6401 90)
			(effects
				(font
					(size 1.27 1.27)
					(thickness 0.15)
				)
				(justify right)
			)
		)
		(property "Voltage" "25V"
			(at 186.944 43.18 90)
			(effects
				(font
					(size 1.27 1.27)
				)
				(justify right)
			)
		)
		(property "Dielectric" "X5R"
			(at 215.9 22.86 0)
			(effects
				(font
					(size 1.27 1.27)
				)
				(justify left bottom)
				(hide yes)
			)
		)
		(property "Public" "False"
			(at 218.44 22.86 0)
			(effects
				(font
					(size 1.27 1.27)
				)
				(justify left bottom)
				(hide yes)
			)
		)
		(pin "2"
		)
		(pin "1"
		)
		(instances
			(project "jetson-agx-thor-baseboard"
				(path ""
					(reference "C298")
					(unit 1)
				)
			)
		)
	)
	(symbol
		(lib_id "antmicropower:GND")
		(at 48.26 107.95 0)
		(unit 1)
		(exclude_from_sim no)
		(in_bom yes)
		(on_board yes)
		(dnp no)
		(property "Reference" "#PWR0546"
			(at 48.26 114.3 0)
			(effects
				(font
					(size 1.27 1.27)
				)
				(justify left bottom)
				(hide yes)
			)
		)
		(property "Value" "GND"
			(at 48.26 111.76 0)
			(effects
				(font
					(size 1.27 1.27)
					(thickness 0.15)
				)
			)
		)
		(property "Footprint" ""
			(at 57.15 115.57 0)
			(effects
				(font
					(size 1.27 1.27)
					(thickness 0.15)
				)
				(justify left bottom)
				(hide yes)
			)
		)
		(property "Datasheet" ""
			(at 57.15 120.65 0)
			(effects
				(font
					(size 1.27 1.27)
					(thickness 0.15)
				)
				(justify left bottom)
				(hide yes)
			)
		)
		(property "Description" ""
			(at 48.26 107.95 0)
			(effects
				(font
					(size 1.27 1.27)
				)
				(hide yes)
			)
		)
		(property "Author" "Antmicro"
			(at 57.15 115.57 0)
			(effects
				(font
					(size 1.27 1.27)
					(thickness 0.15)
				)
				(justify left bottom)
				(hide yes)
			)
		)
		(property "License" "Apache-2.0"
			(at 57.15 118.11 0)
			(effects
				(font
					(size 1.27 1.27)
					(thickness 0.15)
				)
				(justify left bottom)
				(hide yes)
			)
		)
		(pin "1"
		)
		(instances
			(project "jetson-agx-thor-baseboard"
				(path ""
					(reference "#PWR0546")
					(unit 1)
				)
			)
		)
	)
	(symbol
		(lib_id "antmicropower:GND")
		(at 161.29 176.53 0)
		(unit 1)
		(exclude_from_sim no)
		(in_bom yes)
		(on_board yes)
		(dnp no)
		(property "Reference" "#PWR0757"
			(at 161.29 182.88 0)
			(effects
				(font
					(size 1.27 1.27)
				)
				(justify left bottom)
				(hide yes)
			)
		)
		(property "Value" "GND"
			(at 161.29 180.34 0)
			(effects
				(font
					(size 1.27 1.27)
					(thickness 0.15)
				)
			)
		)
		(property "Footprint" ""
			(at 170.18 184.15 0)
			(effects
				(font
					(size 1.27 1.27)
					(thickness 0.15)
				)
				(justify left bottom)
				(hide yes)
			)
		)
		(property "Datasheet" ""
			(at 170.18 189.23 0)
			(effects
				(font
					(size 1.27 1.27)
					(thickness 0.15)
				)
				(justify left bottom)
				(hide yes)
			)
		)
		(property "Description" ""
			(at 161.29 176.53 0)
			(effects
				(font
					(size 1.27 1.27)
				)
				(hide yes)
			)
		)
		(property "Author" "Antmicro"
			(at 170.18 184.15 0)
			(effects
				(font
					(size 1.27 1.27)
					(thickness 0.15)
				)
				(justify left bottom)
				(hide yes)
			)
		)
		(property "License" "Apache-2.0"
			(at 170.18 186.69 0)
			(effects
				(font
					(size 1.27 1.27)
					(thickness 0.15)
				)
				(justify left bottom)
				(hide yes)
			)
		)
		(pin "1"
		)
		(instances
			(project "jetson-agx-thor-baseboard"
				(path ""
					(reference "#PWR0757")
					(unit 1)
				)
			)
		)
	)
	(symbol
		(lib_id "antmicropower:GND")
		(at 233.68 114.3 0)
		(unit 1)
		(exclude_from_sim no)
		(in_bom yes)
		(on_board yes)
		(dnp no)
		(property "Reference" "#PWR0574"
			(at 233.68 120.65 0)
			(effects
				(font
					(size 1.27 1.27)
				)
				(justify left bottom)
				(hide yes)
			)
		)
		(property "Value" "GND"
			(at 233.68 118.11 0)
			(effects
				(font
					(size 1.27 1.27)
					(thickness 0.15)
				)
			)
		)
		(property "Footprint" ""
			(at 242.57 121.92 0)
			(effects
				(font
					(size 1.27 1.27)
					(thickness 0.15)
				)
				(justify left bottom)
				(hide yes)
			)
		)
		(property "Datasheet" ""
			(at 242.57 127 0)
			(effects
				(font
					(size 1.27 1.27)
					(thickness 0.15)
				)
				(justify left bottom)
				(hide yes)
			)
		)
		(property "Description" ""
			(at 233.68 114.3 0)
			(effects
				(font
					(size 1.27 1.27)
				)
				(hide yes)
			)
		)
		(property "Author" "Antmicro"
			(at 242.57 121.92 0)
			(effects
				(font
					(size 1.27 1.27)
					(thickness 0.15)
				)
				(justify left bottom)
				(hide yes)
			)
		)
		(property "License" "Apache-2.0"
			(at 242.57 124.46 0)
			(effects
				(font
					(size 1.27 1.27)
					(thickness 0.15)
				)
				(justify left bottom)
				(hide yes)
			)
		)
		(pin "1"
		)
		(instances
			(project "jetson-agx-thor-baseboard"
				(path ""
					(reference "#PWR0574")
					(unit 1)
				)
			)
		)
	)
	(symbol
		(lib_id "antmicroFixedInductors:L_3u3_6A_Bourns-SRP7028A")
		(at 134.62 167.64 0)
		(unit 1)
		(exclude_from_sim no)
		(in_bom yes)
		(on_board yes)
		(dnp no)
		(fields_autoplaced yes)
		(property "Reference" "L8"
			(at 137.16 162.56 0)
			(effects
				(font
					(size 1.27 1.27)
					(thickness 0.15)
				)
			)
		)
		(property "Value" "L_3u3_6A_Bourns-SRP7028A"
			(at 148.59 172.72 0)
			(effects
				(font
					(size 1.27 1.27)
					(thickness 0.15)
				)
				(justify left bottom)
				(hide yes)
			)
		)
		(property "Footprint" "antmicro-footprints:L_Bourns-SRP7028A"
			(at 148.59 175.26 0)
			(effects
				(font
					(size 1.27 1.27)
					(thickness 0.15)
				)
				(justify left bottom)
				(hide yes)
			)
		)
		(property "Datasheet" "https://www.bourns.com/docs/Product-Datasheets/SRP7028A.pdf"
			(at 148.59 177.8 0)
			(effects
				(font
					(size 1.27 1.27)
					(thickness 0.15)
				)
				(justify left bottom)
				(hide yes)
			)
		)
		(property "Description" "Power Inductor (SMD), 3.3 µH, 6 A, Shielded, 12 A, SRP7028A Series"
			(at 148.59 198.12 0)
			(effects
				(font
					(size 1.27 1.27)
				)
				(justify left bottom)
				(hide yes)
			)
		)
		(property "Val" "3u3/6A"
			(at 137.16 165.1 0)
			(effects
				(font
					(size 1.27 1.27)
					(thickness 0.15)
				)
			)
		)
		(property "Manufacturer" "Bourns"
			(at 148.59 180.34 0)
			(effects
				(font
					(size 1.27 1.27)
					(thickness 0.15)
				)
				(justify left bottom)
				(hide yes)
			)
		)
		(property "MPN" "SRP7028A-3R3M"
			(at 148.59 182.88 0)
			(effects
				(font
					(size 1.27 1.27)
					(thickness 0.15)
				)
				(justify left bottom)
				(hide yes)
			)
		)
		(property "ISat" "12 A"
			(at 148.59 184.15 0)
			(effects
				(font
					(size 1.27 1.27)
				)
				(justify left)
				(hide yes)
			)
		)
		(property "IMax" "6 A"
			(at 148.59 187.96 0)
			(effects
				(font
					(size 1.27 1.27)
					(thickness 0.15)
				)
				(justify left bottom)
				(hide yes)
			)
		)
		(property "Size" "7.3x6.6x2.8"
			(at 148.59 190.5 0)
			(effects
				(font
					(size 1.27 1.27)
					(thickness 0.15)
				)
				(justify left bottom)
				(hide yes)
			)
		)
		(property "Author" "Antmicro"
			(at 148.59 193.04 0)
			(effects
				(font
					(size 1.27 1.27)
					(thickness 0.15)
				)
				(justify left bottom)
				(hide yes)
			)
		)
		(property "License" "Apache-2.0"
			(at 148.59 195.58 0)
			(effects
				(font
					(size 1.27 1.27)
					(thickness 0.15)
				)
				(justify left bottom)
				(hide yes)
			)
		)
		(pin "1"
		)
		(pin "2"
		)
		(instances
			(project ""
				(path ""
					(reference "L8")
					(unit 1)
				)
			)
		)
	)
	(symbol
		(lib_id "antmicroPowerMeasurement:INA219AIDCNR")
		(at 199.39 219.71 0)
		(unit 1)
		(exclude_from_sim no)
		(in_bom yes)
		(on_board yes)
		(dnp no)
		(property "Reference" "U50"
			(at 207.01 214.63 0)
			(effects
				(font
					(size 1.27 1.27)
				)
			)
		)
		(property "Value" "INA219AIDCNR"
			(at 199.39 219.71 0)
			(effects
				(font
					(size 1.27 1.27)
				)
				(hide yes)
			)
		)
		(property "Footprint" "antmicro-footprints:SOT-23-8"
			(at 199.39 219.71 0)
			(effects
				(font
					(size 1.27 1.27)
				)
				(hide yes)
			)
		)
		(property "Datasheet" "https://www.ti.com/lit/ds/symlink/ina219.pdf?ts=1713856455637&ref_url=https%253A%252F%252Fwww.mouser.es%252F"
			(at 199.39 219.71 0)
			(effects
				(font
					(size 1.27 1.27)
				)
				(hide yes)
			)
		)
		(property "Description" "Zerø-Drift, Bidirectional Current/Power Monitor With I2C Interface"
			(at 199.39 219.71 0)
			(effects
				(font
					(size 1.27 1.27)
				)
				(hide yes)
			)
		)
		(property "Manufacturer" "Texas Instruments"
			(at 199.39 219.71 0)
			(effects
				(font
					(size 1.27 1.27)
				)
				(hide yes)
			)
		)
		(property "MPN" "INA219AIDCNR"
			(at 207.01 217.17 0)
			(effects
				(font
					(size 1.27 1.27)
				)
			)
		)
		(property "Author" "Antmicro"
			(at 224.79 240.03 0)
			(effects
				(font
					(size 1.27 1.27)
					(thickness 0.15)
				)
				(justify left bottom)
				(hide yes)
			)
		)
		(property "License" "Apache-2.0"
			(at 224.79 242.57 0)
			(effects
				(font
					(size 1.27 1.27)
					(thickness 0.15)
				)
				(justify left bottom)
				(hide yes)
			)
		)
		(pin "1"
		)
		(pin "2"
		)
		(pin "5"
		)
		(pin "6"
		)
		(pin "8"
		)
		(pin "3"
		)
		(pin "7"
		)
		(pin "4"
		)
		(instances
			(project "jetson-agx-thor-baseboard"
				(path ""
					(reference "U50")
					(unit 1)
				)
			)
		)
	)
	(symbol
		(lib_id "antmicroCapacitors0402:C_100n_0402")
		(at 48.26 34.29 270)
		(unit 1)
		(exclude_from_sim no)
		(in_bom yes)
		(on_board yes)
		(dnp no)
		(property "Reference" "C243"
			(at 48.895 34.925 90)
			(effects
				(font
					(size 1.27 1.27)
				)
				(justify left)
			)
		)
		(property "Value" "C_100n_0402"
			(at 38.1 54.61 0)
			(effects
				(font
					(size 1.27 1.27)
					(thickness 0.15)
				)
				(justify left bottom)
				(hide yes)
			)
		)
		(property "Footprint" "antmicro-footprints:C_0402_1005Metric"
			(at 35.56 54.61 0)
			(effects
				(font
					(size 1.27 1.27)
					(thickness 0.15)
				)
				(justify left bottom)
				(hide yes)
			)
		)
		(property "Datasheet" "https://www.murata.com/products/productdetail?partno=GRM155R61H104KE14%23"
			(at 33.02 54.61 0)
			(effects
				(font
					(size 1.27 1.27)
					(thickness 0.15)
				)
				(justify left bottom)
				(hide yes)
			)
		)
		(property "Description" "SMD Multilayer Ceramic Capacitor, 0.1 µF, 50 V, 0402 [1005 Metric], ± 10%, X5R, GRM Series"
			(at 48.26 34.29 0)
			(effects
				(font
					(size 1.27 1.27)
				)
				(hide yes)
			)
		)
		(property "Manufacturer" "Murata"
			(at 27.94 54.61 0)
			(effects
				(font
					(size 1.27 1.27)
					(thickness 0.15)
				)
				(justify left bottom)
				(hide yes)
			)
		)
		(property "MPN" "GRM155R61H104KE14D"
			(at 30.48 54.61 0)
			(effects
				(font
					(size 1.27 1.27)
					(thickness 0.15)
				)
				(justify left bottom)
				(hide yes)
			)
		)
		(property "Val" "100n"
			(at 48.895 38.735 90)
			(effects
				(font
					(size 1.27 1.27)
					(thickness 0.15)
				)
				(justify left)
			)
		)
		(property "License" "Apache-2.0"
			(at 25.4 54.61 0)
			(effects
				(font
					(size 1.27 1.27)
					(thickness 0.15)
				)
				(justify left bottom)
				(hide yes)
			)
		)
		(property "Author" "Antmicro"
			(at 22.86 54.61 0)
			(effects
				(font
					(size 1.27 1.27)
					(thickness 0.15)
				)
				(justify left bottom)
				(hide yes)
			)
		)
		(property "Voltage" "50V"
			(at 20.32 54.61 0)
			(effects
				(font
					(size 1.27 1.27)
				)
				(justify left bottom)
				(hide yes)
			)
		)
		(property "Dielectric" "X5R"
			(at 17.78 54.61 0)
			(effects
				(font
					(size 1.27 1.27)
				)
				(justify left bottom)
				(hide yes)
			)
		)
		(pin "1"
		)
		(pin "2"
		)
		(instances
			(project "jetson-agx-thor-baseboard"
				(path ""
					(reference "C243")
					(unit 1)
				)
			)
		)
	)
	(symbol
		(lib_id "antmicropower:GND")
		(at 55.88 121.92 0)
		(unit 1)
		(exclude_from_sim no)
		(in_bom yes)
		(on_board yes)
		(dnp no)
		(property "Reference" "#PWR0547"
			(at 55.88 128.27 0)
			(effects
				(font
					(size 1.27 1.27)
				)
				(justify left bottom)
				(hide yes)
			)
		)
		(property "Value" "GND"
			(at 55.88 125.73 0)
			(effects
				(font
					(size 1.27 1.27)
					(thickness 0.15)
				)
			)
		)
		(property "Footprint" ""
			(at 64.77 129.54 0)
			(effects
				(font
					(size 1.27 1.27)
					(thickness 0.15)
				)
				(justify left bottom)
				(hide yes)
			)
		)
		(property "Datasheet" ""
			(at 64.77 134.62 0)
			(effects
				(font
					(size 1.27 1.27)
					(thickness 0.15)
				)
				(justify left bottom)
				(hide yes)
			)
		)
		(property "Description" ""
			(at 55.88 121.92 0)
			(effects
				(font
					(size 1.27 1.27)
				)
				(hide yes)
			)
		)
		(property "Author" "Antmicro"
			(at 64.77 129.54 0)
			(effects
				(font
					(size 1.27 1.27)
					(thickness 0.15)
				)
				(justify left bottom)
				(hide yes)
			)
		)
		(property "License" "Apache-2.0"
			(at 64.77 132.08 0)
			(effects
				(font
					(size 1.27 1.27)
					(thickness 0.15)
				)
				(justify left bottom)
				(hide yes)
			)
		)
		(pin "1"
		)
		(instances
			(project "jetson-agx-thor-baseboard"
				(path ""
					(reference "#PWR0547")
					(unit 1)
				)
			)
		)
	)
	(symbol
		(lib_id "antmicropower:GND")
		(at 177.8 44.45 0)
		(unit 1)
		(exclude_from_sim no)
		(in_bom yes)
		(on_board yes)
		(dnp no)
		(property "Reference" "#PWR0537"
			(at 177.8 50.8 0)
			(effects
				(font
					(size 1.27 1.27)
				)
				(justify left bottom)
				(hide yes)
			)
		)
		(property "Value" "GND"
			(at 177.8 48.26 0)
			(effects
				(font
					(size 1.27 1.27)
					(thickness 0.15)
				)
			)
		)
		(property "Footprint" ""
			(at 186.69 52.07 0)
			(effects
				(font
					(size 1.27 1.27)
					(thickness 0.15)
				)
				(justify left bottom)
				(hide yes)
			)
		)
		(property "Datasheet" ""
			(at 186.69 57.15 0)
			(effects
				(font
					(size 1.27 1.27)
					(thickness 0.15)
				)
				(justify left bottom)
				(hide yes)
			)
		)
		(property "Description" ""
			(at 177.8 44.45 0)
			(effects
				(font
					(size 1.27 1.27)
				)
				(hide yes)
			)
		)
		(property "Author" "Antmicro"
			(at 186.69 52.07 0)
			(effects
				(font
					(size 1.27 1.27)
					(thickness 0.15)
				)
				(justify left bottom)
				(hide yes)
			)
		)
		(property "License" "Apache-2.0"
			(at 186.69 54.61 0)
			(effects
				(font
					(size 1.27 1.27)
					(thickness 0.15)
				)
				(justify left bottom)
				(hide yes)
			)
		)
		(pin "1"
		)
		(instances
			(project "jetson-agx-thor-baseboard"
				(path ""
					(reference "#PWR0537")
					(unit 1)
				)
			)
		)
	)
	(symbol
		(lib_id "antmicropower:GND")
		(at 34.29 41.91 0)
		(unit 1)
		(exclude_from_sim no)
		(in_bom yes)
		(on_board yes)
		(dnp no)
		(property "Reference" "#PWR083"
			(at 34.29 48.26 0)
			(effects
				(font
					(size 1.27 1.27)
				)
				(justify left bottom)
				(hide yes)
			)
		)
		(property "Value" "GND"
			(at 34.29 45.72 0)
			(effects
				(font
					(size 1.27 1.27)
					(thickness 0.15)
				)
			)
		)
		(property "Footprint" ""
			(at 43.18 49.53 0)
			(effects
				(font
					(size 1.27 1.27)
					(thickness 0.15)
				)
				(justify left bottom)
				(hide yes)
			)
		)
		(property "Datasheet" ""
			(at 43.18 54.61 0)
			(effects
				(font
					(size 1.27 1.27)
					(thickness 0.15)
				)
				(justify left bottom)
				(hide yes)
			)
		)
		(property "Description" ""
			(at 34.29 41.91 0)
			(effects
				(font
					(size 1.27 1.27)
				)
				(hide yes)
			)
		)
		(property "Author" "Antmicro"
			(at 43.18 49.53 0)
			(effects
				(font
					(size 1.27 1.27)
					(thickness 0.15)
				)
				(justify left bottom)
				(hide yes)
			)
		)
		(property "License" "Apache-2.0"
			(at 43.18 52.07 0)
			(effects
				(font
					(size 1.27 1.27)
					(thickness 0.15)
				)
				(justify left bottom)
				(hide yes)
			)
		)
		(pin "1"
		)
		(instances
			(project "jetson-agx-thor-baseboard"
				(path ""
					(reference "#PWR083")
					(unit 1)
				)
			)
		)
	)
	(symbol
		(lib_id "antmicropower:GND")
		(at 185.42 140.97 0)
		(unit 1)
		(exclude_from_sim no)
		(in_bom yes)
		(on_board yes)
		(dnp no)
		(property "Reference" "#PWR0592"
			(at 185.42 147.32 0)
			(effects
				(font
					(size 1.27 1.27)
				)
				(justify left bottom)
				(hide yes)
			)
		)
		(property "Value" "GND"
			(at 185.42 144.78 0)
			(effects
				(font
					(size 1.27 1.27)
					(thickness 0.15)
				)
			)
		)
		(property "Footprint" ""
			(at 194.31 148.59 0)
			(effects
				(font
					(size 1.27 1.27)
					(thickness 0.15)
				)
				(justify left bottom)
				(hide yes)
			)
		)
		(property "Datasheet" ""
			(at 194.31 153.67 0)
			(effects
				(font
					(size 1.27 1.27)
					(thickness 0.15)
				)
				(justify left bottom)
				(hide yes)
			)
		)
		(property "Description" ""
			(at 185.42 140.97 0)
			(effects
				(font
					(size 1.27 1.27)
				)
				(hide yes)
			)
		)
		(property "Author" "Antmicro"
			(at 194.31 148.59 0)
			(effects
				(font
					(size 1.27 1.27)
					(thickness 0.15)
				)
				(justify left bottom)
				(hide yes)
			)
		)
		(property "License" "Apache-2.0"
			(at 194.31 151.13 0)
			(effects
				(font
					(size 1.27 1.27)
					(thickness 0.15)
				)
				(justify left bottom)
				(hide yes)
			)
		)
		(pin "1"
		)
		(instances
			(project "jetson-agx-thor-baseboard"
				(path ""
					(reference "#PWR0592")
					(unit 1)
				)
			)
		)
	)
	(symbol
		(lib_id "antmicroCapacitorsmisc:C_22u_25V_0805")
		(at 154.94 109.22 90)
		(unit 1)
		(exclude_from_sim no)
		(in_bom yes)
		(on_board yes)
		(dnp no)
		(property "Reference" "C283"
			(at 156.718 104.1401 90)
			(effects
				(font
					(size 1.27 1.27)
					(thickness 0.15)
				)
				(justify right)
			)
		)
		(property "Value" "C_22u_25V_0805"
			(at 165.1 88.9 0)
			(effects
				(font
					(size 1.27 1.27)
					(thickness 0.15)
				)
				(justify left bottom)
				(hide yes)
			)
		)
		(property "Footprint" "antmicro-footprints:C_0805_2012Metric"
			(at 167.64 88.9 0)
			(effects
				(font
					(size 1.27 1.27)
					(thickness 0.15)
				)
				(justify left bottom)
				(hide yes)
			)
		)
		(property "Datasheet" "https://product.samsungsem.com/mlcc/CL21A226MAYNNN.do"
			(at 170.18 88.9 0)
			(effects
				(font
					(size 1.27 1.27)
					(thickness 0.15)
				)
				(justify left bottom)
				(hide yes)
			)
		)
		(property "Description" "SMT Multilayer Ceramic Capacitor, 22uF, +/-20%, 25V, X5R, 0805 [2012 Metric]"
			(at 187.96 88.9 0)
			(effects
				(font
					(size 1.27 1.27)
				)
				(justify left bottom)
				(hide yes)
			)
		)
		(property "MPN" "CL21A226MAYNNNE"
			(at 172.72 88.9 0)
			(effects
				(font
					(size 1.27 1.27)
					(thickness 0.15)
				)
				(justify left bottom)
				(hide yes)
			)
		)
		(property "Manufacturer" "Samsung Electro-Mechanics"
			(at 175.26 88.9 0)
			(effects
				(font
					(size 1.27 1.27)
					(thickness 0.15)
				)
				(justify left bottom)
				(hide yes)
			)
		)
		(property "License" "Apache-2.0"
			(at 177.8 88.9 0)
			(effects
				(font
					(size 1.27 1.27)
					(thickness 0.15)
				)
				(justify left bottom)
				(hide yes)
			)
		)
		(property "Author" "Antmicro"
			(at 180.34 88.9 0)
			(effects
				(font
					(size 1.27 1.27)
					(thickness 0.15)
				)
				(justify left bottom)
				(hide yes)
			)
		)
		(property "Val" "22u"
			(at 156.718 106.6801 90)
			(effects
				(font
					(size 1.27 1.27)
					(thickness 0.15)
				)
				(justify right)
			)
		)
		(property "Voltage" "25V"
			(at 156.718 109.22 90)
			(effects
				(font
					(size 1.27 1.27)
				)
				(justify right)
			)
		)
		(property "Dielectric" "X5R"
			(at 185.42 88.9 0)
			(effects
				(font
					(size 1.27 1.27)
				)
				(justify left bottom)
				(hide yes)
			)
		)
		(property "Public" "False"
			(at 187.96 88.9 0)
			(effects
				(font
					(size 1.27 1.27)
				)
				(justify left bottom)
				(hide yes)
			)
		)
		(pin "2"
		)
		(pin "1"
		)
		(instances
			(project "jetson-agx-thor-baseboard"
				(path ""
					(reference "C283")
					(unit 1)
				)
			)
		)
	)
	(symbol
		(lib_id "antmicroCapacitorsmisc:C_22u_25V_0805")
		(at 162.56 43.18 90)
		(unit 1)
		(exclude_from_sim no)
		(in_bom yes)
		(on_board yes)
		(dnp no)
		(property "Reference" "C248"
			(at 164.084 38.1001 90)
			(effects
				(font
					(size 1.27 1.27)
					(thickness 0.15)
				)
				(justify right)
			)
		)
		(property "Value" "C_22u_25V_0805"
			(at 172.72 22.86 0)
			(effects
				(font
					(size 1.27 1.27)
					(thickness 0.15)
				)
				(justify left bottom)
				(hide yes)
			)
		)
		(property "Footprint" "antmicro-footprints:C_0805_2012Metric"
			(at 175.26 22.86 0)
			(effects
				(font
					(size 1.27 1.27)
					(thickness 0.15)
				)
				(justify left bottom)
				(hide yes)
			)
		)
		(property "Datasheet" "https://product.samsungsem.com/mlcc/CL21A226MAYNNN.do"
			(at 177.8 22.86 0)
			(effects
				(font
					(size 1.27 1.27)
					(thickness 0.15)
				)
				(justify left bottom)
				(hide yes)
			)
		)
		(property "Description" "SMT Multilayer Ceramic Capacitor, 22uF, +/-20%, 25V, X5R, 0805 [2012 Metric]"
			(at 195.58 22.86 0)
			(effects
				(font
					(size 1.27 1.27)
				)
				(justify left bottom)
				(hide yes)
			)
		)
		(property "MPN" "CL21A226MAYNNNE"
			(at 180.34 22.86 0)
			(effects
				(font
					(size 1.27 1.27)
					(thickness 0.15)
				)
				(justify left bottom)
				(hide yes)
			)
		)
		(property "Manufacturer" "Samsung Electro-Mechanics"
			(at 182.88 22.86 0)
			(effects
				(font
					(size 1.27 1.27)
					(thickness 0.15)
				)
				(justify left bottom)
				(hide yes)
			)
		)
		(property "License" "Apache-2.0"
			(at 185.42 22.86 0)
			(effects
				(font
					(size 1.27 1.27)
					(thickness 0.15)
				)
				(justify left bottom)
				(hide yes)
			)
		)
		(property "Author" "Antmicro"
			(at 187.96 22.86 0)
			(effects
				(font
					(size 1.27 1.27)
					(thickness 0.15)
				)
				(justify left bottom)
				(hide yes)
			)
		)
		(property "Val" "22u"
			(at 164.084 40.6401 90)
			(effects
				(font
					(size 1.27 1.27)
					(thickness 0.15)
				)
				(justify right)
			)
		)
		(property "Voltage" "25V"
			(at 164.084 43.18 90)
			(effects
				(font
					(size 1.27 1.27)
				)
				(justify right)
			)
		)
		(property "Dielectric" "X5R"
			(at 193.04 22.86 0)
			(effects
				(font
					(size 1.27 1.27)
				)
				(justify left bottom)
				(hide yes)
			)
		)
		(property "Public" "False"
			(at 195.58 22.86 0)
			(effects
				(font
					(size 1.27 1.27)
				)
				(justify left bottom)
				(hide yes)
			)
		)
		(pin "2"
		)
		(pin "1"
		)
		(instances
			(project "jetson-agx-thor-baseboard"
				(path ""
					(reference "C248")
					(unit 1)
				)
			)
		)
	)
	(symbol
		(lib_id "antmicroResistors0402:R_191k_0402")
		(at 363.22 44.45 90)
		(unit 1)
		(exclude_from_sim no)
		(in_bom yes)
		(on_board yes)
		(dnp no)
		(fields_autoplaced yes)
		(property "Reference" "R326"
			(at 365.76 40.64 90)
			(effects
				(font
					(size 1.27 1.27)
					(thickness 0.15)
				)
				(justify right)
			)
		)
		(property "Value" "R_191k_0402"
			(at 375.92 24.13 0)
			(effects
				(font
					(size 1.27 1.27)
					(thickness 0.15)
				)
				(justify left bottom)
				(hide yes)
			)
		)
		(property "Footprint" "antmicro-footprints:R_0402_1005Metric"
			(at 378.46 24.13 0)
			(effects
				(font
					(size 1.27 1.27)
					(thickness 0.15)
				)
				(justify left bottom)
				(hide yes)
			)
		)
		(property "Datasheet" "https://www.bourns.com/docs/product-datasheets/cr.pdf"
			(at 381 24.13 0)
			(effects
				(font
					(size 1.27 1.27)
					(thickness 0.15)
				)
				(justify left bottom)
				(hide yes)
			)
		)
		(property "Description" "SMD Chip Resistor, 191 kohm, ± 1%, 100 mW, 0402 [1005 Metric], Thick Film, Precision"
			(at 393.7 24.13 0)
			(effects
				(font
					(size 1.27 1.27)
				)
				(justify left bottom)
				(hide yes)
			)
		)
		(property "MPN" "CR0402-FX-1913GLF"
			(at 383.54 24.13 0)
			(effects
				(font
					(size 1.27 1.27)
					(thickness 0.15)
				)
				(justify left bottom)
				(hide yes)
			)
		)
		(property "Manufacturer" "Bourns"
			(at 386.08 24.13 0)
			(effects
				(font
					(size 1.27 1.27)
					(thickness 0.15)
				)
				(justify left bottom)
				(hide yes)
			)
		)
		(property "License" "Apache-2.0"
			(at 388.62 24.13 0)
			(effects
				(font
					(size 1.27 1.27)
					(thickness 0.15)
				)
				(justify left bottom)
				(hide yes)
			)
		)
		(property "Author" "Antmicro"
			(at 391.16 24.13 0)
			(effects
				(font
					(size 1.27 1.27)
					(thickness 0.15)
				)
				(justify left bottom)
				(hide yes)
			)
		)
		(property "Val" "191k"
			(at 365.76 43.18 90)
			(effects
				(font
					(size 1.27 1.27)
					(thickness 0.15)
				)
				(justify right)
			)
		)
		(property "Tolerance" "1%"
			(at 373.38 24.13 0)
			(effects
				(font
					(size 1.27 1.27)
				)
				(justify left bottom)
				(hide yes)
			)
		)
		(pin "1"
		)
		(pin "2"
		)
		(instances
			(project "jetson-agx-thor-baseboard"
				(path ""
					(reference "R326")
					(unit 1)
				)
			)
		)
	)
	(symbol
		(lib_id "antmicroCapacitorsmisc:C_22u_25V_0805")
		(at 185.42 58.42 90)
		(unit 1)
		(exclude_from_sim no)
		(in_bom yes)
		(on_board yes)
		(dnp no)
		(property "Reference" "C299"
			(at 186.944 53.3401 90)
			(effects
				(font
					(size 1.27 1.27)
					(thickness 0.15)
				)
				(justify right)
			)
		)
		(property "Value" "C_22u_25V_0805"
			(at 195.58 38.1 0)
			(effects
				(font
					(size 1.27 1.27)
					(thickness 0.15)
				)
				(justify left bottom)
				(hide yes)
			)
		)
		(property "Footprint" "antmicro-footprints:C_0805_2012Metric"
			(at 198.12 38.1 0)
			(effects
				(font
					(size 1.27 1.27)
					(thickness 0.15)
				)
				(justify left bottom)
				(hide yes)
			)
		)
		(property "Datasheet" "https://product.samsungsem.com/mlcc/CL21A226MAYNNN.do"
			(at 200.66 38.1 0)
			(effects
				(font
					(size 1.27 1.27)
					(thickness 0.15)
				)
				(justify left bottom)
				(hide yes)
			)
		)
		(property "Description" "SMT Multilayer Ceramic Capacitor, 22uF, +/-20%, 25V, X5R, 0805 [2012 Metric]"
			(at 218.44 38.1 0)
			(effects
				(font
					(size 1.27 1.27)
				)
				(justify left bottom)
				(hide yes)
			)
		)
		(property "MPN" "CL21A226MAYNNNE"
			(at 203.2 38.1 0)
			(effects
				(font
					(size 1.27 1.27)
					(thickness 0.15)
				)
				(justify left bottom)
				(hide yes)
			)
		)
		(property "Manufacturer" "Samsung Electro-Mechanics"
			(at 205.74 38.1 0)
			(effects
				(font
					(size 1.27 1.27)
					(thickness 0.15)
				)
				(justify left bottom)
				(hide yes)
			)
		)
		(property "License" "Apache-2.0"
			(at 208.28 38.1 0)
			(effects
				(font
					(size 1.27 1.27)
					(thickness 0.15)
				)
				(justify left bottom)
				(hide yes)
			)
		)
		(property "Author" "Antmicro"
			(at 210.82 38.1 0)
			(effects
				(font
					(size 1.27 1.27)
					(thickness 0.15)
				)
				(justify left bottom)
				(hide yes)
			)
		)
		(property "Val" "22u"
			(at 186.944 55.8801 90)
			(effects
				(font
					(size 1.27 1.27)
					(thickness 0.15)
				)
				(justify right)
			)
		)
		(property "Voltage" "25V"
			(at 186.944 58.42 90)
			(effects
				(font
					(size 1.27 1.27)
				)
				(justify right)
			)
		)
		(property "Dielectric" "X5R"
			(at 215.9 38.1 0)
			(effects
				(font
					(size 1.27 1.27)
				)
				(justify left bottom)
				(hide yes)
			)
		)
		(property "Public" "False"
			(at 218.44 38.1 0)
			(effects
				(font
					(size 1.27 1.27)
				)
				(justify left bottom)
				(hide yes)
			)
		)
		(pin "2"
		)
		(pin "1"
		)
		(instances
			(project "jetson-agx-thor-baseboard"
				(path ""
					(reference "C299")
					(unit 1)
				)
			)
		)
	)
	(symbol
		(lib_id "antmicropower:+1V8")
		(at 374.65 181.61 0)
		(unit 1)
		(exclude_from_sim no)
		(in_bom yes)
		(on_board yes)
		(dnp no)
		(property "Reference" "#PWR059"
			(at 389.89 184.15 0)
			(effects
				(font
					(size 1.27 1.27)
					(thickness 0.15)
				)
				(justify left bottom)
				(hide yes)
			)
		)
		(property "Value" "+1V15"
			(at 374.65 177.8 0)
			(effects
				(font
					(size 1.27 1.27)
					(thickness 0.15)
				)
			)
		)
		(property "Footprint" ""
			(at 389.89 189.23 0)
			(effects
				(font
					(size 1.27 1.27)
					(thickness 0.15)
				)
				(justify left bottom)
				(hide yes)
			)
		)
		(property "Datasheet" ""
			(at 389.89 191.77 0)
			(effects
				(font
					(size 1.27 1.27)
					(thickness 0.15)
				)
				(justify left bottom)
				(hide yes)
			)
		)
		(property "Description" ""
			(at 374.65 181.61 0)
			(effects
				(font
					(size 1.27 1.27)
				)
				(hide yes)
			)
		)
		(property "Author" "Antmicro"
			(at 389.89 186.69 0)
			(effects
				(font
					(size 1.27 1.27)
					(thickness 0.15)
				)
				(justify left bottom)
				(hide yes)
			)
		)
		(property "License" "Apache-2.0"
			(at 389.89 189.23 0)
			(effects
				(font
					(size 1.27 1.27)
					(thickness 0.15)
				)
				(justify left bottom)
				(hide yes)
			)
		)
		(pin "1"
		)
		(instances
			(project "jetson-agx-thor-baseboard"
				(path ""
					(reference "#PWR059")
					(unit 1)
				)
			)
		)
	)
	(symbol
		(lib_id "antmicroCapacitors0402:C_100n_0402")
		(at 349.25 33.02 180)
		(unit 1)
		(exclude_from_sim no)
		(in_bom yes)
		(on_board yes)
		(dnp no)
		(fields_autoplaced yes)
		(property "Reference" "C221"
			(at 346.7036 26.67 0)
			(effects
				(font
					(size 1.27 1.27)
				)
			)
		)
		(property "Value" "C_100n_0402"
			(at 328.93 22.86 0)
			(effects
				(font
					(size 1.27 1.27)
					(thickness 0.15)
				)
				(justify left bottom)
				(hide yes)
			)
		)
		(property "Footprint" "antmicro-footprints:C_0402_1005Metric"
			(at 328.93 20.32 0)
			(effects
				(font
					(size 1.27 1.27)
					(thickness 0.15)
				)
				(justify left bottom)
				(hide yes)
			)
		)
		(property "Datasheet" "https://www.murata.com/products/productdetail?partno=GRM155R61H104KE14%23"
			(at 328.93 17.78 0)
			(effects
				(font
					(size 1.27 1.27)
					(thickness 0.15)
				)
				(justify left bottom)
				(hide yes)
			)
		)
		(property "Description" "SMD Multilayer Ceramic Capacitor, 0.1 µF, 50 V, 0402 [1005 Metric], ± 10%, X5R, GRM Series"
			(at 349.25 33.02 0)
			(effects
				(font
					(size 1.27 1.27)
				)
				(hide yes)
			)
		)
		(property "Manufacturer" "Murata"
			(at 328.93 12.7 0)
			(effects
				(font
					(size 1.27 1.27)
					(thickness 0.15)
				)
				(justify left bottom)
				(hide yes)
			)
		)
		(property "MPN" "GRM155R61H104KE14D"
			(at 328.93 15.24 0)
			(effects
				(font
					(size 1.27 1.27)
					(thickness 0.15)
				)
				(justify left bottom)
				(hide yes)
			)
		)
		(property "Val" "100n"
			(at 346.7036 29.21 0)
			(effects
				(font
					(size 1.27 1.27)
					(thickness 0.15)
				)
			)
		)
		(property "License" "Apache-2.0"
			(at 328.93 10.16 0)
			(effects
				(font
					(size 1.27 1.27)
					(thickness 0.15)
				)
				(justify left bottom)
				(hide yes)
			)
		)
		(property "Author" "Antmicro"
			(at 328.93 7.62 0)
			(effects
				(font
					(size 1.27 1.27)
					(thickness 0.15)
				)
				(justify left bottom)
				(hide yes)
			)
		)
		(property "Voltage" "50V"
			(at 328.93 5.08 0)
			(effects
				(font
					(size 1.27 1.27)
				)
				(justify left bottom)
				(hide yes)
			)
		)
		(property "Dielectric" "X5R"
			(at 328.93 2.54 0)
			(effects
				(font
					(size 1.27 1.27)
				)
				(justify left bottom)
				(hide yes)
			)
		)
		(pin "1"
		)
		(pin "2"
		)
		(instances
			(project "jetson-agx-thor-baseboard"
				(path ""
					(reference "C221")
					(unit 1)
				)
			)
		)
	)
	(symbol
		(lib_id "antmicroResistors0402:R_45k3_0402")
		(at 143.51 265.43 90)
		(unit 1)
		(exclude_from_sim no)
		(in_bom yes)
		(on_board yes)
		(dnp no)
		(property "Reference" "R54"
			(at 144.78 261.62 90)
			(effects
				(font
					(size 1.27 1.27)
					(thickness 0.15)
				)
				(justify right)
			)
		)
		(property "Value" "R_45k3_0402"
			(at 156.21 245.11 0)
			(effects
				(font
					(size 1.27 1.27)
					(thickness 0.15)
				)
				(justify left bottom)
				(hide yes)
			)
		)
		(property "Footprint" "antmicro-footprints:R_0402_1005Metric"
			(at 158.75 245.11 0)
			(effects
				(font
					(size 1.27 1.27)
					(thickness 0.15)
				)
				(justify left bottom)
				(hide yes)
			)
		)
		(property "Datasheet" "https://www.bourns.com/docs/product-datasheets/cr.pdf"
			(at 161.29 245.11 0)
			(effects
				(font
					(size 1.27 1.27)
					(thickness 0.15)
				)
				(justify left bottom)
				(hide yes)
			)
		)
		(property "Description" "SMD Chip Resistor"
			(at 143.51 265.43 0)
			(effects
				(font
					(size 1.27 1.27)
				)
				(hide yes)
			)
		)
		(property "MPN" "CR0402-FX-4532GLF"
			(at 163.83 245.11 0)
			(effects
				(font
					(size 1.27 1.27)
					(thickness 0.15)
				)
				(justify left bottom)
				(hide yes)
			)
		)
		(property "Manufacturer" "Bourns"
			(at 166.37 245.11 0)
			(effects
				(font
					(size 1.27 1.27)
					(thickness 0.15)
				)
				(justify left bottom)
				(hide yes)
			)
		)
		(property "License" "Apache-2.0"
			(at 168.91 245.11 0)
			(effects
				(font
					(size 1.27 1.27)
					(thickness 0.15)
				)
				(justify left bottom)
				(hide yes)
			)
		)
		(property "Author" "Antmicro"
			(at 171.45 245.11 0)
			(effects
				(font
					(size 1.27 1.27)
					(thickness 0.15)
				)
				(justify left bottom)
				(hide yes)
			)
		)
		(property "Val" "45k3"
			(at 144.78 264.16 90)
			(effects
				(font
					(size 1.27 1.27)
					(thickness 0.15)
				)
				(justify right)
			)
		)
		(property "Tolerance" "1%"
			(at 153.67 245.11 0)
			(effects
				(font
					(size 1.27 1.27)
				)
				(justify left bottom)
				(hide yes)
			)
		)
		(pin "2"
		)
		(pin "1"
		)
		(instances
			(project "jetson-agx-thor-baseboard"
				(path ""
					(reference "R54")
					(unit 1)
				)
			)
		)
	)
	(symbol
		(lib_id "antmicropower:GND")
		(at 143.51 121.92 0)
		(unit 1)
		(exclude_from_sim no)
		(in_bom yes)
		(on_board yes)
		(dnp no)
		(property "Reference" "#PWR0553"
			(at 143.51 128.27 0)
			(effects
				(font
					(size 1.27 1.27)
				)
				(justify left bottom)
				(hide yes)
			)
		)
		(property "Value" "GND"
			(at 143.51 125.73 0)
			(effects
				(font
					(size 1.27 1.27)
					(thickness 0.15)
				)
			)
		)
		(property "Footprint" ""
			(at 152.4 129.54 0)
			(effects
				(font
					(size 1.27 1.27)
					(thickness 0.15)
				)
				(justify left bottom)
				(hide yes)
			)
		)
		(property "Datasheet" ""
			(at 152.4 134.62 0)
			(effects
				(font
					(size 1.27 1.27)
					(thickness 0.15)
				)
				(justify left bottom)
				(hide yes)
			)
		)
		(property "Description" ""
			(at 143.51 121.92 0)
			(effects
				(font
					(size 1.27 1.27)
				)
				(hide yes)
			)
		)
		(property "Author" "Antmicro"
			(at 152.4 129.54 0)
			(effects
				(font
					(size 1.27 1.27)
					(thickness 0.15)
				)
				(justify left bottom)
				(hide yes)
			)
		)
		(property "License" "Apache-2.0"
			(at 152.4 132.08 0)
			(effects
				(font
					(size 1.27 1.27)
					(thickness 0.15)
				)
				(justify left bottom)
				(hide yes)
			)
		)
		(pin "1"
		)
		(instances
			(project "jetson-agx-thor-baseboard"
				(path ""
					(reference "#PWR0553")
					(unit 1)
				)
			)
		)
	)
	(symbol
		(lib_id "antmicroResistors0402:R_51k_0402")
		(at 285.75 57.15 90)
		(unit 1)
		(exclude_from_sim no)
		(in_bom yes)
		(on_board yes)
		(dnp no)
		(property "Reference" "R15"
			(at 287.02 53.34 90)
			(effects
				(font
					(size 1.27 1.27)
					(thickness 0.15)
				)
				(justify right)
			)
		)
		(property "Value" "R_51k_0402"
			(at 298.45 36.83 0)
			(effects
				(font
					(size 1.27 1.27)
					(thickness 0.15)
				)
				(justify left bottom)
				(hide yes)
			)
		)
		(property "Footprint" "antmicro-footprints:R_0402_1005Metric"
			(at 300.99 36.83 0)
			(effects
				(font
					(size 1.27 1.27)
					(thickness 0.15)
				)
				(justify left bottom)
				(hide yes)
			)
		)
		(property "Datasheet" "https://www.bourns.com/docs/product-datasheets/cr.pdf"
			(at 303.53 36.83 0)
			(effects
				(font
					(size 1.27 1.27)
					(thickness 0.15)
				)
				(justify left bottom)
				(hide yes)
			)
		)
		(property "Description" "SMD Chip Resistor, 51 kohm, ± 1%, 63 mW, 0402 [1005 Metric], Thick Film, General Purpose"
			(at 285.75 57.15 0)
			(effects
				(font
					(size 1.27 1.27)
				)
				(hide yes)
			)
		)
		(property "MPN" "CR0402-FX-5102GLF"
			(at 306.07 36.83 0)
			(effects
				(font
					(size 1.27 1.27)
					(thickness 0.15)
				)
				(justify left bottom)
				(hide yes)
			)
		)
		(property "Manufacturer" "Bourns"
			(at 308.61 36.83 0)
			(effects
				(font
					(size 1.27 1.27)
					(thickness 0.15)
				)
				(justify left bottom)
				(hide yes)
			)
		)
		(property "License" "Apache-2.0"
			(at 311.15 36.83 0)
			(effects
				(font
					(size 1.27 1.27)
					(thickness 0.15)
				)
				(justify left bottom)
				(hide yes)
			)
		)
		(property "Author" "Antmicro"
			(at 313.69 36.83 0)
			(effects
				(font
					(size 1.27 1.27)
					(thickness 0.15)
				)
				(justify left bottom)
				(hide yes)
			)
		)
		(property "Val" "51k"
			(at 287.02 55.88 90)
			(effects
				(font
					(size 1.27 1.27)
					(thickness 0.15)
				)
				(justify right)
			)
		)
		(property "Tolerance" "1%"
			(at 295.91 36.83 0)
			(effects
				(font
					(size 1.27 1.27)
				)
				(justify left bottom)
				(hide yes)
			)
		)
		(pin "2"
		)
		(pin "1"
		)
		(instances
			(project "jetson-agx-thor-baseboard"
				(path ""
					(reference "R15")
					(unit 1)
				)
			)
		)
	)
	(symbol
		(lib_id "antmicroCapacitorsmisc:C_22u_25V_0805")
		(at 170.18 43.18 90)
		(unit 1)
		(exclude_from_sim no)
		(in_bom yes)
		(on_board yes)
		(dnp no)
		(property "Reference" "C249"
			(at 171.958 38.1001 90)
			(effects
				(font
					(size 1.27 1.27)
					(thickness 0.15)
				)
				(justify right)
			)
		)
		(property "Value" "C_22u_25V_0805"
			(at 180.34 22.86 0)
			(effects
				(font
					(size 1.27 1.27)
					(thickness 0.15)
				)
				(justify left bottom)
				(hide yes)
			)
		)
		(property "Footprint" "antmicro-footprints:C_0805_2012Metric"
			(at 182.88 22.86 0)
			(effects
				(font
					(size 1.27 1.27)
					(thickness 0.15)
				)
				(justify left bottom)
				(hide yes)
			)
		)
		(property "Datasheet" "https://product.samsungsem.com/mlcc/CL21A226MAYNNN.do"
			(at 185.42 22.86 0)
			(effects
				(font
					(size 1.27 1.27)
					(thickness 0.15)
				)
				(justify left bottom)
				(hide yes)
			)
		)
		(property "Description" "SMT Multilayer Ceramic Capacitor, 22uF, +/-20%, 25V, X5R, 0805 [2012 Metric]"
			(at 203.2 22.86 0)
			(effects
				(font
					(size 1.27 1.27)
				)
				(justify left bottom)
				(hide yes)
			)
		)
		(property "MPN" "CL21A226MAYNNNE"
			(at 187.96 22.86 0)
			(effects
				(font
					(size 1.27 1.27)
					(thickness 0.15)
				)
				(justify left bottom)
				(hide yes)
			)
		)
		(property "Manufacturer" "Samsung Electro-Mechanics"
			(at 190.5 22.86 0)
			(effects
				(font
					(size 1.27 1.27)
					(thickness 0.15)
				)
				(justify left bottom)
				(hide yes)
			)
		)
		(property "License" "Apache-2.0"
			(at 193.04 22.86 0)
			(effects
				(font
					(size 1.27 1.27)
					(thickness 0.15)
				)
				(justify left bottom)
				(hide yes)
			)
		)
		(property "Author" "Antmicro"
			(at 195.58 22.86 0)
			(effects
				(font
					(size 1.27 1.27)
					(thickness 0.15)
				)
				(justify left bottom)
				(hide yes)
			)
		)
		(property "Val" "22u"
			(at 171.958 40.6401 90)
			(effects
				(font
					(size 1.27 1.27)
					(thickness 0.15)
				)
				(justify right)
			)
		)
		(property "Voltage" "25V"
			(at 171.958 43.18 90)
			(effects
				(font
					(size 1.27 1.27)
				)
				(justify right)
			)
		)
		(property "Dielectric" "X5R"
			(at 200.66 22.86 0)
			(effects
				(font
					(size 1.27 1.27)
				)
				(justify left bottom)
				(hide yes)
			)
		)
		(property "Public" "False"
			(at 203.2 22.86 0)
			(effects
				(font
					(size 1.27 1.27)
				)
				(justify left bottom)
				(hide yes)
			)
		)
		(pin "2"
		)
		(pin "1"
		)
		(instances
			(project "jetson-agx-thor-baseboard"
				(path ""
					(reference "C249")
					(unit 1)
				)
			)
		)
	)
	(symbol
		(lib_id "antmicropower:GND")
		(at 170.18 110.49 0)
		(unit 1)
		(exclude_from_sim no)
		(in_bom yes)
		(on_board yes)
		(dnp no)
		(property "Reference" "#PWR0558"
			(at 170.18 116.84 0)
			(effects
				(font
					(size 1.27 1.27)
				)
				(justify left bottom)
				(hide yes)
			)
		)
		(property "Value" "GND"
			(at 170.18 114.3 0)
			(effects
				(font
					(size 1.27 1.27)
					(thickness 0.15)
				)
			)
		)
		(property "Footprint" ""
			(at 179.07 118.11 0)
			(effects
				(font
					(size 1.27 1.27)
					(thickness 0.15)
				)
				(justify left bottom)
				(hide yes)
			)
		)
		(property "Datasheet" ""
			(at 179.07 123.19 0)
			(effects
				(font
					(size 1.27 1.27)
					(thickness 0.15)
				)
				(justify left bottom)
				(hide yes)
			)
		)
		(property "Description" ""
			(at 170.18 110.49 0)
			(effects
				(font
					(size 1.27 1.27)
				)
				(hide yes)
			)
		)
		(property "Author" "Antmicro"
			(at 179.07 118.11 0)
			(effects
				(font
					(size 1.27 1.27)
					(thickness 0.15)
				)
				(justify left bottom)
				(hide yes)
			)
		)
		(property "License" "Apache-2.0"
			(at 179.07 120.65 0)
			(effects
				(font
					(size 1.27 1.27)
					(thickness 0.15)
				)
				(justify left bottom)
				(hide yes)
			)
		)
		(pin "1"
		)
		(instances
			(project "jetson-agx-thor-baseboard"
				(path ""
					(reference "#PWR0558")
					(unit 1)
				)
			)
		)
	)
	(symbol
		(lib_id "antmicropower:GND")
		(at 185.42 125.73 0)
		(unit 1)
		(exclude_from_sim no)
		(in_bom yes)
		(on_board yes)
		(dnp no)
		(property "Reference" "#PWR0587"
			(at 185.42 132.08 0)
			(effects
				(font
					(size 1.27 1.27)
				)
				(justify left bottom)
				(hide yes)
			)
		)
		(property "Value" "GND"
			(at 185.42 129.54 0)
			(effects
				(font
					(size 1.27 1.27)
					(thickness 0.15)
				)
			)
		)
		(property "Footprint" ""
			(at 194.31 133.35 0)
			(effects
				(font
					(size 1.27 1.27)
					(thickness 0.15)
				)
				(justify left bottom)
				(hide yes)
			)
		)
		(property "Datasheet" ""
			(at 194.31 138.43 0)
			(effects
				(font
					(size 1.27 1.27)
					(thickness 0.15)
				)
				(justify left bottom)
				(hide yes)
			)
		)
		(property "Description" ""
			(at 185.42 125.73 0)
			(effects
				(font
					(size 1.27 1.27)
				)
				(hide yes)
			)
		)
		(property "Author" "Antmicro"
			(at 194.31 133.35 0)
			(effects
				(font
					(size 1.27 1.27)
					(thickness 0.15)
				)
				(justify left bottom)
				(hide yes)
			)
		)
		(property "License" "Apache-2.0"
			(at 194.31 135.89 0)
			(effects
				(font
					(size 1.27 1.27)
					(thickness 0.15)
				)
				(justify left bottom)
				(hide yes)
			)
		)
		(pin "1"
		)
		(instances
			(project "jetson-agx-thor-baseboard"
				(path ""
					(reference "#PWR0587")
					(unit 1)
				)
			)
		)
	)
	(symbol
		(lib_id "antmicropower:GND")
		(at 397.51 58.42 0)
		(unit 1)
		(exclude_from_sim no)
		(in_bom yes)
		(on_board yes)
		(dnp no)
		(property "Reference" "#PWR089"
			(at 397.51 64.77 0)
			(effects
				(font
					(size 1.27 1.27)
				)
				(justify left bottom)
				(hide yes)
			)
		)
		(property "Value" "GND"
			(at 397.51 62.23 0)
			(effects
				(font
					(size 1.27 1.27)
					(thickness 0.15)
				)
			)
		)
		(property "Footprint" ""
			(at 406.4 66.04 0)
			(effects
				(font
					(size 1.27 1.27)
					(thickness 0.15)
				)
				(justify left bottom)
				(hide yes)
			)
		)
		(property "Datasheet" ""
			(at 406.4 71.12 0)
			(effects
				(font
					(size 1.27 1.27)
					(thickness 0.15)
				)
				(justify left bottom)
				(hide yes)
			)
		)
		(property "Description" ""
			(at 397.51 58.42 0)
			(effects
				(font
					(size 1.27 1.27)
				)
				(hide yes)
			)
		)
		(property "Author" "Antmicro"
			(at 406.4 66.04 0)
			(effects
				(font
					(size 1.27 1.27)
					(thickness 0.15)
				)
				(justify left bottom)
				(hide yes)
			)
		)
		(property "License" "Apache-2.0"
			(at 406.4 68.58 0)
			(effects
				(font
					(size 1.27 1.27)
					(thickness 0.15)
				)
				(justify left bottom)
				(hide yes)
			)
		)
		(pin "1"
		)
		(instances
			(project "jetson-agx-thor-baseboard"
				(path ""
					(reference "#PWR089")
					(unit 1)
				)
			)
		)
	)
	(symbol
		(lib_id "antmicroCapacitorsmisc:C_22u_25V_0805")
		(at 43.18 165.1 90)
		(unit 1)
		(exclude_from_sim no)
		(in_bom yes)
		(on_board yes)
		(dnp no)
		(property "Reference" "C373"
			(at 43.815 160.655 90)
			(effects
				(font
					(size 1.27 1.27)
					(thickness 0.15)
				)
				(justify right)
			)
		)
		(property "Value" "C_22u_25V_0805"
			(at 53.34 144.78 0)
			(effects
				(font
					(size 1.27 1.27)
					(thickness 0.15)
				)
				(justify left bottom)
				(hide yes)
			)
		)
		(property "Footprint" "antmicro-footprints:C_0805_2012Metric"
			(at 55.88 144.78 0)
			(effects
				(font
					(size 1.27 1.27)
					(thickness 0.15)
				)
				(justify left bottom)
				(hide yes)
			)
		)
		(property "Datasheet" "https://product.samsungsem.com/mlcc/CL21A226MAYNNN.do"
			(at 58.42 144.78 0)
			(effects
				(font
					(size 1.27 1.27)
					(thickness 0.15)
				)
				(justify left bottom)
				(hide yes)
			)
		)
		(property "Description" "SMT Multilayer Ceramic Capacitor, 22uF, +/-20%, 25V, X5R, 0805 [2012 Metric]"
			(at 43.18 165.1 0)
			(effects
				(font
					(size 1.27 1.27)
				)
				(hide yes)
			)
		)
		(property "MPN" "CL21A226MAYNNNE"
			(at 60.96 144.78 0)
			(effects
				(font
					(size 1.27 1.27)
					(thickness 0.15)
				)
				(justify left bottom)
				(hide yes)
			)
		)
		(property "Manufacturer" "Samsung Electro-Mechanics"
			(at 63.5 144.78 0)
			(effects
				(font
					(size 1.27 1.27)
					(thickness 0.15)
				)
				(justify left bottom)
				(hide yes)
			)
		)
		(property "License" "Apache-2.0"
			(at 66.04 144.78 0)
			(effects
				(font
					(size 1.27 1.27)
					(thickness 0.15)
				)
				(justify left bottom)
				(hide yes)
			)
		)
		(property "Author" "Antmicro"
			(at 68.58 144.78 0)
			(effects
				(font
					(size 1.27 1.27)
					(thickness 0.15)
				)
				(justify left bottom)
				(hide yes)
			)
		)
		(property "Val" "22u"
			(at 43.815 164.465 90)
			(effects
				(font
					(size 1.27 1.27)
					(thickness 0.15)
				)
				(justify right)
			)
		)
		(property "Voltage" "25V"
			(at 43.815 167.005 90)
			(effects
				(font
					(size 1.27 1.27)
				)
				(justify right)
			)
		)
		(property "Dielectric" "X5R"
			(at 73.66 144.78 0)
			(effects
				(font
					(size 1.27 1.27)
				)
				(justify left bottom)
				(hide yes)
			)
		)
		(property "Public" "False"
			(at 76.2 144.78 0)
			(effects
				(font
					(size 1.27 1.27)
				)
				(justify left bottom)
				(hide yes)
			)
		)
		(pin "1"
		)
		(pin "2"
		)
		(instances
			(project "jetson-agx-thor-baseboard"
				(path ""
					(reference "C373")
					(unit 1)
				)
			)
		)
	)
	(symbol
		(lib_id "antmicropower:GND")
		(at 346.71 130.81 0)
		(unit 1)
		(exclude_from_sim no)
		(in_bom yes)
		(on_board yes)
		(dnp no)
		(property "Reference" "#PWR0624"
			(at 355.6 133.35 0)
			(effects
				(font
					(size 1.27 1.27)
					(thickness 0.15)
				)
				(justify left bottom)
				(hide yes)
			)
		)
		(property "Value" "GND"
			(at 346.71 134.62 0)
			(effects
				(font
					(size 1.27 1.27)
					(thickness 0.15)
				)
			)
		)
		(property "Footprint" ""
			(at 355.6 138.43 0)
			(effects
				(font
					(size 1.27 1.27)
					(thickness 0.15)
				)
				(justify left bottom)
				(hide yes)
			)
		)
		(property "Datasheet" ""
			(at 355.6 143.51 0)
			(effects
				(font
					(size 1.27 1.27)
					(thickness 0.15)
				)
				(justify left bottom)
				(hide yes)
			)
		)
		(property "Description" ""
			(at 346.71 130.81 0)
			(effects
				(font
					(size 1.27 1.27)
				)
				(hide yes)
			)
		)
		(property "Author" "Antmicro"
			(at 355.6 138.43 0)
			(effects
				(font
					(size 1.27 1.27)
					(thickness 0.15)
				)
				(justify left bottom)
				(hide yes)
			)
		)
		(property "License" "Apache-2.0"
			(at 355.6 140.97 0)
			(effects
				(font
					(size 1.27 1.27)
					(thickness 0.15)
				)
				(justify left bottom)
				(hide yes)
			)
		)
		(pin "1"
		)
		(instances
			(project "jetson-agx-thor-baseboard"
				(path ""
					(reference "#PWR0624")
					(unit 1)
				)
			)
		)
	)
	(symbol
		(lib_id "antmicroCapacitorsmisc:C_22u_25V_0805")
		(at 374.65 62.23 90)
		(unit 1)
		(exclude_from_sim no)
		(in_bom yes)
		(on_board yes)
		(dnp no)
		(property "Reference" "C306"
			(at 377.19 57.1435 90)
			(effects
				(font
					(size 1.27 1.27)
				)
				(justify right)
			)
		)
		(property "Value" "C_22u_25V_0805"
			(at 384.81 41.91 0)
			(effects
				(font
					(size 1.27 1.27)
					(thickness 0.15)
				)
				(justify left bottom)
				(hide yes)
			)
		)
		(property "Footprint" "antmicro-footprints:C_0805_2012Metric"
			(at 387.35 41.91 0)
			(effects
				(font
					(size 1.27 1.27)
					(thickness 0.15)
				)
				(justify left bottom)
				(hide yes)
			)
		)
		(property "Datasheet" "https://product.samsungsem.com/mlcc/CL21A226MAYNNN.do"
			(at 389.89 41.91 0)
			(effects
				(font
					(size 1.27 1.27)
					(thickness 0.15)
				)
				(justify left bottom)
				(hide yes)
			)
		)
		(property "Description" "SMT Multilayer Ceramic Capacitor, 22uF, +/-20%, 25V, X5R, 0805 [2012 Metric]"
			(at 374.65 62.23 0)
			(effects
				(font
					(size 1.27 1.27)
				)
				(hide yes)
			)
		)
		(property "Manufacturer" "Samsung Electro-Mechanics"
			(at 394.97 41.91 0)
			(effects
				(font
					(size 1.27 1.27)
					(thickness 0.15)
				)
				(justify left bottom)
				(hide yes)
			)
		)
		(property "MPN" "CL21A226MAYNNNE"
			(at 392.43 41.91 0)
			(effects
				(font
					(size 1.27 1.27)
					(thickness 0.15)
				)
				(justify left bottom)
				(hide yes)
			)
		)
		(property "Val" "22u"
			(at 377.19 59.6836 90)
			(effects
				(font
					(size 1.27 1.27)
					(thickness 0.15)
				)
				(justify right)
			)
		)
		(property "License" "Apache-2.0"
			(at 397.51 41.91 0)
			(effects
				(font
					(size 1.27 1.27)
					(thickness 0.15)
				)
				(justify left bottom)
				(hide yes)
			)
		)
		(property "Author" "Antmicro"
			(at 400.05 41.91 0)
			(effects
				(font
					(size 1.27 1.27)
					(thickness 0.15)
				)
				(justify left bottom)
				(hide yes)
			)
		)
		(property "Voltage" "25V"
			(at 377.19 62.2235 90)
			(effects
				(font
					(size 1.27 1.27)
				)
				(justify right)
			)
		)
		(property "Dielectric" "X5R"
			(at 405.13 41.91 0)
			(effects
				(font
					(size 1.27 1.27)
				)
				(justify left bottom)
				(hide yes)
			)
		)
		(property "Public" "False"
			(at 407.67 41.91 0)
			(effects
				(font
					(size 1.27 1.27)
				)
				(justify left bottom)
				(hide yes)
			)
		)
		(pin "1"
		)
		(pin "2"
		)
		(instances
			(project "jetson-agx-thor-baseboard"
				(path ""
					(reference "C306")
					(unit 1)
				)
			)
		)
	)
	(symbol
		(lib_id "antmicropower:GND")
		(at 355.6 130.81 0)
		(unit 1)
		(exclude_from_sim no)
		(in_bom yes)
		(on_board yes)
		(dnp no)
		(property "Reference" "#PWR0625"
			(at 364.49 133.35 0)
			(effects
				(font
					(size 1.27 1.27)
					(thickness 0.15)
				)
				(justify left bottom)
				(hide yes)
			)
		)
		(property "Value" "GND"
			(at 355.6 134.62 0)
			(effects
				(font
					(size 1.27 1.27)
					(thickness 0.15)
				)
			)
		)
		(property "Footprint" ""
			(at 364.49 138.43 0)
			(effects
				(font
					(size 1.27 1.27)
					(thickness 0.15)
				)
				(justify left bottom)
				(hide yes)
			)
		)
		(property "Datasheet" ""
			(at 364.49 143.51 0)
			(effects
				(font
					(size 1.27 1.27)
					(thickness 0.15)
				)
				(justify left bottom)
				(hide yes)
			)
		)
		(property "Description" ""
			(at 355.6 130.81 0)
			(effects
				(font
					(size 1.27 1.27)
				)
				(hide yes)
			)
		)
		(property "Author" "Antmicro"
			(at 364.49 138.43 0)
			(effects
				(font
					(size 1.27 1.27)
					(thickness 0.15)
				)
				(justify left bottom)
				(hide yes)
			)
		)
		(property "License" "Apache-2.0"
			(at 364.49 140.97 0)
			(effects
				(font
					(size 1.27 1.27)
					(thickness 0.15)
				)
				(justify left bottom)
				(hide yes)
			)
		)
		(pin "1"
		)
		(instances
			(project "jetson-agx-thor-baseboard"
				(path ""
					(reference "#PWR0625")
					(unit 1)
				)
			)
		)
	)
	(symbol
		(lib_id "antmicropower:GND")
		(at 40.64 279.4 0)
		(unit 1)
		(exclude_from_sim no)
		(in_bom yes)
		(on_board yes)
		(dnp no)
		(property "Reference" "#PWR097"
			(at 40.64 285.75 0)
			(effects
				(font
					(size 1.27 1.27)
				)
				(justify left bottom)
				(hide yes)
			)
		)
		(property "Value" "GND"
			(at 40.64 283.21 0)
			(effects
				(font
					(size 1.27 1.27)
					(thickness 0.15)
				)
			)
		)
		(property "Footprint" ""
			(at 49.53 287.02 0)
			(effects
				(font
					(size 1.27 1.27)
					(thickness 0.15)
				)
				(justify left bottom)
				(hide yes)
			)
		)
		(property "Datasheet" ""
			(at 49.53 292.1 0)
			(effects
				(font
					(size 1.27 1.27)
					(thickness 0.15)
				)
				(justify left bottom)
				(hide yes)
			)
		)
		(property "Description" ""
			(at 40.64 279.4 0)
			(effects
				(font
					(size 1.27 1.27)
				)
				(hide yes)
			)
		)
		(property "Author" "Antmicro"
			(at 49.53 287.02 0)
			(effects
				(font
					(size 1.27 1.27)
					(thickness 0.15)
				)
				(justify left bottom)
				(hide yes)
			)
		)
		(property "License" "Apache-2.0"
			(at 49.53 289.56 0)
			(effects
				(font
					(size 1.27 1.27)
					(thickness 0.15)
				)
				(justify left bottom)
				(hide yes)
			)
		)
		(pin "1"
		)
		(instances
			(project "jetson-agx-thor-baseboard"
				(path ""
					(reference "#PWR097")
					(unit 1)
				)
			)
		)
	)
	(symbol
		(lib_id "antmicropower:GND")
		(at 64.77 232.41 0)
		(unit 1)
		(exclude_from_sim no)
		(in_bom yes)
		(on_board yes)
		(dnp no)
		(property "Reference" "#PWR0105"
			(at 64.77 238.76 0)
			(effects
				(font
					(size 1.27 1.27)
				)
				(justify left bottom)
				(hide yes)
			)
		)
		(property "Value" "GND"
			(at 64.77 236.22 0)
			(effects
				(font
					(size 1.27 1.27)
					(thickness 0.15)
				)
			)
		)
		(property "Footprint" ""
			(at 73.66 240.03 0)
			(effects
				(font
					(size 1.27 1.27)
					(thickness 0.15)
				)
				(justify left bottom)
				(hide yes)
			)
		)
		(property "Datasheet" ""
			(at 73.66 245.11 0)
			(effects
				(font
					(size 1.27 1.27)
					(thickness 0.15)
				)
				(justify left bottom)
				(hide yes)
			)
		)
		(property "Description" ""
			(at 64.77 232.41 0)
			(effects
				(font
					(size 1.27 1.27)
				)
				(hide yes)
			)
		)
		(property "Author" "Antmicro"
			(at 73.66 240.03 0)
			(effects
				(font
					(size 1.27 1.27)
					(thickness 0.15)
				)
				(justify left bottom)
				(hide yes)
			)
		)
		(property "License" "Apache-2.0"
			(at 73.66 242.57 0)
			(effects
				(font
					(size 1.27 1.27)
					(thickness 0.15)
				)
				(justify left bottom)
				(hide yes)
			)
		)
		(pin "1"
		)
		(instances
			(project "jetson-agx-thor-baseboard"
				(path ""
					(reference "#PWR0105")
					(unit 1)
				)
			)
		)
	)
	(symbol
		(lib_id "antmicroCapacitors0603:C_22u_16V_0603")
		(at 355.6 187.96 270)
		(unit 1)
		(exclude_from_sim no)
		(in_bom yes)
		(on_board yes)
		(dnp no)
		(fields_autoplaced yes)
		(property "Reference" "C224"
			(at 358.14 189.2363 90)
			(effects
				(font
					(size 1.27 1.27)
					(thickness 0.15)
				)
				(justify left)
			)
		)
		(property "Value" "C_22u_16V_0603"
			(at 353.06 201.93 0)
			(effects
				(font
					(size 1.27 1.27)
					(thickness 0.15)
				)
				(justify left bottom)
				(hide yes)
			)
		)
		(property "Footprint" "antmicro-footprints:C_0603_1608Metric_EIA"
			(at 347.98 201.93 0)
			(effects
				(font
					(size 1.27 1.27)
					(thickness 0.15)
				)
				(justify left bottom)
				(hide yes)
			)
		)
		(property "Datasheet" "https://product.samsungsem.com/mlcc/CL10A226MO7JZN.do"
			(at 345.44 201.93 0)
			(effects
				(font
					(size 1.27 1.27)
					(thickness 0.15)
				)
				(justify left bottom)
				(hide yes)
			)
		)
		(property "Description" "SMD Multilayer Ceramic Capacitor"
			(at 355.6 187.96 0)
			(effects
				(font
					(size 1.27 1.27)
				)
				(hide yes)
			)
		)
		(property "Val" "22u"
			(at 358.14 191.7763 90)
			(effects
				(font
					(size 1.27 1.27)
					(thickness 0.15)
				)
				(justify left)
			)
		)
		(property "MPN" "CL10A226MO7JZNC"
			(at 342.9 201.93 0)
			(effects
				(font
					(size 1.27 1.27)
					(thickness 0.15)
				)
				(justify left bottom)
				(hide yes)
			)
		)
		(property "Manufacturer" "Samsung Electro-Mechanics"
			(at 340.36 201.93 0)
			(effects
				(font
					(size 1.27 1.27)
					(thickness 0.15)
				)
				(justify left bottom)
				(hide yes)
			)
		)
		(property "License" "Apache-2.0"
			(at 337.82 201.93 0)
			(effects
				(font
					(size 1.27 1.27)
					(thickness 0.15)
				)
				(justify left bottom)
				(hide yes)
			)
		)
		(property "Author" "Antmicro"
			(at 335.28 201.93 0)
			(effects
				(font
					(size 1.27 1.27)
					(thickness 0.15)
				)
				(justify left bottom)
				(hide yes)
			)
		)
		(property "Voltage" "16V"
			(at 358.14 192.5065 90)
			(effects
				(font
					(size 1.27 1.27)
				)
				(justify left)
				(hide yes)
			)
		)
		(property "Dielectric" ""
			(at 330.2 201.93 0)
			(effects
				(font
					(size 1.27 1.27)
				)
				(justify left bottom)
				(hide yes)
			)
		)
		(pin "2"
		)
		(pin "1"
		)
		(instances
			(project "jetson-agx-thor-baseboard"
				(path ""
					(reference "C224")
					(unit 1)
				)
			)
		)
	)
	(symbol
		(lib_id "antmicroResistors0402:R_499k_0402")
		(at 55.88 262.89 90)
		(unit 1)
		(exclude_from_sim no)
		(in_bom no)
		(on_board yes)
		(dnp yes)
		(property "Reference" "R38"
			(at 57.15 259.08 90)
			(effects
				(font
					(size 1.27 1.27)
					(thickness 0.15)
				)
				(justify right)
			)
		)
		(property "Value" "R_499k_0402"
			(at 68.58 242.57 0)
			(effects
				(font
					(size 1.27 1.27)
					(thickness 0.15)
				)
				(justify left bottom)
				(hide yes)
			)
		)
		(property "Footprint" "antmicro-footprints:R_0402_1005Metric"
			(at 71.12 242.57 0)
			(effects
				(font
					(size 1.27 1.27)
					(thickness 0.15)
				)
				(justify left bottom)
				(hide yes)
			)
		)
		(property "Datasheet" "https://www.mouser.com/datasheet/2/54/cr-1858361.pdf"
			(at 73.66 242.57 0)
			(effects
				(font
					(size 1.27 1.27)
					(thickness 0.15)
				)
				(justify left bottom)
				(hide yes)
			)
		)
		(property "Description" "SMD Chip Resistor, 499 kohm, ± 1%, 63 mW, 0402 [1005 Metric], Thick Film, General Purpose"
			(at 55.88 262.89 0)
			(effects
				(font
					(size 1.27 1.27)
				)
				(hide yes)
			)
		)
		(property "MPN" "CR0402-FX-4993GLF"
			(at 76.2 242.57 0)
			(effects
				(font
					(size 1.27 1.27)
					(thickness 0.15)
				)
				(justify left bottom)
				(hide yes)
			)
		)
		(property "Manufacturer" "Bourns"
			(at 78.74 242.57 0)
			(effects
				(font
					(size 1.27 1.27)
					(thickness 0.15)
				)
				(justify left bottom)
				(hide yes)
			)
		)
		(property "License" "Apache-2.0"
			(at 81.28 242.57 0)
			(effects
				(font
					(size 1.27 1.27)
					(thickness 0.15)
				)
				(justify left bottom)
				(hide yes)
			)
		)
		(property "Author" "Antmicro"
			(at 83.82 242.57 0)
			(effects
				(font
					(size 1.27 1.27)
					(thickness 0.15)
				)
				(justify left bottom)
				(hide yes)
			)
		)
		(property "Val" "499k"
			(at 57.15 261.62 90)
			(effects
				(font
					(size 1.27 1.27)
					(thickness 0.15)
				)
				(justify right)
			)
		)
		(property "Tolerance" "1%"
			(at 66.04 242.57 0)
			(effects
				(font
					(size 1.27 1.27)
				)
				(justify left bottom)
				(hide yes)
			)
		)
		(pin "2"
		)
		(pin "1"
		)
		(instances
			(project "jetson-agx-thor-baseboard"
				(path ""
					(reference "R38")
					(unit 1)
				)
			)
		)
	)
	(symbol
		(lib_id "antmicropower:GND")
		(at 255.27 44.45 0)
		(unit 1)
		(exclude_from_sim no)
		(in_bom yes)
		(on_board yes)
		(dnp no)
		(property "Reference" "#PWR046"
			(at 255.27 50.8 0)
			(effects
				(font
					(size 1.27 1.27)
				)
				(justify left bottom)
				(hide yes)
			)
		)
		(property "Value" "GND"
			(at 255.27 48.26 0)
			(effects
				(font
					(size 1.27 1.27)
					(thickness 0.15)
				)
			)
		)
		(property "Footprint" ""
			(at 264.16 52.07 0)
			(effects
				(font
					(size 1.27 1.27)
					(thickness 0.15)
				)
				(justify left bottom)
				(hide yes)
			)
		)
		(property "Datasheet" ""
			(at 264.16 57.15 0)
			(effects
				(font
					(size 1.27 1.27)
					(thickness 0.15)
				)
				(justify left bottom)
				(hide yes)
			)
		)
		(property "Description" ""
			(at 255.27 44.45 0)
			(effects
				(font
					(size 1.27 1.27)
				)
				(hide yes)
			)
		)
		(property "Author" "Antmicro"
			(at 264.16 52.07 0)
			(effects
				(font
					(size 1.27 1.27)
					(thickness 0.15)
				)
				(justify left bottom)
				(hide yes)
			)
		)
		(property "License" "Apache-2.0"
			(at 264.16 54.61 0)
			(effects
				(font
					(size 1.27 1.27)
					(thickness 0.15)
				)
				(justify left bottom)
				(hide yes)
			)
		)
		(pin "1"
		)
		(instances
			(project "jetson-agx-thor-baseboard"
				(path ""
					(reference "#PWR046")
					(unit 1)
				)
			)
		)
	)
	(symbol
		(lib_id "antmicroResistorsmisc:R_0R001_0805")
		(at 204.47 158.75 0)
		(unit 1)
		(exclude_from_sim no)
		(in_bom yes)
		(on_board yes)
		(dnp no)
		(property "Reference" "R366"
			(at 207.01 153.67 0)
			(effects
				(font
					(size 1.27 1.27)
					(thickness 0.15)
				)
			)
		)
		(property "Value" "R_0R001_0805"
			(at 224.79 171.45 0)
			(effects
				(font
					(size 1.27 1.27)
					(thickness 0.15)
				)
				(justify left bottom)
				(hide yes)
			)
		)
		(property "Footprint" "antmicro-footprints:R_0805_2012Metric"
			(at 224.79 173.99 0)
			(effects
				(font
					(size 1.27 1.27)
					(thickness 0.15)
				)
				(justify left bottom)
				(hide yes)
			)
		)
		(property "Datasheet" "https://www.eaton.com/content/dam/eaton/products/electronic-components/resources/data-sheet/eaton-msma-automotive-smd-current-sense-resistor-metal-strip-data-sheet-elx1179.pdf"
			(at 224.79 176.53 0)
			(effects
				(font
					(size 1.27 1.27)
					(thickness 0.15)
				)
				(justify left bottom)
				(hide yes)
			)
		)
		(property "Description" "Current Sense Resistors - SMD MSMA, 0805 SIZE, 1/2 Watt, 1 mohm, 50 TCR MnCu Metal AEC-Q"
			(at 204.47 158.75 0)
			(effects
				(font
					(size 1.27 1.27)
				)
				(hide yes)
			)
		)
		(property "MPN" "MSMA0805R0010FSM"
			(at 224.79 179.07 0)
			(effects
				(font
					(size 1.27 1.27)
					(thickness 0.15)
				)
				(justify left bottom)
				(hide yes)
			)
		)
		(property "Manufacturer" "Eaton"
			(at 224.79 181.61 0)
			(effects
				(font
					(size 1.27 1.27)
					(thickness 0.15)
				)
				(justify left bottom)
				(hide yes)
			)
		)
		(property "License" "Apache-2.0"
			(at 224.79 184.15 0)
			(effects
				(font
					(size 1.27 1.27)
					(thickness 0.15)
				)
				(justify left bottom)
				(hide yes)
			)
		)
		(property "Author" "Antmicro"
			(at 224.79 186.69 0)
			(effects
				(font
					(size 1.27 1.27)
					(thickness 0.15)
				)
				(justify left bottom)
				(hide yes)
			)
		)
		(property "Val" "0R001"
			(at 207.01 156.21 0)
			(effects
				(font
					(size 1.27 1.27)
					(thickness 0.15)
				)
			)
		)
		(property "Tolerance" "1%"
			(at 224.79 168.91 0)
			(effects
				(font
					(size 1.27 1.27)
				)
				(justify left bottom)
				(hide yes)
			)
		)
		(property "Public" "False"
			(at 224.79 189.23 0)
			(effects
				(font
					(size 1.27 1.27)
				)
				(justify left bottom)
				(hide yes)
			)
		)
		(pin "2"
		)
		(pin "1"
		)
		(instances
			(project "jetson-agx-thor-baseboard"
				(path ""
					(reference "R366")
					(unit 1)
				)
			)
		)
	)
	(symbol
		(lib_id "antmicropower:GND")
		(at 220.98 132.08 0)
		(unit 1)
		(exclude_from_sim no)
		(in_bom yes)
		(on_board yes)
		(dnp no)
		(property "Reference" "#PWR0568"
			(at 229.87 134.62 0)
			(effects
				(font
					(size 1.27 1.27)
					(thickness 0.15)
				)
				(justify left bottom)
				(hide yes)
			)
		)
		(property "Value" "GND"
			(at 220.98 135.89 0)
			(effects
				(font
					(size 1.27 1.27)
					(thickness 0.15)
				)
			)
		)
		(property "Footprint" ""
			(at 229.87 139.7 0)
			(effects
				(font
					(size 1.27 1.27)
					(thickness 0.15)
				)
				(justify left bottom)
				(hide yes)
			)
		)
		(property "Datasheet" ""
			(at 229.87 144.78 0)
			(effects
				(font
					(size 1.27 1.27)
					(thickness 0.15)
				)
				(justify left bottom)
				(hide yes)
			)
		)
		(property "Description" ""
			(at 220.98 132.08 0)
			(effects
				(font
					(size 1.27 1.27)
				)
				(hide yes)
			)
		)
		(property "Author" "Antmicro"
			(at 229.87 139.7 0)
			(effects
				(font
					(size 1.27 1.27)
					(thickness 0.15)
				)
				(justify left bottom)
				(hide yes)
			)
		)
		(property "License" "Apache-2.0"
			(at 229.87 142.24 0)
			(effects
				(font
					(size 1.27 1.27)
					(thickness 0.15)
				)
				(justify left bottom)
				(hide yes)
			)
		)
		(pin "1"
		)
		(instances
			(project "jetson-agx-thor-baseboard"
				(path ""
					(reference "#PWR0568")
					(unit 1)
				)
			)
		)
	)
	(symbol
		(lib_id "antmicroCapacitorsmisc:C_22u_25V_0805")
		(at 40.64 39.37 90)
		(unit 1)
		(exclude_from_sim no)
		(in_bom yes)
		(on_board yes)
		(dnp no)
		(property "Reference" "C242"
			(at 41.275 34.925 90)
			(effects
				(font
					(size 1.27 1.27)
					(thickness 0.15)
				)
				(justify right)
			)
		)
		(property "Value" "C_22u_25V_0805"
			(at 50.8 19.05 0)
			(effects
				(font
					(size 1.27 1.27)
					(thickness 0.15)
				)
				(justify left bottom)
				(hide yes)
			)
		)
		(property "Footprint" "antmicro-footprints:C_0805_2012Metric"
			(at 53.34 19.05 0)
			(effects
				(font
					(size 1.27 1.27)
					(thickness 0.15)
				)
				(justify left bottom)
				(hide yes)
			)
		)
		(property "Datasheet" "https://product.samsungsem.com/mlcc/CL21A226MAYNNN.do"
			(at 55.88 19.05 0)
			(effects
				(font
					(size 1.27 1.27)
					(thickness 0.15)
				)
				(justify left bottom)
				(hide yes)
			)
		)
		(property "Description" "SMT Multilayer Ceramic Capacitor, 22uF, +/-20%, 25V, X5R, 0805 [2012 Metric]"
			(at 40.64 39.37 0)
			(effects
				(font
					(size 1.27 1.27)
				)
				(hide yes)
			)
		)
		(property "MPN" "CL21A226MAYNNNE"
			(at 58.42 19.05 0)
			(effects
				(font
					(size 1.27 1.27)
					(thickness 0.15)
				)
				(justify left bottom)
				(hide yes)
			)
		)
		(property "Manufacturer" "Samsung Electro-Mechanics"
			(at 60.96 19.05 0)
			(effects
				(font
					(size 1.27 1.27)
					(thickness 0.15)
				)
				(justify left bottom)
				(hide yes)
			)
		)
		(property "License" "Apache-2.0"
			(at 63.5 19.05 0)
			(effects
				(font
					(size 1.27 1.27)
					(thickness 0.15)
				)
				(justify left bottom)
				(hide yes)
			)
		)
		(property "Author" "Antmicro"
			(at 66.04 19.05 0)
			(effects
				(font
					(size 1.27 1.27)
					(thickness 0.15)
				)
				(justify left bottom)
				(hide yes)
			)
		)
		(property "Val" "22u"
			(at 41.275 38.735 90)
			(effects
				(font
					(size 1.27 1.27)
					(thickness 0.15)
				)
				(justify right)
			)
		)
		(property "Voltage" "25V"
			(at 41.275 41.275 90)
			(effects
				(font
					(size 1.27 1.27)
				)
				(justify right)
			)
		)
		(property "Dielectric" "X5R"
			(at 71.12 19.05 0)
			(effects
				(font
					(size 1.27 1.27)
				)
				(justify left bottom)
				(hide yes)
			)
		)
		(property "Public" "False"
			(at 73.66 19.05 0)
			(effects
				(font
					(size 1.27 1.27)
				)
				(justify left bottom)
				(hide yes)
			)
		)
		(pin "1"
		)
		(pin "2"
		)
		(instances
			(project "jetson-agx-thor-baseboard"
				(path ""
					(reference "C242")
					(unit 1)
				)
			)
		)
	)
	(symbol
		(lib_id "antmicroResistors0402:R_10k_0402")
		(at 143.51 181.61 90)
		(unit 1)
		(exclude_from_sim no)
		(in_bom yes)
		(on_board yes)
		(dnp no)
		(property "Reference" "R313"
			(at 144.78 177.8 90)
			(effects
				(font
					(size 1.27 1.27)
					(thickness 0.15)
				)
				(justify right)
			)
		)
		(property "Value" "R_10k_0402"
			(at 156.21 161.29 0)
			(effects
				(font
					(size 1.27 1.27)
					(thickness 0.15)
				)
				(justify left bottom)
				(hide yes)
			)
		)
		(property "Footprint" "antmicro-footprints:R_0402_1005Metric"
			(at 158.75 161.29 0)
			(effects
				(font
					(size 1.27 1.27)
					(thickness 0.15)
				)
				(justify left bottom)
				(hide yes)
			)
		)
		(property "Datasheet" "https://www.bourns.com/docs/product-datasheets/cr.pdf"
			(at 161.29 161.29 0)
			(effects
				(font
					(size 1.27 1.27)
					(thickness 0.15)
				)
				(justify left bottom)
				(hide yes)
			)
		)
		(property "Description" "SMD Chip Resistor, 10 kohm, ± 1%, 62.5 mW, 0402 [1005 Metric], Thick Film, General Purpose"
			(at 143.51 181.61 0)
			(effects
				(font
					(size 1.27 1.27)
				)
				(hide yes)
			)
		)
		(property "MPN" "CR0402-FX-1002GLF"
			(at 163.83 161.29 0)
			(effects
				(font
					(size 1.27 1.27)
					(thickness 0.15)
				)
				(justify left bottom)
				(hide yes)
			)
		)
		(property "Manufacturer" "Bourns"
			(at 166.37 161.29 0)
			(effects
				(font
					(size 1.27 1.27)
					(thickness 0.15)
				)
				(justify left bottom)
				(hide yes)
			)
		)
		(property "License" "Apache-2.0"
			(at 168.91 161.29 0)
			(effects
				(font
					(size 1.27 1.27)
					(thickness 0.15)
				)
				(justify left bottom)
				(hide yes)
			)
		)
		(property "Author" "Antmicro"
			(at 171.45 161.29 0)
			(effects
				(font
					(size 1.27 1.27)
					(thickness 0.15)
				)
				(justify left bottom)
				(hide yes)
			)
		)
		(property "Val" "10k"
			(at 144.78 180.34 90)
			(effects
				(font
					(size 1.27 1.27)
					(thickness 0.15)
				)
				(justify right)
			)
		)
		(property "Tolerance" "1%"
			(at 153.67 161.29 0)
			(effects
				(font
					(size 1.27 1.27)
				)
				(justify left bottom)
				(hide yes)
			)
		)
		(pin "2"
		)
		(pin "1"
		)
		(instances
			(project "jetson-agx-thor-baseboard"
				(path ""
					(reference "R313")
					(unit 1)
				)
			)
		)
	)
	(symbol
		(lib_id "antmicropower:GND")
		(at 72.39 55.88 0)
		(unit 1)
		(exclude_from_sim no)
		(in_bom yes)
		(on_board yes)
		(dnp no)
		(property "Reference" "#PWR0495"
			(at 72.39 62.23 0)
			(effects
				(font
					(size 1.27 1.27)
				)
				(justify left bottom)
				(hide yes)
			)
		)
		(property "Value" "GND"
			(at 72.39 59.69 0)
			(effects
				(font
					(size 1.27 1.27)
					(thickness 0.15)
				)
			)
		)
		(property "Footprint" ""
			(at 81.28 63.5 0)
			(effects
				(font
					(size 1.27 1.27)
					(thickness 0.15)
				)
				(justify left bottom)
				(hide yes)
			)
		)
		(property "Datasheet" ""
			(at 81.28 68.58 0)
			(effects
				(font
					(size 1.27 1.27)
					(thickness 0.15)
				)
				(justify left bottom)
				(hide yes)
			)
		)
		(property "Description" ""
			(at 72.39 55.88 0)
			(effects
				(font
					(size 1.27 1.27)
				)
				(hide yes)
			)
		)
		(property "Author" "Antmicro"
			(at 81.28 63.5 0)
			(effects
				(font
					(size 1.27 1.27)
					(thickness 0.15)
				)
				(justify left bottom)
				(hide yes)
			)
		)
		(property "License" "Apache-2.0"
			(at 81.28 66.04 0)
			(effects
				(font
					(size 1.27 1.27)
					(thickness 0.15)
				)
				(justify left bottom)
				(hide yes)
			)
		)
		(pin "1"
		)
		(instances
			(project "jetson-agx-thor-baseboard"
				(path ""
					(reference "#PWR0495")
					(unit 1)
				)
			)
		)
	)
	(symbol
		(lib_id "antmicropower:GND")
		(at 83.82 187.96 0)
		(unit 1)
		(exclude_from_sim no)
		(in_bom yes)
		(on_board yes)
		(dnp no)
		(property "Reference" "#PWR0753"
			(at 83.82 194.31 0)
			(effects
				(font
					(size 1.27 1.27)
				)
				(justify left bottom)
				(hide yes)
			)
		)
		(property "Value" "GND"
			(at 83.82 191.77 0)
			(effects
				(font
					(size 1.27 1.27)
					(thickness 0.15)
				)
			)
		)
		(property "Footprint" ""
			(at 92.71 195.58 0)
			(effects
				(font
					(size 1.27 1.27)
					(thickness 0.15)
				)
				(justify left bottom)
				(hide yes)
			)
		)
		(property "Datasheet" ""
			(at 92.71 200.66 0)
			(effects
				(font
					(size 1.27 1.27)
					(thickness 0.15)
				)
				(justify left bottom)
				(hide yes)
			)
		)
		(property "Description" ""
			(at 83.82 187.96 0)
			(effects
				(font
					(size 1.27 1.27)
				)
				(hide yes)
			)
		)
		(property "Author" "Antmicro"
			(at 92.71 195.58 0)
			(effects
				(font
					(size 1.27 1.27)
					(thickness 0.15)
				)
				(justify left bottom)
				(hide yes)
			)
		)
		(property "License" "Apache-2.0"
			(at 92.71 198.12 0)
			(effects
				(font
					(size 1.27 1.27)
					(thickness 0.15)
				)
				(justify left bottom)
				(hide yes)
			)
		)
		(pin "1"
		)
		(instances
			(project "jetson-agx-thor-baseboard"
				(path ""
					(reference "#PWR0753")
					(unit 1)
				)
			)
		)
	)
	(symbol
		(lib_id "antmicropower:GND")
		(at 55.88 279.4 0)
		(unit 1)
		(exclude_from_sim no)
		(in_bom yes)
		(on_board yes)
		(dnp no)
		(property "Reference" "#PWR0103"
			(at 55.88 285.75 0)
			(effects
				(font
					(size 1.27 1.27)
				)
				(justify left bottom)
				(hide yes)
			)
		)
		(property "Value" "GND"
			(at 55.88 283.21 0)
			(effects
				(font
					(size 1.27 1.27)
					(thickness 0.15)
				)
			)
		)
		(property "Footprint" ""
			(at 64.77 287.02 0)
			(effects
				(font
					(size 1.27 1.27)
					(thickness 0.15)
				)
				(justify left bottom)
				(hide yes)
			)
		)
		(property "Datasheet" ""
			(at 64.77 292.1 0)
			(effects
				(font
					(size 1.27 1.27)
					(thickness 0.15)
				)
				(justify left bottom)
				(hide yes)
			)
		)
		(property "Description" ""
			(at 55.88 279.4 0)
			(effects
				(font
					(size 1.27 1.27)
				)
				(hide yes)
			)
		)
		(property "Author" "Antmicro"
			(at 64.77 287.02 0)
			(effects
				(font
					(size 1.27 1.27)
					(thickness 0.15)
				)
				(justify left bottom)
				(hide yes)
			)
		)
		(property "License" "Apache-2.0"
			(at 64.77 289.56 0)
			(effects
				(font
					(size 1.27 1.27)
					(thickness 0.15)
				)
				(justify left bottom)
				(hide yes)
			)
		)
		(pin "1"
		)
		(instances
			(project "jetson-agx-thor-baseboard"
				(path ""
					(reference "#PWR0103")
					(unit 1)
				)
			)
		)
	)
	(symbol
		(lib_id "antmicroCapacitors0402:C_4u7_25V_0402")
		(at 83.82 278.13 90)
		(unit 1)
		(exclude_from_sim no)
		(in_bom yes)
		(on_board yes)
		(dnp no)
		(property "Reference" "C56"
			(at 84.455 273.685 90)
			(effects
				(font
					(size 1.27 1.27)
					(thickness 0.15)
				)
				(justify right)
			)
		)
		(property "Value" "C_4u7_25V_0402"
			(at 93.98 257.81 0)
			(effects
				(font
					(size 1.27 1.27)
					(thickness 0.15)
				)
				(justify left bottom)
				(hide yes)
			)
		)
		(property "Footprint" "antmicro-footprints:C_0402_1005Metric"
			(at 96.52 257.81 0)
			(effects
				(font
					(size 1.27 1.27)
					(thickness 0.15)
				)
				(justify left bottom)
				(hide yes)
			)
		)
		(property "Datasheet" "https://www.murata.com/products/productdetail?partno=GRM155C61E475ME15%23"
			(at 99.06 257.81 0)
			(effects
				(font
					(size 1.27 1.27)
					(thickness 0.15)
				)
				(justify left bottom)
				(hide yes)
			)
		)
		(property "Description" "SMD Multilayer Ceramic Capacitor"
			(at 83.82 278.13 0)
			(effects
				(font
					(size 1.27 1.27)
				)
				(hide yes)
			)
		)
		(property "MPN" "GRM155C61E475ME15J"
			(at 101.6 257.81 0)
			(effects
				(font
					(size 1.27 1.27)
					(thickness 0.15)
				)
				(justify left bottom)
				(hide yes)
			)
		)
		(property "Manufacturer" "Murata"
			(at 104.14 257.81 0)
			(effects
				(font
					(size 1.27 1.27)
					(thickness 0.15)
				)
				(justify left bottom)
				(hide yes)
			)
		)
		(property "License" "Apache-2.0"
			(at 106.68 257.81 0)
			(effects
				(font
					(size 1.27 1.27)
					(thickness 0.15)
				)
				(justify left bottom)
				(hide yes)
			)
		)
		(property "Author" "Antmicro"
			(at 109.22 257.81 0)
			(effects
				(font
					(size 1.27 1.27)
					(thickness 0.15)
				)
				(justify left bottom)
				(hide yes)
			)
		)
		(property "Val" "4u7"
			(at 84.455 277.495 90)
			(effects
				(font
					(size 1.27 1.27)
					(thickness 0.15)
				)
				(justify right)
			)
		)
		(property "Voltage" "25V"
			(at 111.76 257.81 0)
			(effects
				(font
					(size 1.27 1.27)
				)
				(justify left bottom)
				(hide yes)
			)
		)
		(property "Dielectric" "X5S"
			(at 114.3 257.81 0)
			(effects
				(font
					(size 1.27 1.27)
				)
				(justify left bottom)
				(hide yes)
			)
		)
		(pin "2"
		)
		(pin "1"
		)
		(instances
			(project "jetson-agx-thor-baseboard"
				(path ""
					(reference "C56")
					(unit 1)
				)
			)
		)
	)
	(symbol
		(lib_id "antmicropower:+5V")
		(at 232.41 166.37 0)
		(unit 1)
		(exclude_from_sim no)
		(in_bom yes)
		(on_board yes)
		(dnp no)
		(property "Reference" "#PWR0653"
			(at 232.41 170.18 0)
			(effects
				(font
					(size 1.27 1.27)
				)
				(justify left bottom)
				(hide yes)
			)
		)
		(property "Value" "+5V_AON"
			(at 232.41 162.052 0)
			(effects
				(font
					(size 1.27 1.27)
					(thickness 0.15)
				)
			)
		)
		(property "Footprint" ""
			(at 247.65 173.99 0)
			(effects
				(font
					(size 1.27 1.27)
					(thickness 0.15)
				)
				(justify left bottom)
				(hide yes)
			)
		)
		(property "Datasheet" ""
			(at 247.65 176.53 0)
			(effects
				(font
					(size 1.27 1.27)
					(thickness 0.15)
				)
				(justify left bottom)
				(hide yes)
			)
		)
		(property "Description" ""
			(at 232.41 166.37 0)
			(effects
				(font
					(size 1.27 1.27)
				)
				(hide yes)
			)
		)
		(property "Author" "Antmicro"
			(at 247.65 173.99 0)
			(effects
				(font
					(size 1.27 1.27)
					(thickness 0.15)
				)
				(justify left bottom)
				(hide yes)
			)
		)
		(property "License" "Apache-2.0"
			(at 247.65 176.53 0)
			(effects
				(font
					(size 1.27 1.27)
					(thickness 0.15)
				)
				(justify left bottom)
				(hide yes)
			)
		)
		(pin "1"
		)
		(instances
			(project "jetson-agx-thor-baseboard"
				(path ""
					(reference "#PWR0653")
					(unit 1)
				)
			)
		)
	)
	(symbol
		(lib_id "antmicroCapacitorsmisc:C_22u_25V_0805")
		(at 27.94 224.79 90)
		(unit 1)
		(exclude_from_sim no)
		(in_bom yes)
		(on_board yes)
		(dnp no)
		(property "Reference" "C271"
			(at 28.575 220.345 90)
			(effects
				(font
					(size 1.27 1.27)
					(thickness 0.15)
				)
				(justify right)
			)
		)
		(property "Value" "C_22u_25V_0805"
			(at 38.1 204.47 0)
			(effects
				(font
					(size 1.27 1.27)
					(thickness 0.15)
				)
				(justify left bottom)
				(hide yes)
			)
		)
		(property "Footprint" "antmicro-footprints:C_0805_2012Metric"
			(at 40.64 204.47 0)
			(effects
				(font
					(size 1.27 1.27)
					(thickness 0.15)
				)
				(justify left bottom)
				(hide yes)
			)
		)
		(property "Datasheet" "https://product.samsungsem.com/mlcc/CL21A226MAYNNN.do"
			(at 43.18 204.47 0)
			(effects
				(font
					(size 1.27 1.27)
					(thickness 0.15)
				)
				(justify left bottom)
				(hide yes)
			)
		)
		(property "Description" "SMT Multilayer Ceramic Capacitor, 22uF, +/-20%, 25V, X5R, 0805 [2012 Metric]"
			(at 27.94 224.79 0)
			(effects
				(font
					(size 1.27 1.27)
				)
				(hide yes)
			)
		)
		(property "MPN" "CL21A226MAYNNNE"
			(at 45.72 204.47 0)
			(effects
				(font
					(size 1.27 1.27)
					(thickness 0.15)
				)
				(justify left bottom)
				(hide yes)
			)
		)
		(property "Manufacturer" "Samsung Electro-Mechanics"
			(at 48.26 204.47 0)
			(effects
				(font
					(size 1.27 1.27)
					(thickness 0.15)
				)
				(justify left bottom)
				(hide yes)
			)
		)
		(property "License" "Apache-2.0"
			(at 50.8 204.47 0)
			(effects
				(font
					(size 1.27 1.27)
					(thickness 0.15)
				)
				(justify left bottom)
				(hide yes)
			)
		)
		(property "Author" "Antmicro"
			(at 53.34 204.47 0)
			(effects
				(font
					(size 1.27 1.27)
					(thickness 0.15)
				)
				(justify left bottom)
				(hide yes)
			)
		)
		(property "Val" "22u"
			(at 28.575 224.155 90)
			(effects
				(font
					(size 1.27 1.27)
					(thickness 0.15)
				)
				(justify right)
			)
		)
		(property "Voltage" "25V"
			(at 28.575 226.695 90)
			(effects
				(font
					(size 1.27 1.27)
				)
				(justify right)
			)
		)
		(property "Dielectric" "X5R"
			(at 58.42 204.47 0)
			(effects
				(font
					(size 1.27 1.27)
				)
				(justify left bottom)
				(hide yes)
			)
		)
		(property "Public" "False"
			(at 60.96 204.47 0)
			(effects
				(font
					(size 1.27 1.27)
				)
				(justify left bottom)
				(hide yes)
			)
		)
		(pin "1"
		)
		(pin "2"
		)
		(instances
			(project "jetson-agx-thor-baseboard"
				(path ""
					(reference "C271")
					(unit 1)
				)
			)
		)
	)
	(symbol
		(lib_id "antmicropower:GND")
		(at 26.67 187.96 0)
		(unit 1)
		(exclude_from_sim no)
		(in_bom yes)
		(on_board yes)
		(dnp no)
		(fields_autoplaced yes)
		(property "Reference" "#PWR0133"
			(at 26.67 194.31 0)
			(effects
				(font
					(size 1.27 1.27)
				)
				(justify left bottom)
				(hide yes)
			)
		)
		(property "Value" "GND"
			(at 26.67 191.77 0)
			(effects
				(font
					(size 1.27 1.27)
					(thickness 0.15)
				)
			)
		)
		(property "Footprint" ""
			(at 35.56 195.58 0)
			(effects
				(font
					(size 1.27 1.27)
					(thickness 0.15)
				)
				(justify left bottom)
				(hide yes)
			)
		)
		(property "Datasheet" ""
			(at 35.56 200.66 0)
			(effects
				(font
					(size 1.27 1.27)
					(thickness 0.15)
				)
				(justify left bottom)
				(hide yes)
			)
		)
		(property "Description" ""
			(at 26.67 187.96 0)
			(effects
				(font
					(size 1.27 1.27)
				)
				(hide yes)
			)
		)
		(property "Author" "Antmicro"
			(at 35.56 195.58 0)
			(effects
				(font
					(size 1.27 1.27)
					(thickness 0.15)
				)
				(justify left bottom)
				(hide yes)
			)
		)
		(property "License" "Apache-2.0"
			(at 35.56 198.12 0)
			(effects
				(font
					(size 1.27 1.27)
					(thickness 0.15)
				)
				(justify left bottom)
				(hide yes)
			)
		)
		(pin "1"
		)
		(instances
			(project "jetson-agx-thor-baseboard"
				(path ""
					(reference "#PWR0133")
					(unit 1)
				)
			)
		)
	)
	(symbol
		(lib_id "antmicroCapacitors0402:C_100n_0402")
		(at 130.81 162.56 180)
		(unit 1)
		(exclude_from_sim no)
		(in_bom yes)
		(on_board yes)
		(dnp no)
		(fields_autoplaced yes)
		(property "Reference" "C377"
			(at 128.2636 156.21 0)
			(effects
				(font
					(size 1.27 1.27)
				)
			)
		)
		(property "Value" "C_100n_0402"
			(at 110.49 152.4 0)
			(effects
				(font
					(size 1.27 1.27)
					(thickness 0.15)
				)
				(justify left bottom)
				(hide yes)
			)
		)
		(property "Footprint" "antmicro-footprints:C_0402_1005Metric"
			(at 110.49 149.86 0)
			(effects
				(font
					(size 1.27 1.27)
					(thickness 0.15)
				)
				(justify left bottom)
				(hide yes)
			)
		)
		(property "Datasheet" "https://www.murata.com/products/productdetail?partno=GRM155R61H104KE14%23"
			(at 110.49 147.32 0)
			(effects
				(font
					(size 1.27 1.27)
					(thickness 0.15)
				)
				(justify left bottom)
				(hide yes)
			)
		)
		(property "Description" "SMD Multilayer Ceramic Capacitor, 0.1 µF, 50 V, 0402 [1005 Metric], ± 10%, X5R, GRM Series"
			(at 130.81 162.56 0)
			(effects
				(font
					(size 1.27 1.27)
				)
				(hide yes)
			)
		)
		(property "Manufacturer" "Murata"
			(at 110.49 142.24 0)
			(effects
				(font
					(size 1.27 1.27)
					(thickness 0.15)
				)
				(justify left bottom)
				(hide yes)
			)
		)
		(property "MPN" "GRM155R61H104KE14D"
			(at 110.49 144.78 0)
			(effects
				(font
					(size 1.27 1.27)
					(thickness 0.15)
				)
				(justify left bottom)
				(hide yes)
			)
		)
		(property "Val" "100n"
			(at 128.2636 158.75 0)
			(effects
				(font
					(size 1.27 1.27)
					(thickness 0.15)
				)
			)
		)
		(property "License" "Apache-2.0"
			(at 110.49 139.7 0)
			(effects
				(font
					(size 1.27 1.27)
					(thickness 0.15)
				)
				(justify left bottom)
				(hide yes)
			)
		)
		(property "Author" "Antmicro"
			(at 110.49 137.16 0)
			(effects
				(font
					(size 1.27 1.27)
					(thickness 0.15)
				)
				(justify left bottom)
				(hide yes)
			)
		)
		(property "Voltage" "50V"
			(at 110.49 134.62 0)
			(effects
				(font
					(size 1.27 1.27)
				)
				(justify left bottom)
				(hide yes)
			)
		)
		(property "Dielectric" "X5R"
			(at 110.49 132.08 0)
			(effects
				(font
					(size 1.27 1.27)
				)
				(justify left bottom)
				(hide yes)
			)
		)
		(pin "1"
		)
		(pin "2"
		)
		(instances
			(project "jetson-agx-thor-baseboard"
				(path ""
					(reference "C377")
					(unit 1)
				)
			)
		)
	)
	(symbol
		(lib_id "antmicroTVSDiodes:PESD5Z5_0F")
		(at 232.41 267.97 270)
		(unit 1)
		(exclude_from_sim no)
		(in_bom yes)
		(on_board yes)
		(dnp no)
		(property "Reference" "D9"
			(at 233.68 269.24 90)
			(effects
				(font
					(size 1.27 1.27)
				)
				(justify left)
			)
		)
		(property "Value" "PESD5Z5.0F"
			(at 217.17 289.56 0)
			(effects
				(font
					(size 1.27 1.27)
					(thickness 0.15)
				)
				(justify left bottom)
				(hide yes)
			)
		)
		(property "Footprint" "antmicro-footprints:SOD-523"
			(at 227.33 283.21 0)
			(effects
				(font
					(size 1.27 1.27)
					(thickness 0.15)
				)
				(justify left bottom)
				(hide yes)
			)
		)
		(property "Datasheet" "https://assets.nexperia.com/documents/data-sheet/PESD5Z5_0.pdf"
			(at 224.79 283.21 0)
			(effects
				(font
					(size 1.27 1.27)
					(thickness 0.15)
				)
				(justify left bottom)
				(hide yes)
			)
		)
		(property "Description" "Unidirectional TVS, 30 kV,  SOD-523, 5 V, 89 pF"
			(at 212.09 283.21 0)
			(effects
				(font
					(size 1.27 1.27)
				)
				(justify left bottom)
				(hide yes)
			)
		)
		(property "Manufacturer" "Nexperia"
			(at 222.25 283.21 0)
			(effects
				(font
					(size 1.27 1.27)
					(thickness 0.15)
				)
				(justify left bottom)
				(hide yes)
			)
		)
		(property "MPN" "PESD5Z5.0F"
			(at 233.68 271.78 90)
			(effects
				(font
					(size 1.27 1.27)
					(thickness 0.15)
				)
				(justify left bottom)
			)
		)
		(property "Author" "Antmicro"
			(at 217.17 283.21 0)
			(effects
				(font
					(size 1.27 1.27)
					(thickness 0.15)
				)
				(justify left bottom)
				(hide yes)
			)
		)
		(property "License" "Apache-2.0"
			(at 214.63 283.21 0)
			(effects
				(font
					(size 1.27 1.27)
					(thickness 0.15)
				)
				(justify left bottom)
				(hide yes)
			)
		)
		(pin "1"
		)
		(pin "2"
		)
		(instances
			(project "jetson-agx-thor-baseboard"
				(path ""
					(reference "D9")
					(unit 1)
				)
			)
		)
	)
	(symbol
		(lib_id "antmicroCapacitors0402:C_4u7_25V_0402")
		(at 83.82 186.69 90)
		(unit 1)
		(exclude_from_sim no)
		(in_bom yes)
		(on_board yes)
		(dnp no)
		(property "Reference" "C376"
			(at 84.455 182.245 90)
			(effects
				(font
					(size 1.27 1.27)
					(thickness 0.15)
				)
				(justify right)
			)
		)
		(property "Value" "C_4u7_25V_0402"
			(at 93.98 166.37 0)
			(effects
				(font
					(size 1.27 1.27)
					(thickness 0.15)
				)
				(justify left bottom)
				(hide yes)
			)
		)
		(property "Footprint" "antmicro-footprints:C_0402_1005Metric"
			(at 96.52 166.37 0)
			(effects
				(font
					(size 1.27 1.27)
					(thickness 0.15)
				)
				(justify left bottom)
				(hide yes)
			)
		)
		(property "Datasheet" "https://www.murata.com/products/productdetail?partno=GRM155C61E475ME15%23"
			(at 99.06 166.37 0)
			(effects
				(font
					(size 1.27 1.27)
					(thickness 0.15)
				)
				(justify left bottom)
				(hide yes)
			)
		)
		(property "Description" "SMD Multilayer Ceramic Capacitor"
			(at 83.82 186.69 0)
			(effects
				(font
					(size 1.27 1.27)
				)
				(hide yes)
			)
		)
		(property "MPN" "GRM155C61E475ME15J"
			(at 101.6 166.37 0)
			(effects
				(font
					(size 1.27 1.27)
					(thickness 0.15)
				)
				(justify left bottom)
				(hide yes)
			)
		)
		(property "Manufacturer" "Murata"
			(at 104.14 166.37 0)
			(effects
				(font
					(size 1.27 1.27)
					(thickness 0.15)
				)
				(justify left bottom)
				(hide yes)
			)
		)
		(property "License" "Apache-2.0"
			(at 106.68 166.37 0)
			(effects
				(font
					(size 1.27 1.27)
					(thickness 0.15)
				)
				(justify left bottom)
				(hide yes)
			)
		)
		(property "Author" "Antmicro"
			(at 109.22 166.37 0)
			(effects
				(font
					(size 1.27 1.27)
					(thickness 0.15)
				)
				(justify left bottom)
				(hide yes)
			)
		)
		(property "Val" "4u7"
			(at 84.455 186.055 90)
			(effects
				(font
					(size 1.27 1.27)
					(thickness 0.15)
				)
				(justify right)
			)
		)
		(property "Voltage" "25V"
			(at 111.76 166.37 0)
			(effects
				(font
					(size 1.27 1.27)
				)
				(justify left bottom)
				(hide yes)
			)
		)
		(property "Dielectric" "X5S"
			(at 114.3 166.37 0)
			(effects
				(font
					(size 1.27 1.27)
				)
				(justify left bottom)
				(hide yes)
			)
		)
		(pin "2"
		)
		(pin "1"
		)
		(instances
			(project "jetson-agx-thor-baseboard"
				(path ""
					(reference "C376")
					(unit 1)
				)
			)
		)
	)
	(symbol
		(lib_id "antmicropower:GND")
		(at 16.51 187.96 0)
		(unit 1)
		(exclude_from_sim no)
		(in_bom yes)
		(on_board yes)
		(dnp no)
		(property "Reference" "#PWR0664"
			(at 16.51 194.31 0)
			(effects
				(font
					(size 1.27 1.27)
				)
				(justify left bottom)
				(hide yes)
			)
		)
		(property "Value" "GND"
			(at 16.51 191.77 0)
			(effects
				(font
					(size 1.27 1.27)
					(thickness 0.15)
				)
			)
		)
		(property "Footprint" ""
			(at 25.4 195.58 0)
			(effects
				(font
					(size 1.27 1.27)
					(thickness 0.15)
				)
				(justify left bottom)
				(hide yes)
			)
		)
		(property "Datasheet" ""
			(at 25.4 200.66 0)
			(effects
				(font
					(size 1.27 1.27)
					(thickness 0.15)
				)
				(justify left bottom)
				(hide yes)
			)
		)
		(property "Description" ""
			(at 16.51 187.96 0)
			(effects
				(font
					(size 1.27 1.27)
				)
				(hide yes)
			)
		)
		(property "Author" "Antmicro"
			(at 25.4 195.58 0)
			(effects
				(font
					(size 1.27 1.27)
					(thickness 0.15)
				)
				(justify left bottom)
				(hide yes)
			)
		)
		(property "License" "Apache-2.0"
			(at 25.4 198.12 0)
			(effects
				(font
					(size 1.27 1.27)
					(thickness 0.15)
				)
				(justify left bottom)
				(hide yes)
			)
		)
		(pin "1"
		)
		(instances
			(project "jetson-agx-thor-baseboard"
				(path ""
					(reference "#PWR0664")
					(unit 1)
				)
			)
		)
	)
	(symbol
		(lib_id "antmicroResistors0402:R_27R_0402")
		(at 198.12 165.1 270)
		(mirror x)
		(unit 1)
		(exclude_from_sim no)
		(in_bom yes)
		(on_board yes)
		(dnp no)
		(property "Reference" "R314"
			(at 196.85 161.2899 90)
			(effects
				(font
					(size 1.27 1.27)
				)
				(justify right)
			)
		)
		(property "Value" "R_27R_0402"
			(at 185.42 144.78 0)
			(effects
				(font
					(size 1.27 1.27)
					(thickness 0.15)
				)
				(justify left bottom)
				(hide yes)
			)
		)
		(property "Footprint" "antmicro-footprints:R_0402_1005Metric"
			(at 182.88 144.78 0)
			(effects
				(font
					(size 1.27 1.27)
					(thickness 0.15)
				)
				(justify left bottom)
				(hide yes)
			)
		)
		(property "Datasheet" "https://www.bourns.com/docs/product-datasheets/cr.pdf"
			(at 180.34 144.78 0)
			(effects
				(font
					(size 1.27 1.27)
					(thickness 0.15)
				)
				(justify left bottom)
				(hide yes)
			)
		)
		(property "Description" "SMD Chip Resistor, 27 ohm, ± 1%, 63 mW, 0402 [1005 Metric], Thick Film, General Purpose"
			(at 198.12 165.1 0)
			(effects
				(font
					(size 1.27 1.27)
				)
				(hide yes)
			)
		)
		(property "Manufacturer" "Bourns"
			(at 175.26 144.78 0)
			(effects
				(font
					(size 1.27 1.27)
					(thickness 0.15)
				)
				(justify left bottom)
				(hide yes)
			)
		)
		(property "MPN" "CR0402-FX-27R0GLF"
			(at 177.8 144.78 0)
			(effects
				(font
					(size 1.27 1.27)
					(thickness 0.15)
				)
				(justify left bottom)
				(hide yes)
			)
		)
		(property "Val" "27R"
			(at 196.85 163.83 90)
			(effects
				(font
					(size 1.27 1.27)
					(thickness 0.15)
				)
				(justify right)
			)
		)
		(property "License" "Apache-2.0"
			(at 172.72 144.78 0)
			(effects
				(font
					(size 1.27 1.27)
					(thickness 0.15)
				)
				(justify left bottom)
				(hide yes)
			)
		)
		(property "Author" "Antmicro"
			(at 170.18 144.78 0)
			(effects
				(font
					(size 1.27 1.27)
					(thickness 0.15)
				)
				(justify left bottom)
				(hide yes)
			)
		)
		(property "Tolerance" "1%"
			(at 187.96 144.78 0)
			(effects
				(font
					(size 1.27 1.27)
				)
				(justify left bottom)
				(hide yes)
			)
		)
		(pin "1"
		)
		(pin "2"
		)
		(instances
			(project "jetson-agx-thor-baseboard"
				(path ""
					(reference "R314")
					(unit 1)
				)
			)
		)
	)
	(symbol
		(lib_id "antmicropower:GND")
		(at 64.77 279.4 0)
		(unit 1)
		(exclude_from_sim no)
		(in_bom yes)
		(on_board yes)
		(dnp no)
		(property "Reference" "#PWR0106"
			(at 64.77 285.75 0)
			(effects
				(font
					(size 1.27 1.27)
				)
				(justify left bottom)
				(hide yes)
			)
		)
		(property "Value" "GND"
			(at 64.77 283.21 0)
			(effects
				(font
					(size 1.27 1.27)
					(thickness 0.15)
				)
			)
		)
		(property "Footprint" ""
			(at 73.66 287.02 0)
			(effects
				(font
					(size 1.27 1.27)
					(thickness 0.15)
				)
				(justify left bottom)
				(hide yes)
			)
		)
		(property "Datasheet" ""
			(at 73.66 292.1 0)
			(effects
				(font
					(size 1.27 1.27)
					(thickness 0.15)
				)
				(justify left bottom)
				(hide yes)
			)
		)
		(property "Description" ""
			(at 64.77 279.4 0)
			(effects
				(font
					(size 1.27 1.27)
				)
				(hide yes)
			)
		)
		(property "Author" "Antmicro"
			(at 73.66 287.02 0)
			(effects
				(font
					(size 1.27 1.27)
					(thickness 0.15)
				)
				(justify left bottom)
				(hide yes)
			)
		)
		(property "License" "Apache-2.0"
			(at 73.66 289.56 0)
			(effects
				(font
					(size 1.27 1.27)
					(thickness 0.15)
				)
				(justify left bottom)
				(hide yes)
			)
		)
		(pin "1"
		)
		(instances
			(project "jetson-agx-thor-baseboard"
				(path ""
					(reference "#PWR0106")
					(unit 1)
				)
			)
		)
	)
	(symbol
		(lib_id "antmicropower:+3V3")
		(at 232.41 257.81 0)
		(unit 1)
		(exclude_from_sim no)
		(in_bom yes)
		(on_board yes)
		(dnp no)
		(property "Reference" "#PWR0157"
			(at 247.65 257.81 0)
			(effects
				(font
					(size 1.27 1.27)
					(thickness 0.15)
				)
				(justify left bottom)
				(hide yes)
			)
		)
		(property "Value" "+3V3"
			(at 231.648 254 0)
			(effects
				(font
					(size 1.27 1.27)
					(thickness 0.15)
				)
			)
		)
		(property "Footprint" ""
			(at 247.65 265.43 0)
			(effects
				(font
					(size 1.27 1.27)
					(thickness 0.15)
				)
				(justify left bottom)
				(hide yes)
			)
		)
		(property "Datasheet" ""
			(at 247.65 267.97 0)
			(effects
				(font
					(size 1.27 1.27)
					(thickness 0.15)
				)
				(justify left bottom)
				(hide yes)
			)
		)
		(property "Description" ""
			(at 232.41 257.81 0)
			(effects
				(font
					(size 1.27 1.27)
				)
				(hide yes)
			)
		)
		(property "Author" "Antmicro"
			(at 247.65 260.35 0)
			(effects
				(font
					(size 1.27 1.27)
					(thickness 0.15)
				)
				(justify left bottom)
				(hide yes)
			)
		)
		(property "License" "Apache-2.0"
			(at 247.65 262.89 0)
			(effects
				(font
					(size 1.27 1.27)
					(thickness 0.15)
				)
				(justify left bottom)
				(hide yes)
			)
		)
		(pin "1"
		)
		(instances
			(project "jetson-agx-thor-baseboard"
				(path ""
					(reference "#PWR0157")
					(unit 1)
				)
			)
		)
	)
	(symbol
		(lib_id "antmicroCapacitorsmisc:C_22u_25V_0805")
		(at 27.94 105.41 90)
		(unit 1)
		(exclude_from_sim no)
		(in_bom yes)
		(on_board yes)
		(dnp no)
		(property "Reference" "C274"
			(at 28.575 100.965 90)
			(effects
				(font
					(size 1.27 1.27)
					(thickness 0.15)
				)
				(justify right)
			)
		)
		(property "Value" "C_22u_25V_0805"
			(at 38.1 85.09 0)
			(effects
				(font
					(size 1.27 1.27)
					(thickness 0.15)
				)
				(justify left bottom)
				(hide yes)
			)
		)
		(property "Footprint" "antmicro-footprints:C_0805_2012Metric"
			(at 40.64 85.09 0)
			(effects
				(font
					(size 1.27 1.27)
					(thickness 0.15)
				)
				(justify left bottom)
				(hide yes)
			)
		)
		(property "Datasheet" "https://product.samsungsem.com/mlcc/CL21A226MAYNNN.do"
			(at 43.18 85.09 0)
			(effects
				(font
					(size 1.27 1.27)
					(thickness 0.15)
				)
				(justify left bottom)
				(hide yes)
			)
		)
		(property "Description" "SMT Multilayer Ceramic Capacitor, 22uF, +/-20%, 25V, X5R, 0805 [2012 Metric]"
			(at 27.94 105.41 0)
			(effects
				(font
					(size 1.27 1.27)
				)
				(hide yes)
			)
		)
		(property "MPN" "CL21A226MAYNNNE"
			(at 45.72 85.09 0)
			(effects
				(font
					(size 1.27 1.27)
					(thickness 0.15)
				)
				(justify left bottom)
				(hide yes)
			)
		)
		(property "Manufacturer" "Samsung Electro-Mechanics"
			(at 48.26 85.09 0)
			(effects
				(font
					(size 1.27 1.27)
					(thickness 0.15)
				)
				(justify left bottom)
				(hide yes)
			)
		)
		(property "License" "Apache-2.0"
			(at 50.8 85.09 0)
			(effects
				(font
					(size 1.27 1.27)
					(thickness 0.15)
				)
				(justify left bottom)
				(hide yes)
			)
		)
		(property "Author" "Antmicro"
			(at 53.34 85.09 0)
			(effects
				(font
					(size 1.27 1.27)
					(thickness 0.15)
				)
				(justify left bottom)
				(hide yes)
			)
		)
		(property "Val" "22u"
			(at 28.575 104.775 90)
			(effects
				(font
					(size 1.27 1.27)
					(thickness 0.15)
				)
				(justify right)
			)
		)
		(property "Voltage" "25V"
			(at 28.575 107.315 90)
			(effects
				(font
					(size 1.27 1.27)
				)
				(justify right)
			)
		)
		(property "Dielectric" "X5R"
			(at 58.42 85.09 0)
			(effects
				(font
					(size 1.27 1.27)
				)
				(justify left bottom)
				(hide yes)
			)
		)
		(property "Public" "False"
			(at 60.96 85.09 0)
			(effects
				(font
					(size 1.27 1.27)
				)
				(justify left bottom)
				(hide yes)
			)
		)
		(pin "1"
		)
		(pin "2"
		)
		(instances
			(project "jetson-agx-thor-baseboard"
				(path ""
					(reference "C274")
					(unit 1)
				)
			)
		)
	)
	(symbol
		(lib_id "antmicroResistorsmisc:R_0R001_0805")
		(at 204.47 203.2 0)
		(unit 1)
		(exclude_from_sim no)
		(in_bom yes)
		(on_board yes)
		(dnp no)
		(property "Reference" "R77"
			(at 207.01 198.12 0)
			(effects
				(font
					(size 1.27 1.27)
					(thickness 0.15)
				)
			)
		)
		(property "Value" "R_0R001_0805"
			(at 224.79 215.9 0)
			(effects
				(font
					(size 1.27 1.27)
					(thickness 0.15)
				)
				(justify left bottom)
				(hide yes)
			)
		)
		(property "Footprint" "antmicro-footprints:R_0805_2012Metric"
			(at 224.79 218.44 0)
			(effects
				(font
					(size 1.27 1.27)
					(thickness 0.15)
				)
				(justify left bottom)
				(hide yes)
			)
		)
		(property "Datasheet" "https://www.eaton.com/content/dam/eaton/products/electronic-components/resources/data-sheet/eaton-msma-automotive-smd-current-sense-resistor-metal-strip-data-sheet-elx1179.pdf"
			(at 224.79 220.98 0)
			(effects
				(font
					(size 1.27 1.27)
					(thickness 0.15)
				)
				(justify left bottom)
				(hide yes)
			)
		)
		(property "Description" "Current Sense Resistors - SMD MSMA, 0805 SIZE, 1/2 Watt, 1 mohm, 50 TCR MnCu Metal AEC-Q"
			(at 204.47 203.2 0)
			(effects
				(font
					(size 1.27 1.27)
				)
				(hide yes)
			)
		)
		(property "MPN" "MSMA0805R0010FSM"
			(at 224.79 223.52 0)
			(effects
				(font
					(size 1.27 1.27)
					(thickness 0.15)
				)
				(justify left bottom)
				(hide yes)
			)
		)
		(property "Manufacturer" "Eaton"
			(at 224.79 226.06 0)
			(effects
				(font
					(size 1.27 1.27)
					(thickness 0.15)
				)
				(justify left bottom)
				(hide yes)
			)
		)
		(property "License" "Apache-2.0"
			(at 224.79 228.6 0)
			(effects
				(font
					(size 1.27 1.27)
					(thickness 0.15)
				)
				(justify left bottom)
				(hide yes)
			)
		)
		(property "Author" "Antmicro"
			(at 224.79 231.14 0)
			(effects
				(font
					(size 1.27 1.27)
					(thickness 0.15)
				)
				(justify left bottom)
				(hide yes)
			)
		)
		(property "Val" "0R001"
			(at 207.01 200.66 0)
			(effects
				(font
					(size 1.27 1.27)
					(thickness 0.15)
				)
			)
		)
		(property "Tolerance" "1%"
			(at 224.79 213.36 0)
			(effects
				(font
					(size 1.27 1.27)
				)
				(justify left bottom)
				(hide yes)
			)
		)
		(property "Public" "False"
			(at 224.79 233.68 0)
			(effects
				(font
					(size 1.27 1.27)
				)
				(justify left bottom)
				(hide yes)
			)
		)
		(pin "2"
		)
		(pin "1"
		)
		(instances
			(project "jetson-agx-thor-baseboard"
				(path ""
					(reference "R77")
					(unit 1)
				)
			)
		)
	)
	(symbol
		(lib_id "antmicroCapacitorsmisc:C_22u_25V_0805")
		(at 34.29 105.41 90)
		(unit 1)
		(exclude_from_sim no)
		(in_bom yes)
		(on_board yes)
		(dnp no)
		(property "Reference" "C276"
			(at 34.925 100.965 90)
			(effects
				(font
					(size 1.27 1.27)
					(thickness 0.15)
				)
				(justify right)
			)
		)
		(property "Value" "C_22u_25V_0805"
			(at 44.45 85.09 0)
			(effects
				(font
					(size 1.27 1.27)
					(thickness 0.15)
				)
				(justify left bottom)
				(hide yes)
			)
		)
		(property "Footprint" "antmicro-footprints:C_0805_2012Metric"
			(at 46.99 85.09 0)
			(effects
				(font
					(size 1.27 1.27)
					(thickness 0.15)
				)
				(justify left bottom)
				(hide yes)
			)
		)
		(property "Datasheet" "https://product.samsungsem.com/mlcc/CL21A226MAYNNN.do"
			(at 49.53 85.09 0)
			(effects
				(font
					(size 1.27 1.27)
					(thickness 0.15)
				)
				(justify left bottom)
				(hide yes)
			)
		)
		(property "Description" "SMT Multilayer Ceramic Capacitor, 22uF, +/-20%, 25V, X5R, 0805 [2012 Metric]"
			(at 34.29 105.41 0)
			(effects
				(font
					(size 1.27 1.27)
				)
				(hide yes)
			)
		)
		(property "MPN" "CL21A226MAYNNNE"
			(at 52.07 85.09 0)
			(effects
				(font
					(size 1.27 1.27)
					(thickness 0.15)
				)
				(justify left bottom)
				(hide yes)
			)
		)
		(property "Manufacturer" "Samsung Electro-Mechanics"
			(at 54.61 85.09 0)
			(effects
				(font
					(size 1.27 1.27)
					(thickness 0.15)
				)
				(justify left bottom)
				(hide yes)
			)
		)
		(property "License" "Apache-2.0"
			(at 57.15 85.09 0)
			(effects
				(font
					(size 1.27 1.27)
					(thickness 0.15)
				)
				(justify left bottom)
				(hide yes)
			)
		)
		(property "Author" "Antmicro"
			(at 59.69 85.09 0)
			(effects
				(font
					(size 1.27 1.27)
					(thickness 0.15)
				)
				(justify left bottom)
				(hide yes)
			)
		)
		(property "Val" "22u"
			(at 34.925 104.775 90)
			(effects
				(font
					(size 1.27 1.27)
					(thickness 0.15)
				)
				(justify right)
			)
		)
		(property "Voltage" "25V"
			(at 34.925 107.315 90)
			(effects
				(font
					(size 1.27 1.27)
				)
				(justify right)
			)
		)
		(property "Dielectric" "X5R"
			(at 64.77 85.09 0)
			(effects
				(font
					(size 1.27 1.27)
				)
				(justify left bottom)
				(hide yes)
			)
		)
		(property "Public" "False"
			(at 67.31 85.09 0)
			(effects
				(font
					(size 1.27 1.27)
				)
				(justify left bottom)
				(hide yes)
			)
		)
		(pin "2"
		)
		(pin "1"
		)
		(instances
			(project "jetson-agx-thor-baseboard"
				(path ""
					(reference "C276")
					(unit 1)
				)
			)
		)
	)
	(symbol
		(lib_id "antmicropower:+3V3_AON")
		(at 179.07 187.96 0)
		(unit 1)
		(exclude_from_sim no)
		(in_bom yes)
		(on_board yes)
		(dnp no)
		(property "Reference" "#PWR0655"
			(at 179.07 191.77 0)
			(effects
				(font
					(size 1.27 1.27)
				)
				(hide yes)
			)
		)
		(property "Value" "+3V3_AON"
			(at 179.07 184.15 0)
			(effects
				(font
					(size 1.27 1.27)
				)
			)
		)
		(property "Footprint" ""
			(at 179.07 187.96 0)
			(effects
				(font
					(size 1.27 1.27)
				)
				(hide yes)
			)
		)
		(property "Datasheet" ""
			(at 179.07 187.96 0)
			(effects
				(font
					(size 1.27 1.27)
				)
				(hide yes)
			)
		)
		(property "Description" ""
			(at 179.07 187.96 0)
			(effects
				(font
					(size 1.27 1.27)
				)
				(hide yes)
			)
		)
		(pin "1"
		)
		(instances
			(project "jetson-agx-thor-baseboard"
				(path ""
					(reference "#PWR0655")
					(unit 1)
				)
			)
		)
	)
	(symbol
		(lib_id "antmicropower:GND")
		(at 48.26 232.41 0)
		(unit 1)
		(exclude_from_sim no)
		(in_bom yes)
		(on_board yes)
		(dnp no)
		(property "Reference" "#PWR099"
			(at 48.26 238.76 0)
			(effects
				(font
					(size 1.27 1.27)
				)
				(justify left bottom)
				(hide yes)
			)
		)
		(property "Value" "GND"
			(at 48.26 236.22 0)
			(effects
				(font
					(size 1.27 1.27)
					(thickness 0.15)
				)
			)
		)
		(property "Footprint" ""
			(at 57.15 240.03 0)
			(effects
				(font
					(size 1.27 1.27)
					(thickness 0.15)
				)
				(justify left bottom)
				(hide yes)
			)
		)
		(property "Datasheet" ""
			(at 57.15 245.11 0)
			(effects
				(font
					(size 1.27 1.27)
					(thickness 0.15)
				)
				(justify left bottom)
				(hide yes)
			)
		)
		(property "Description" ""
			(at 48.26 232.41 0)
			(effects
				(font
					(size 1.27 1.27)
				)
				(hide yes)
			)
		)
		(property "Author" "Antmicro"
			(at 57.15 240.03 0)
			(effects
				(font
					(size 1.27 1.27)
					(thickness 0.15)
				)
				(justify left bottom)
				(hide yes)
			)
		)
		(property "License" "Apache-2.0"
			(at 57.15 242.57 0)
			(effects
				(font
					(size 1.27 1.27)
					(thickness 0.15)
				)
				(justify left bottom)
				(hide yes)
			)
		)
		(pin "1"
		)
		(instances
			(project "jetson-agx-thor-baseboard"
				(path ""
					(reference "#PWR099")
					(unit 1)
				)
			)
		)
	)
	(symbol
		(lib_id "antmicropower:GND")
		(at 153.67 176.53 0)
		(unit 1)
		(exclude_from_sim no)
		(in_bom yes)
		(on_board yes)
		(dnp no)
		(property "Reference" "#PWR0755"
			(at 153.67 182.88 0)
			(effects
				(font
					(size 1.27 1.27)
				)
				(justify left bottom)
				(hide yes)
			)
		)
		(property "Value" "GND"
			(at 153.67 180.34 0)
			(effects
				(font
					(size 1.27 1.27)
					(thickness 0.15)
				)
			)
		)
		(property "Footprint" ""
			(at 162.56 184.15 0)
			(effects
				(font
					(size 1.27 1.27)
					(thickness 0.15)
				)
				(justify left bottom)
				(hide yes)
			)
		)
		(property "Datasheet" ""
			(at 162.56 189.23 0)
			(effects
				(font
					(size 1.27 1.27)
					(thickness 0.15)
				)
				(justify left bottom)
				(hide yes)
			)
		)
		(property "Description" ""
			(at 153.67 176.53 0)
			(effects
				(font
					(size 1.27 1.27)
				)
				(hide yes)
			)
		)
		(property "Author" "Antmicro"
			(at 162.56 184.15 0)
			(effects
				(font
					(size 1.27 1.27)
					(thickness 0.15)
				)
				(justify left bottom)
				(hide yes)
			)
		)
		(property "License" "Apache-2.0"
			(at 162.56 186.69 0)
			(effects
				(font
					(size 1.27 1.27)
					(thickness 0.15)
				)
				(justify left bottom)
				(hide yes)
			)
		)
		(pin "1"
		)
		(instances
			(project "jetson-agx-thor-baseboard"
				(path ""
					(reference "#PWR0755")
					(unit 1)
				)
			)
		)
	)
	(symbol
		(lib_id "antmicroCapacitors0402:C_100n_0402")
		(at 214.63 43.18 180)
		(unit 1)
		(exclude_from_sim no)
		(in_bom yes)
		(on_board yes)
		(dnp no)
		(property "Reference" "C385"
			(at 212.09 37.846 0)
			(effects
				(font
					(size 1.27 1.27)
				)
			)
		)
		(property "Value" "C_100n_0402"
			(at 194.31 33.02 0)
			(effects
				(font
					(size 1.27 1.27)
					(thickness 0.15)
				)
				(justify left bottom)
				(hide yes)
			)
		)
		(property "Footprint" "antmicro-footprints:C_0402_1005Metric"
			(at 194.31 30.48 0)
			(effects
				(font
					(size 1.27 1.27)
					(thickness 0.15)
				)
				(justify left bottom)
				(hide yes)
			)
		)
		(property "Datasheet" "https://www.murata.com/products/productdetail?partno=GRM155R61H104KE14%23"
			(at 194.31 27.94 0)
			(effects
				(font
					(size 1.27 1.27)
					(thickness 0.15)
				)
				(justify left bottom)
				(hide yes)
			)
		)
		(property "Description" "SMD Multilayer Ceramic Capacitor, 0.1 µF, 50 V, 0402 [1005 Metric], ± 10%, X5R, GRM Series"
			(at 214.63 43.18 0)
			(effects
				(font
					(size 1.27 1.27)
				)
				(hide yes)
			)
		)
		(property "Manufacturer" "Murata"
			(at 194.31 22.86 0)
			(effects
				(font
					(size 1.27 1.27)
					(thickness 0.15)
				)
				(justify left bottom)
				(hide yes)
			)
		)
		(property "MPN" "GRM155R61H104KE14D"
			(at 194.31 25.4 0)
			(effects
				(font
					(size 1.27 1.27)
					(thickness 0.15)
				)
				(justify left bottom)
				(hide yes)
			)
		)
		(property "Val" "100n"
			(at 212.09 40.386 0)
			(effects
				(font
					(size 1.27 1.27)
					(thickness 0.15)
				)
			)
		)
		(property "License" "Apache-2.0"
			(at 194.31 20.32 0)
			(effects
				(font
					(size 1.27 1.27)
					(thickness 0.15)
				)
				(justify left bottom)
				(hide yes)
			)
		)
		(property "Author" "Antmicro"
			(at 194.31 17.78 0)
			(effects
				(font
					(size 1.27 1.27)
					(thickness 0.15)
				)
				(justify left bottom)
				(hide yes)
			)
		)
		(property "Voltage" "50V"
			(at 194.31 15.24 0)
			(effects
				(font
					(size 1.27 1.27)
				)
				(justify left bottom)
				(hide yes)
			)
		)
		(property "Dielectric" "X5R"
			(at 194.31 12.7 0)
			(effects
				(font
					(size 1.27 1.27)
				)
				(justify left bottom)
				(hide yes)
			)
		)
		(pin "1"
		)
		(pin "2"
		)
		(instances
			(project "jetson-agx-thor-baseboard"
				(path ""
					(reference "C385")
					(unit 1)
				)
			)
		)
	)
	(symbol
		(lib_id "antmicroDCDCConverters:SIC437AED-T1-GE3")
		(at 92.71 162.56 0)
		(unit 1)
		(exclude_from_sim no)
		(in_bom yes)
		(on_board yes)
		(dnp no)
		(property "Reference" "U75"
			(at 103.505 156.21 0)
			(effects
				(font
					(size 1.27 1.27)
					(thickness 0.15)
				)
			)
		)
		(property "Value" "SIC437AED-T1-GE3"
			(at 125.73 170.18 0)
			(effects
				(font
					(size 1.27 1.27)
					(thickness 0.15)
				)
				(justify left bottom)
				(hide yes)
			)
		)
		(property "Footprint" "antmicro-footprints:MLP44-24L_4x4x0.75mm"
			(at 125.73 172.72 0)
			(effects
				(font
					(size 1.27 1.27)
					(thickness 0.15)
				)
				(justify left bottom)
				(hide yes)
			)
		)
		(property "Datasheet" "https://www.vishay.com/docs/75921/sic437.pdf"
			(at 125.73 175.26 0)
			(effects
				(font
					(size 1.27 1.27)
					(thickness 0.15)
				)
				(justify left bottom)
				(hide yes)
			)
		)
		(property "Description" "DC/DC Buck Step Down Regulator Adjustable, 4.5-28V In, 0.6V to 20V/12A Out, 1MHz, PowerPAK MLP44-24"
			(at 125.73 185.42 0)
			(effects
				(font
					(size 1.27 1.27)
				)
				(justify left bottom)
				(hide yes)
			)
		)
		(property "Manufacturer" "Vishay"
			(at 125.73 177.8 0)
			(effects
				(font
					(size 1.27 1.27)
					(thickness 0.15)
				)
				(justify left bottom)
				(hide yes)
			)
		)
		(property "MPN" "SIC437AED-T1-GE3"
			(at 103.505 158.75 0)
			(effects
				(font
					(size 1.27 1.27)
					(thickness 0.15)
				)
			)
		)
		(property "Author" "Antmicro"
			(at 125.73 180.34 0)
			(effects
				(font
					(size 1.27 1.27)
					(thickness 0.15)
				)
				(justify left bottom)
				(hide yes)
			)
		)
		(property "License" "Apache-2.0"
			(at 125.73 182.88 0)
			(effects
				(font
					(size 1.27 1.27)
					(thickness 0.15)
				)
				(justify left bottom)
				(hide yes)
			)
		)
		(pin "7"
		)
		(pin "16"
		)
		(pin "18"
		)
		(pin "8"
		)
		(pin "15"
		)
		(pin "14"
		)
		(pin "20"
		)
		(pin "2"
		)
		(pin "12"
		)
		(pin "22"
		)
		(pin "11"
		)
		(pin "26"
		)
		(pin "10"
		)
		(pin "19"
		)
		(pin "5"
		)
		(pin "4"
		)
		(pin "17"
		)
		(pin "6"
		)
		(pin "3"
		)
		(pin "1"
		)
		(pin "13"
		)
		(pin "23"
		)
		(pin "25"
		)
		(pin "21"
		)
		(pin "24"
		)
		(pin "9"
		)
		(pin "27"
		)
		(pin "28"
		)
		(instances
			(project "jetson-agx-thor-baseboard"
				(path ""
					(reference "U75")
					(unit 1)
				)
			)
		)
	)
	(symbol
		(lib_id "antmicroResistors0402:R_27R_0402")
		(at 215.9 209.55 90)
		(unit 1)
		(exclude_from_sim no)
		(in_bom yes)
		(on_board yes)
		(dnp no)
		(property "Reference" "R368"
			(at 216.916 205.7399 90)
			(effects
				(font
					(size 1.27 1.27)
				)
				(justify right)
			)
		)
		(property "Value" "R_27R_0402"
			(at 228.6 189.23 0)
			(effects
				(font
					(size 1.27 1.27)
					(thickness 0.15)
				)
				(justify left bottom)
				(hide yes)
			)
		)
		(property "Footprint" "antmicro-footprints:R_0402_1005Metric"
			(at 231.14 189.23 0)
			(effects
				(font
					(size 1.27 1.27)
					(thickness 0.15)
				)
				(justify left bottom)
				(hide yes)
			)
		)
		(property "Datasheet" "https://www.bourns.com/docs/product-datasheets/cr.pdf"
			(at 233.68 189.23 0)
			(effects
				(font
					(size 1.27 1.27)
					(thickness 0.15)
				)
				(justify left bottom)
				(hide yes)
			)
		)
		(property "Description" "SMD Chip Resistor, 27 ohm, ± 1%, 63 mW, 0402 [1005 Metric], Thick Film, General Purpose"
			(at 215.9 209.55 0)
			(effects
				(font
					(size 1.27 1.27)
				)
				(hide yes)
			)
		)
		(property "Manufacturer" "Bourns"
			(at 238.76 189.23 0)
			(effects
				(font
					(size 1.27 1.27)
					(thickness 0.15)
				)
				(justify left bottom)
				(hide yes)
			)
		)
		(property "MPN" "CR0402-FX-27R0GLF"
			(at 236.22 189.23 0)
			(effects
				(font
					(size 1.27 1.27)
					(thickness 0.15)
				)
				(justify left bottom)
				(hide yes)
			)
		)
		(property "Val" "27R"
			(at 216.916 208.28 90)
			(effects
				(font
					(size 1.27 1.27)
					(thickness 0.15)
				)
				(justify right)
			)
		)
		(property "License" "Apache-2.0"
			(at 241.3 189.23 0)
			(effects
				(font
					(size 1.27 1.27)
					(thickness 0.15)
				)
				(justify left bottom)
				(hide yes)
			)
		)
		(property "Author" "Antmicro"
			(at 243.84 189.23 0)
			(effects
				(font
					(size 1.27 1.27)
					(thickness 0.15)
				)
				(justify left bottom)
				(hide yes)
			)
		)
		(property "Tolerance" "1%"
			(at 226.06 189.23 0)
			(effects
				(font
					(size 1.27 1.27)
				)
				(justify left bottom)
				(hide yes)
			)
		)
		(pin "1"
		)
		(pin "2"
		)
		(instances
			(project "jetson-agx-thor-baseboard"
				(path ""
					(reference "R368")
					(unit 1)
				)
			)
		)
	)
	(symbol
		(lib_id "antmicropower:GND")
		(at 185.42 44.45 0)
		(unit 1)
		(exclude_from_sim no)
		(in_bom yes)
		(on_board yes)
		(dnp no)
		(property "Reference" "#PWR0584"
			(at 185.42 50.8 0)
			(effects
				(font
					(size 1.27 1.27)
				)
				(justify left bottom)
				(hide yes)
			)
		)
		(property "Value" "GND"
			(at 185.42 48.26 0)
			(effects
				(font
					(size 1.27 1.27)
					(thickness 0.15)
				)
			)
		)
		(property "Footprint" ""
			(at 194.31 52.07 0)
			(effects
				(font
					(size 1.27 1.27)
					(thickness 0.15)
				)
				(justify left bottom)
				(hide yes)
			)
		)
		(property "Datasheet" ""
			(at 194.31 57.15 0)
			(effects
				(font
					(size 1.27 1.27)
					(thickness 0.15)
				)
				(justify left bottom)
				(hide yes)
			)
		)
		(property "Description" ""
			(at 185.42 44.45 0)
			(effects
				(font
					(size 1.27 1.27)
				)
				(hide yes)
			)
		)
		(property "Author" "Antmicro"
			(at 194.31 52.07 0)
			(effects
				(font
					(size 1.27 1.27)
					(thickness 0.15)
				)
				(justify left bottom)
				(hide yes)
			)
		)
		(property "License" "Apache-2.0"
			(at 194.31 54.61 0)
			(effects
				(font
					(size 1.27 1.27)
					(thickness 0.15)
				)
				(justify left bottom)
				(hide yes)
			)
		)
		(pin "1"
		)
		(instances
			(project "jetson-agx-thor-baseboard"
				(path ""
					(reference "#PWR0584")
					(unit 1)
				)
			)
		)
	)
	(symbol
		(lib_id "antmicroFixedInductors:L_560n_17.7A_Bourns-SRP5030CA")
		(at 134.62 259.08 0)
		(unit 1)
		(exclude_from_sim no)
		(in_bom yes)
		(on_board yes)
		(dnp no)
		(fields_autoplaced yes)
		(property "Reference" "L2"
			(at 137.16 254 0)
			(effects
				(font
					(size 1.27 1.27)
					(thickness 0.15)
				)
			)
		)
		(property "Value" "L_560n_17.7A_Bourns-SRP5030CA"
			(at 148.59 261.62 0)
			(effects
				(font
					(size 1.27 1.27)
					(thickness 0.15)
				)
				(justify left bottom)
				(hide yes)
			)
		)
		(property "Footprint" "antmicro-footprints:L_Bourns-SRP5030CA"
			(at 148.59 266.7 0)
			(effects
				(font
					(size 1.27 1.27)
					(thickness 0.15)
				)
				(justify left bottom)
				(hide yes)
			)
		)
		(property "Datasheet" "https://www.bourns.com/docs/Product-Datasheets/SRP5030CA.pdf"
			(at 148.59 269.24 0)
			(effects
				(font
					(size 1.27 1.27)
					(thickness 0.15)
				)
				(justify left bottom)
				(hide yes)
			)
		)
		(property "Description" "Power Inductor (SMT), 560 nH, 17.7 A, Shielded, 22.2 A, SRP5030CA"
			(at 134.62 259.08 0)
			(effects
				(font
					(size 1.27 1.27)
				)
				(hide yes)
			)
		)
		(property "Val" "560n/17.7A"
			(at 137.16 256.54 0)
			(effects
				(font
					(size 1.27 1.27)
					(thickness 0.15)
				)
			)
		)
		(property "Manufacturer" "Bourns"
			(at 148.59 271.78 0)
			(effects
				(font
					(size 1.27 1.27)
					(thickness 0.15)
				)
				(justify left bottom)
				(hide yes)
			)
		)
		(property "MPN" "SRP5030CA-R56M"
			(at 148.59 274.32 0)
			(effects
				(font
					(size 1.27 1.27)
					(thickness 0.15)
				)
				(justify left bottom)
				(hide yes)
			)
		)
		(property "ISat" "22.2 A"
			(at 148.59 275.59 0)
			(effects
				(font
					(size 1.27 1.27)
				)
				(justify left)
				(hide yes)
			)
		)
		(property "IMax" "17.7 A"
			(at 148.59 279.4 0)
			(effects
				(font
					(size 1.27 1.27)
					(thickness 0.15)
				)
				(justify left bottom)
				(hide yes)
			)
		)
		(property "Size" "5.5x5.3"
			(at 148.59 281.94 0)
			(effects
				(font
					(size 1.27 1.27)
					(thickness 0.15)
				)
				(justify left bottom)
				(hide yes)
			)
		)
		(property "Author" "Antmicro"
			(at 148.59 284.48 0)
			(effects
				(font
					(size 1.27 1.27)
					(thickness 0.15)
				)
				(justify left bottom)
				(hide yes)
			)
		)
		(property "License" "Apache-2.0"
			(at 148.59 287.02 0)
			(effects
				(font
					(size 1.27 1.27)
					(thickness 0.15)
				)
				(justify left bottom)
				(hide yes)
			)
		)
		(pin "2"
		)
		(pin "1"
		)
		(instances
			(project "jetson-agx-thor-baseboard"
				(path ""
					(reference "L2")
					(unit 1)
				)
			)
		)
	)
	(symbol
		(lib_id "antmicropower:GND")
		(at 83.82 232.41 0)
		(unit 1)
		(exclude_from_sim no)
		(in_bom yes)
		(on_board yes)
		(dnp no)
		(property "Reference" "#PWR0113"
			(at 83.82 238.76 0)
			(effects
				(font
					(size 1.27 1.27)
				)
				(justify left bottom)
				(hide yes)
			)
		)
		(property "Value" "GND"
			(at 83.82 236.22 0)
			(effects
				(font
					(size 1.27 1.27)
					(thickness 0.15)
				)
			)
		)
		(property "Footprint" ""
			(at 92.71 240.03 0)
			(effects
				(font
					(size 1.27 1.27)
					(thickness 0.15)
				)
				(justify left bottom)
				(hide yes)
			)
		)
		(property "Datasheet" ""
			(at 92.71 245.11 0)
			(effects
				(font
					(size 1.27 1.27)
					(thickness 0.15)
				)
				(justify left bottom)
				(hide yes)
			)
		)
		(property "Description" ""
			(at 83.82 232.41 0)
			(effects
				(font
					(size 1.27 1.27)
				)
				(hide yes)
			)
		)
		(property "Author" "Antmicro"
			(at 92.71 240.03 0)
			(effects
				(font
					(size 1.27 1.27)
					(thickness 0.15)
				)
				(justify left bottom)
				(hide yes)
			)
		)
		(property "License" "Apache-2.0"
			(at 92.71 242.57 0)
			(effects
				(font
					(size 1.27 1.27)
					(thickness 0.15)
				)
				(justify left bottom)
				(hide yes)
			)
		)
		(pin "1"
		)
		(instances
			(project "jetson-agx-thor-baseboard"
				(path ""
					(reference "#PWR0113")
					(unit 1)
				)
			)
		)
	)
	(symbol
		(lib_id "antmicroCapacitors0402:C_100n_0402")
		(at 209.55 257.81 180)
		(unit 1)
		(exclude_from_sim no)
		(in_bom yes)
		(on_board yes)
		(dnp no)
		(property "Reference" "C384"
			(at 207.01 252.476 0)
			(effects
				(font
					(size 1.27 1.27)
				)
			)
		)
		(property "Value" "C_100n_0402"
			(at 189.23 247.65 0)
			(effects
				(font
					(size 1.27 1.27)
					(thickness 0.15)
				)
				(justify left bottom)
				(hide yes)
			)
		)
		(property "Footprint" "antmicro-footprints:C_0402_1005Metric"
			(at 189.23 245.11 0)
			(effects
				(font
					(size 1.27 1.27)
					(thickness 0.15)
				)
				(justify left bottom)
				(hide yes)
			)
		)
		(property "Datasheet" "https://www.murata.com/products/productdetail?partno=GRM155R61H104KE14%23"
			(at 189.23 242.57 0)
			(effects
				(font
					(size 1.27 1.27)
					(thickness 0.15)
				)
				(justify left bottom)
				(hide yes)
			)
		)
		(property "Description" "SMD Multilayer Ceramic Capacitor, 0.1 µF, 50 V, 0402 [1005 Metric], ± 10%, X5R, GRM Series"
			(at 209.55 257.81 0)
			(effects
				(font
					(size 1.27 1.27)
				)
				(hide yes)
			)
		)
		(property "Manufacturer" "Murata"
			(at 189.23 237.49 0)
			(effects
				(font
					(size 1.27 1.27)
					(thickness 0.15)
				)
				(justify left bottom)
				(hide yes)
			)
		)
		(property "MPN" "GRM155R61H104KE14D"
			(at 189.23 240.03 0)
			(effects
				(font
					(size 1.27 1.27)
					(thickness 0.15)
				)
				(justify left bottom)
				(hide yes)
			)
		)
		(property "Val" "100n"
			(at 207.01 255.016 0)
			(effects
				(font
					(size 1.27 1.27)
					(thickness 0.15)
				)
			)
		)
		(property "License" "Apache-2.0"
			(at 189.23 234.95 0)
			(effects
				(font
					(size 1.27 1.27)
					(thickness 0.15)
				)
				(justify left bottom)
				(hide yes)
			)
		)
		(property "Author" "Antmicro"
			(at 189.23 232.41 0)
			(effects
				(font
					(size 1.27 1.27)
					(thickness 0.15)
				)
				(justify left bottom)
				(hide yes)
			)
		)
		(property "Voltage" "50V"
			(at 189.23 229.87 0)
			(effects
				(font
					(size 1.27 1.27)
				)
				(justify left bottom)
				(hide yes)
			)
		)
		(property "Dielectric" "X5R"
			(at 189.23 227.33 0)
			(effects
				(font
					(size 1.27 1.27)
				)
				(justify left bottom)
				(hide yes)
			)
		)
		(pin "1"
		)
		(pin "2"
		)
		(instances
			(project "jetson-agx-thor-baseboard"
				(path ""
					(reference "C384")
					(unit 1)
				)
			)
		)
	)
	(symbol
		(lib_id "antmicropower:GND")
		(at 374.65 49.53 0)
		(mirror y)
		(unit 1)
		(exclude_from_sim no)
		(in_bom yes)
		(on_board yes)
		(dnp no)
		(property "Reference" "#PWR072"
			(at 374.65 55.88 0)
			(effects
				(font
					(size 1.27 1.27)
				)
				(justify left bottom)
				(hide yes)
			)
		)
		(property "Value" "GND"
			(at 374.65 53.34 0)
			(effects
				(font
					(size 1.27 1.27)
					(thickness 0.15)
				)
			)
		)
		(property "Footprint" ""
			(at 365.76 57.15 0)
			(effects
				(font
					(size 1.27 1.27)
					(thickness 0.15)
				)
				(justify left bottom)
				(hide yes)
			)
		)
		(property "Datasheet" ""
			(at 365.76 62.23 0)
			(effects
				(font
					(size 1.27 1.27)
					(thickness 0.15)
				)
				(justify left bottom)
				(hide yes)
			)
		)
		(property "Description" ""
			(at 374.65 49.53 0)
			(effects
				(font
					(size 1.27 1.27)
				)
				(hide yes)
			)
		)
		(property "Author" "Antmicro"
			(at 365.76 57.15 0)
			(effects
				(font
					(size 1.27 1.27)
					(thickness 0.15)
				)
				(justify left bottom)
				(hide yes)
			)
		)
		(property "License" "Apache-2.0"
			(at 365.76 59.69 0)
			(effects
				(font
					(size 1.27 1.27)
					(thickness 0.15)
				)
				(justify left bottom)
				(hide yes)
			)
		)
		(pin "1"
		)
		(instances
			(project "jetson-agx-thor-baseboard"
				(path ""
					(reference "#PWR072")
					(unit 1)
				)
			)
		)
	)
	(symbol
		(lib_id "antmicroResistors0402:R_499k_0402")
		(at 58.42 171.45 90)
		(unit 1)
		(exclude_from_sim no)
		(in_bom no)
		(on_board yes)
		(dnp yes)
		(property "Reference" "R309"
			(at 59.69 167.64 90)
			(effects
				(font
					(size 1.27 1.27)
					(thickness 0.15)
				)
				(justify right)
			)
		)
		(property "Value" "R_499k_0402"
			(at 71.12 151.13 0)
			(effects
				(font
					(size 1.27 1.27)
					(thickness 0.15)
				)
				(justify left bottom)
				(hide yes)
			)
		)
		(property "Footprint" "antmicro-footprints:R_0402_1005Metric"
			(at 73.66 151.13 0)
			(effects
				(font
					(size 1.27 1.27)
					(thickness 0.15)
				)
				(justify left bottom)
				(hide yes)
			)
		)
		(property "Datasheet" "https://www.mouser.com/datasheet/2/54/cr-1858361.pdf"
			(at 76.2 151.13 0)
			(effects
				(font
					(size 1.27 1.27)
					(thickness 0.15)
				)
				(justify left bottom)
				(hide yes)
			)
		)
		(property "Description" "SMD Chip Resistor, 499 kohm, ± 1%, 63 mW, 0402 [1005 Metric], Thick Film, General Purpose"
			(at 58.42 171.45 0)
			(effects
				(font
					(size 1.27 1.27)
				)
				(hide yes)
			)
		)
		(property "MPN" "CR0402-FX-4993GLF"
			(at 78.74 151.13 0)
			(effects
				(font
					(size 1.27 1.27)
					(thickness 0.15)
				)
				(justify left bottom)
				(hide yes)
			)
		)
		(property "Manufacturer" "Bourns"
			(at 81.28 151.13 0)
			(effects
				(font
					(size 1.27 1.27)
					(thickness 0.15)
				)
				(justify left bottom)
				(hide yes)
			)
		)
		(property "License" "Apache-2.0"
			(at 83.82 151.13 0)
			(effects
				(font
					(size 1.27 1.27)
					(thickness 0.15)
				)
				(justify left bottom)
				(hide yes)
			)
		)
		(property "Author" "Antmicro"
			(at 86.36 151.13 0)
			(effects
				(font
					(size 1.27 1.27)
					(thickness 0.15)
				)
				(justify left bottom)
				(hide yes)
			)
		)
		(property "Val" "499k"
			(at 59.69 170.18 90)
			(effects
				(font
					(size 1.27 1.27)
					(thickness 0.15)
				)
				(justify right)
			)
		)
		(property "Tolerance" "1%"
			(at 68.58 151.13 0)
			(effects
				(font
					(size 1.27 1.27)
				)
				(justify left bottom)
				(hide yes)
			)
		)
		(pin "2"
		)
		(pin "1"
		)
		(instances
			(project "jetson-agx-thor-baseboard"
				(path ""
					(reference "R309")
					(unit 1)
				)
			)
		)
	)
	(symbol
		(lib_id "antmicropower:GND")
		(at 162.56 74.93 0)
		(unit 1)
		(exclude_from_sim no)
		(in_bom yes)
		(on_board yes)
		(dnp no)
		(property "Reference" "#PWR0594"
			(at 162.56 81.28 0)
			(effects
				(font
					(size 1.27 1.27)
				)
				(justify left bottom)
				(hide yes)
			)
		)
		(property "Value" "GND"
			(at 162.56 78.74 0)
			(effects
				(font
					(size 1.27 1.27)
					(thickness 0.15)
				)
			)
		)
		(property "Footprint" ""
			(at 171.45 82.55 0)
			(effects
				(font
					(size 1.27 1.27)
					(thickness 0.15)
				)
				(justify left bottom)
				(hide yes)
			)
		)
		(property "Datasheet" ""
			(at 171.45 87.63 0)
			(effects
				(font
					(size 1.27 1.27)
					(thickness 0.15)
				)
				(justify left bottom)
				(hide yes)
			)
		)
		(property "Description" ""
			(at 162.56 74.93 0)
			(effects
				(font
					(size 1.27 1.27)
				)
				(hide yes)
			)
		)
		(property "Author" "Antmicro"
			(at 171.45 82.55 0)
			(effects
				(font
					(size 1.27 1.27)
					(thickness 0.15)
				)
				(justify left bottom)
				(hide yes)
			)
		)
		(property "License" "Apache-2.0"
			(at 171.45 85.09 0)
			(effects
				(font
					(size 1.27 1.27)
					(thickness 0.15)
				)
				(justify left bottom)
				(hide yes)
			)
		)
		(pin "1"
		)
		(instances
			(project "jetson-agx-thor-baseboard"
				(path ""
					(reference "#PWR0594")
					(unit 1)
				)
			)
		)
	)
	(symbol
		(lib_id "antmicropower:GND")
		(at 72.39 232.41 0)
		(unit 1)
		(exclude_from_sim no)
		(in_bom yes)
		(on_board yes)
		(dnp no)
		(property "Reference" "#PWR0110"
			(at 72.39 238.76 0)
			(effects
				(font
					(size 1.27 1.27)
				)
				(justify left bottom)
				(hide yes)
			)
		)
		(property "Value" "GND"
			(at 72.39 236.22 0)
			(effects
				(font
					(size 1.27 1.27)
					(thickness 0.15)
				)
			)
		)
		(property "Footprint" ""
			(at 81.28 240.03 0)
			(effects
				(font
					(size 1.27 1.27)
					(thickness 0.15)
				)
				(justify left bottom)
				(hide yes)
			)
		)
		(property "Datasheet" ""
			(at 81.28 245.11 0)
			(effects
				(font
					(size 1.27 1.27)
					(thickness 0.15)
				)
				(justify left bottom)
				(hide yes)
			)
		)
		(property "Description" ""
			(at 72.39 232.41 0)
			(effects
				(font
					(size 1.27 1.27)
				)
				(hide yes)
			)
		)
		(property "Author" "Antmicro"
			(at 81.28 240.03 0)
			(effects
				(font
					(size 1.27 1.27)
					(thickness 0.15)
				)
				(justify left bottom)
				(hide yes)
			)
		)
		(property "License" "Apache-2.0"
			(at 81.28 242.57 0)
			(effects
				(font
					(size 1.27 1.27)
					(thickness 0.15)
				)
				(justify left bottom)
				(hide yes)
			)
		)
		(pin "1"
		)
		(instances
			(project "jetson-agx-thor-baseboard"
				(path ""
					(reference "#PWR0110")
					(unit 1)
				)
			)
		)
	)
	(symbol
		(lib_id "antmicroResistors0402:R_27R_0402")
		(at 203.2 107.95 270)
		(mirror x)
		(unit 1)
		(exclude_from_sim no)
		(in_bom yes)
		(on_board yes)
		(dnp no)
		(property "Reference" "R365"
			(at 200.66 104.1399 90)
			(effects
				(font
					(size 1.27 1.27)
				)
				(justify right)
			)
		)
		(property "Value" "R_27R_0402"
			(at 190.5 87.63 0)
			(effects
				(font
					(size 1.27 1.27)
					(thickness 0.15)
				)
				(justify left bottom)
				(hide yes)
			)
		)
		(property "Footprint" "antmicro-footprints:R_0402_1005Metric"
			(at 187.96 87.63 0)
			(effects
				(font
					(size 1.27 1.27)
					(thickness 0.15)
				)
				(justify left bottom)
				(hide yes)
			)
		)
		(property "Datasheet" "https://www.bourns.com/docs/product-datasheets/cr.pdf"
			(at 185.42 87.63 0)
			(effects
				(font
					(size 1.27 1.27)
					(thickness 0.15)
				)
				(justify left bottom)
				(hide yes)
			)
		)
		(property "Description" "SMD Chip Resistor, 27 ohm, ± 1%, 63 mW, 0402 [1005 Metric], Thick Film, General Purpose"
			(at 203.2 107.95 0)
			(effects
				(font
					(size 1.27 1.27)
				)
				(hide yes)
			)
		)
		(property "Manufacturer" "Bourns"
			(at 180.34 87.63 0)
			(effects
				(font
					(size 1.27 1.27)
					(thickness 0.15)
				)
				(justify left bottom)
				(hide yes)
			)
		)
		(property "MPN" "CR0402-FX-27R0GLF"
			(at 182.88 87.63 0)
			(effects
				(font
					(size 1.27 1.27)
					(thickness 0.15)
				)
				(justify left bottom)
				(hide yes)
			)
		)
		(property "Val" "27R"
			(at 200.66 106.68 90)
			(effects
				(font
					(size 1.27 1.27)
					(thickness 0.15)
				)
				(justify right)
			)
		)
		(property "License" "Apache-2.0"
			(at 177.8 87.63 0)
			(effects
				(font
					(size 1.27 1.27)
					(thickness 0.15)
				)
				(justify left bottom)
				(hide yes)
			)
		)
		(property "Author" "Antmicro"
			(at 175.26 87.63 0)
			(effects
				(font
					(size 1.27 1.27)
					(thickness 0.15)
				)
				(justify left bottom)
				(hide yes)
			)
		)
		(property "Tolerance" "1%"
			(at 193.04 87.63 0)
			(effects
				(font
					(size 1.27 1.27)
				)
				(justify left bottom)
				(hide yes)
			)
		)
		(pin "1"
		)
		(pin "2"
		)
		(instances
			(project "jetson-agx-thor-baseboard"
				(path ""
					(reference "R365")
					(unit 1)
				)
			)
		)
	)
	(symbol
		(lib_id "antmicroFixedInductors:L_3u3_15.1A_Coilcraft-XAL7070")
		(at 134.62 101.6 0)
		(unit 1)
		(exclude_from_sim no)
		(in_bom yes)
		(on_board yes)
		(dnp no)
		(fields_autoplaced yes)
		(property "Reference" "L4"
			(at 137.16 96.52 0)
			(effects
				(font
					(size 1.27 1.27)
					(thickness 0.15)
				)
			)
		)
		(property "Value" "L_3u3_15.1A_Coilcraft-XAL7070"
			(at 148.59 104.14 0)
			(effects
				(font
					(size 1.27 1.27)
					(thickness 0.15)
				)
				(justify left bottom)
				(hide yes)
			)
		)
		(property "Footprint" "antmicro-footprints:L_Coilcraft-XAL7070"
			(at 148.59 109.22 0)
			(effects
				(font
					(size 1.27 1.27)
					(thickness 0.15)
				)
				(justify left bottom)
				(hide yes)
			)
		)
		(property "Datasheet" "https://www.coilcraft.com/en-us/products/power/shielded-inductors/molded-inductor/xal/xal7070/xal7070-332/"
			(at 148.59 111.76 0)
			(effects
				(font
					(size 1.27 1.27)
					(thickness 0.15)
				)
				(justify left bottom)
				(hide yes)
			)
		)
		(property "Description" "Power Inductor (SMD), 3.3 µH, 15.1 A, Shielded, 19.4 A, XAL7070"
			(at 148.59 132.08 0)
			(effects
				(font
					(size 1.27 1.27)
				)
				(justify left bottom)
				(hide yes)
			)
		)
		(property "Val" "3u3/15.1A"
			(at 137.16 99.06 0)
			(effects
				(font
					(size 1.27 1.27)
					(thickness 0.15)
				)
			)
		)
		(property "Manufacturer" "Coilcraft"
			(at 148.59 114.3 0)
			(effects
				(font
					(size 1.27 1.27)
					(thickness 0.15)
				)
				(justify left bottom)
				(hide yes)
			)
		)
		(property "MPN" "XAL7070-332MEB"
			(at 148.59 116.84 0)
			(effects
				(font
					(size 1.27 1.27)
					(thickness 0.15)
				)
				(justify left bottom)
				(hide yes)
			)
		)
		(property "ISat" "19.4 A"
			(at 148.59 118.11 0)
			(effects
				(font
					(size 1.27 1.27)
				)
				(justify left)
				(hide yes)
			)
		)
		(property "IMax" "15.1 A"
			(at 148.59 121.92 0)
			(effects
				(font
					(size 1.27 1.27)
					(thickness 0.15)
				)
				(justify left bottom)
				(hide yes)
			)
		)
		(property "Size" "7.7x8"
			(at 148.59 124.46 0)
			(effects
				(font
					(size 1.27 1.27)
					(thickness 0.15)
				)
				(justify left bottom)
				(hide yes)
			)
		)
		(property "Author" "Antmicro"
			(at 148.59 127 0)
			(effects
				(font
					(size 1.27 1.27)
					(thickness 0.15)
				)
				(justify left bottom)
				(hide yes)
			)
		)
		(property "License" "Apache-2.0"
			(at 148.59 129.54 0)
			(effects
				(font
					(size 1.27 1.27)
					(thickness 0.15)
				)
				(justify left bottom)
				(hide yes)
			)
		)
		(pin "2"
		)
		(pin "1"
		)
		(instances
			(project "jetson-agx-thor-baseboard"
				(path ""
					(reference "L4")
					(unit 1)
				)
			)
		)
	)
	(symbol
		(lib_id "antmicropower:PWR_FLAG")
		(at 233.68 212.09 270)
		(unit 1)
		(exclude_from_sim no)
		(in_bom yes)
		(on_board yes)
		(dnp no)
		(property "Reference" "#FLG04"
			(at 235.585 212.09 0)
			(effects
				(font
					(size 1.27 1.27)
				)
				(hide yes)
			)
		)
		(property "Value" "PWR_FLAG"
			(at 241.554 212.09 90)
			(effects
				(font
					(size 1.27 1.27)
				)
			)
		)
		(property "Footprint" ""
			(at 233.68 212.09 0)
			(effects
				(font
					(size 1.27 1.27)
				)
				(hide yes)
			)
		)
		(property "Datasheet" ""
			(at 233.68 212.09 0)
			(effects
				(font
					(size 1.27 1.27)
				)
				(hide yes)
			)
		)
		(property "Description" ""
			(at 233.68 212.09 0)
			(effects
				(font
					(size 1.27 1.27)
				)
				(hide yes)
			)
		)
		(pin "1"
		)
		(instances
			(project "jetson-agx-thor-baseboard"
				(path ""
					(reference "#FLG04")
					(unit 1)
				)
			)
		)
	)
	(symbol
		(lib_id "antmicropower:GND")
		(at 299.72 128.27 0)
		(unit 1)
		(exclude_from_sim no)
		(in_bom yes)
		(on_board yes)
		(dnp no)
		(property "Reference" "#PWR0622"
			(at 308.61 130.81 0)
			(effects
				(font
					(size 1.27 1.27)
					(thickness 0.15)
				)
				(justify left bottom)
				(hide yes)
			)
		)
		(property "Value" "GND"
			(at 299.72 132.08 0)
			(effects
				(font
					(size 1.27 1.27)
					(thickness 0.15)
				)
			)
		)
		(property "Footprint" ""
			(at 308.61 135.89 0)
			(effects
				(font
					(size 1.27 1.27)
					(thickness 0.15)
				)
				(justify left bottom)
				(hide yes)
			)
		)
		(property "Datasheet" ""
			(at 308.61 140.97 0)
			(effects
				(font
					(size 1.27 1.27)
					(thickness 0.15)
				)
				(justify left bottom)
				(hide yes)
			)
		)
		(property "Description" ""
			(at 299.72 128.27 0)
			(effects
				(font
					(size 1.27 1.27)
				)
				(hide yes)
			)
		)
		(property "Author" "Antmicro"
			(at 308.61 135.89 0)
			(effects
				(font
					(size 1.27 1.27)
					(thickness 0.15)
				)
				(justify left bottom)
				(hide yes)
			)
		)
		(property "License" "Apache-2.0"
			(at 308.61 138.43 0)
			(effects
				(font
					(size 1.27 1.27)
					(thickness 0.15)
				)
				(justify left bottom)
				(hide yes)
			)
		)
		(pin "1"
		)
		(instances
			(project "jetson-agx-thor-baseboard"
				(path ""
					(reference "#PWR0622")
					(unit 1)
				)
			)
		)
	)
	(symbol
		(lib_id "antmicroResistors0402:R_10k_0402")
		(at 363.22 52.07 270)
		(mirror x)
		(unit 1)
		(exclude_from_sim no)
		(in_bom yes)
		(on_board yes)
		(dnp no)
		(property "Reference" "R18"
			(at 361.95 48.26 90)
			(effects
				(font
					(size 1.27 1.27)
					(thickness 0.15)
				)
				(justify right)
			)
		)
		(property "Value" "R_10k_0402"
			(at 350.52 31.75 0)
			(effects
				(font
					(size 1.27 1.27)
					(thickness 0.15)
				)
				(justify left bottom)
				(hide yes)
			)
		)
		(property "Footprint" "antmicro-footprints:R_0402_1005Metric"
			(at 347.98 31.75 0)
			(effects
				(font
					(size 1.27 1.27)
					(thickness 0.15)
				)
				(justify left bottom)
				(hide yes)
			)
		)
		(property "Datasheet" "https://www.bourns.com/docs/product-datasheets/cr.pdf"
			(at 345.44 31.75 0)
			(effects
				(font
					(size 1.27 1.27)
					(thickness 0.15)
				)
				(justify left bottom)
				(hide yes)
			)
		)
		(property "Description" "SMD Chip Resistor, 10 kohm, ± 1%, 62.5 mW, 0402 [1005 Metric], Thick Film, General Purpose"
			(at 363.22 52.07 0)
			(effects
				(font
					(size 1.27 1.27)
				)
				(hide yes)
			)
		)
		(property "MPN" "CR0402-FX-1002GLF"
			(at 342.9 31.75 0)
			(effects
				(font
					(size 1.27 1.27)
					(thickness 0.15)
				)
				(justify left bottom)
				(hide yes)
			)
		)
		(property "Manufacturer" "Bourns"
			(at 340.36 31.75 0)
			(effects
				(font
					(size 1.27 1.27)
					(thickness 0.15)
				)
				(justify left bottom)
				(hide yes)
			)
		)
		(property "License" "Apache-2.0"
			(at 337.82 31.75 0)
			(effects
				(font
					(size 1.27 1.27)
					(thickness 0.15)
				)
				(justify left bottom)
				(hide yes)
			)
		)
		(property "Author" "Antmicro"
			(at 335.28 31.75 0)
			(effects
				(font
					(size 1.27 1.27)
					(thickness 0.15)
				)
				(justify left bottom)
				(hide yes)
			)
		)
		(property "Val" "10k"
			(at 361.95 50.8 90)
			(effects
				(font
					(size 1.27 1.27)
					(thickness 0.15)
				)
				(justify right)
			)
		)
		(property "Tolerance" "1%"
			(at 353.06 31.75 0)
			(effects
				(font
					(size 1.27 1.27)
				)
				(justify left bottom)
				(hide yes)
			)
		)
		(pin "2"
		)
		(pin "1"
		)
		(instances
			(project "jetson-agx-thor-baseboard"
				(path ""
					(reference "R18")
					(unit 1)
				)
			)
		)
	)
	(symbol
		(lib_id "antmicropower:GND")
		(at 72.39 279.4 0)
		(unit 1)
		(exclude_from_sim no)
		(in_bom yes)
		(on_board yes)
		(dnp no)
		(property "Reference" "#PWR0111"
			(at 72.39 285.75 0)
			(effects
				(font
					(size 1.27 1.27)
				)
				(justify left bottom)
				(hide yes)
			)
		)
		(property "Value" "GND"
			(at 72.39 283.21 0)
			(effects
				(font
					(size 1.27 1.27)
					(thickness 0.15)
				)
			)
		)
		(property "Footprint" ""
			(at 81.28 287.02 0)
			(effects
				(font
					(size 1.27 1.27)
					(thickness 0.15)
				)
				(justify left bottom)
				(hide yes)
			)
		)
		(property "Datasheet" ""
			(at 81.28 292.1 0)
			(effects
				(font
					(size 1.27 1.27)
					(thickness 0.15)
				)
				(justify left bottom)
				(hide yes)
			)
		)
		(property "Description" ""
			(at 72.39 279.4 0)
			(effects
				(font
					(size 1.27 1.27)
				)
				(hide yes)
			)
		)
		(property "Author" "Antmicro"
			(at 81.28 287.02 0)
			(effects
				(font
					(size 1.27 1.27)
					(thickness 0.15)
				)
				(justify left bottom)
				(hide yes)
			)
		)
		(property "License" "Apache-2.0"
			(at 81.28 289.56 0)
			(effects
				(font
					(size 1.27 1.27)
					(thickness 0.15)
				)
				(justify left bottom)
				(hide yes)
			)
		)
		(pin "1"
		)
		(instances
			(project "jetson-agx-thor-baseboard"
				(path ""
					(reference "#PWR0111")
					(unit 1)
				)
			)
		)
	)
	(symbol
		(lib_id "antmicroResistors0402:R_73k2_0402")
		(at 143.51 173.99 90)
		(unit 1)
		(exclude_from_sim no)
		(in_bom yes)
		(on_board yes)
		(dnp no)
		(property "Reference" "R312"
			(at 144.78 170.18 90)
			(effects
				(font
					(size 1.27 1.27)
					(thickness 0.15)
				)
				(justify right)
			)
		)
		(property "Value" "R_73k2_0402"
			(at 156.21 153.67 0)
			(effects
				(font
					(size 1.27 1.27)
					(thickness 0.15)
				)
				(justify left bottom)
				(hide yes)
			)
		)
		(property "Footprint" "antmicro-footprints:R_0402_1005Metric"
			(at 158.75 153.67 0)
			(effects
				(font
					(size 1.27 1.27)
					(thickness 0.15)
				)
				(justify left bottom)
				(hide yes)
			)
		)
		(property "Datasheet" "https://www.bourns.com/docs/product-datasheets/cr.pdf"
			(at 161.29 153.67 0)
			(effects
				(font
					(size 1.27 1.27)
					(thickness 0.15)
				)
				(justify left bottom)
				(hide yes)
			)
		)
		(property "Description" "SMD Chip Resistor"
			(at 143.51 173.99 0)
			(effects
				(font
					(size 1.27 1.27)
				)
				(hide yes)
			)
		)
		(property "MPN" "CR0402-FX-7322GLF"
			(at 163.83 153.67 0)
			(effects
				(font
					(size 1.27 1.27)
					(thickness 0.15)
				)
				(justify left bottom)
				(hide yes)
			)
		)
		(property "Manufacturer" "Bourns"
			(at 166.37 153.67 0)
			(effects
				(font
					(size 1.27 1.27)
					(thickness 0.15)
				)
				(justify left bottom)
				(hide yes)
			)
		)
		(property "License" "Apache-2.0"
			(at 168.91 153.67 0)
			(effects
				(font
					(size 1.27 1.27)
					(thickness 0.15)
				)
				(justify left bottom)
				(hide yes)
			)
		)
		(property "Author" "Antmicro"
			(at 171.45 153.67 0)
			(effects
				(font
					(size 1.27 1.27)
					(thickness 0.15)
				)
				(justify left bottom)
				(hide yes)
			)
		)
		(property "Val" "73k2"
			(at 144.78 172.72 90)
			(effects
				(font
					(size 1.27 1.27)
					(thickness 0.15)
				)
				(justify right)
			)
		)
		(property "Tolerance" "1%"
			(at 153.67 153.67 0)
			(effects
				(font
					(size 1.27 1.27)
				)
				(justify left bottom)
				(hide yes)
			)
		)
		(pin "2"
		)
		(pin "1"
		)
		(instances
			(project "jetson-agx-thor-baseboard"
				(path ""
					(reference "R312")
					(unit 1)
				)
			)
		)
	)
	(symbol
		(lib_id "antmicropower:VCC")
		(at 21.59 95.25 0)
		(unit 1)
		(exclude_from_sim no)
		(in_bom yes)
		(on_board yes)
		(dnp no)
		(property "Reference" "#PWR0663"
			(at 21.59 99.06 0)
			(effects
				(font
					(size 1.27 1.27)
				)
				(justify left bottom)
				(hide yes)
			)
		)
		(property "Value" "VCC"
			(at 21.59 91.44 0)
			(effects
				(font
					(size 1.27 1.27)
				)
			)
		)
		(property "Footprint" ""
			(at 21.59 95.25 0)
			(effects
				(font
					(size 1.27 1.27)
				)
				(hide yes)
			)
		)
		(property "Datasheet" ""
			(at 21.59 95.25 0)
			(effects
				(font
					(size 1.27 1.27)
				)
				(hide yes)
			)
		)
		(property "Description" ""
			(at 21.59 95.25 0)
			(effects
				(font
					(size 1.27 1.27)
				)
				(hide yes)
			)
		)
		(pin "1"
		)
		(instances
			(project "jetson-agx-thor-baseboard"
				(path ""
					(reference "#PWR0663")
					(unit 1)
				)
			)
		)
	)
	(symbol
		(lib_id "antmicropower:GND")
		(at 143.51 185.42 0)
		(unit 1)
		(exclude_from_sim no)
		(in_bom yes)
		(on_board yes)
		(dnp no)
		(property "Reference" "#PWR0756"
			(at 143.51 191.77 0)
			(effects
				(font
					(size 1.27 1.27)
				)
				(justify left bottom)
				(hide yes)
			)
		)
		(property "Value" "GND"
			(at 143.51 189.23 0)
			(effects
				(font
					(size 1.27 1.27)
					(thickness 0.15)
				)
			)
		)
		(property "Footprint" ""
			(at 152.4 193.04 0)
			(effects
				(font
					(size 1.27 1.27)
					(thickness 0.15)
				)
				(justify left bottom)
				(hide yes)
			)
		)
		(property "Datasheet" ""
			(at 152.4 198.12 0)
			(effects
				(font
					(size 1.27 1.27)
					(thickness 0.15)
				)
				(justify left bottom)
				(hide yes)
			)
		)
		(property "Description" ""
			(at 143.51 185.42 0)
			(effects
				(font
					(size 1.27 1.27)
				)
				(hide yes)
			)
		)
		(property "Author" "Antmicro"
			(at 152.4 193.04 0)
			(effects
				(font
					(size 1.27 1.27)
					(thickness 0.15)
				)
				(justify left bottom)
				(hide yes)
			)
		)
		(property "License" "Apache-2.0"
			(at 152.4 195.58 0)
			(effects
				(font
					(size 1.27 1.27)
					(thickness 0.15)
				)
				(justify left bottom)
				(hide yes)
			)
		)
		(pin "1"
		)
		(instances
			(project "jetson-agx-thor-baseboard"
				(path ""
					(reference "#PWR0756")
					(unit 1)
				)
			)
		)
	)
	(symbol
		(lib_id "antmicroResistors0402:R_49k9_0402")
		(at 48.26 134.62 270)
		(mirror x)
		(unit 1)
		(exclude_from_sim no)
		(in_bom no)
		(on_board yes)
		(dnp yes)
		(property "Reference" "R34"
			(at 46.99 130.81 90)
			(effects
				(font
					(size 1.27 1.27)
					(thickness 0.15)
				)
				(justify right)
			)
		)
		(property "Value" "R_49k9_0402"
			(at 35.56 114.3 0)
			(effects
				(font
					(size 1.27 1.27)
					(thickness 0.15)
				)
				(justify left bottom)
				(hide yes)
			)
		)
		(property "Footprint" "antmicro-footprints:R_0402_1005Metric"
			(at 33.02 114.3 0)
			(effects
				(font
					(size 1.27 1.27)
					(thickness 0.15)
				)
				(justify left bottom)
				(hide yes)
			)
		)
		(property "Datasheet" "https://www.bourns.com/docs/product-datasheets/cr.pdf"
			(at 30.48 114.3 0)
			(effects
				(font
					(size 1.27 1.27)
					(thickness 0.15)
				)
				(justify left bottom)
				(hide yes)
			)
		)
		(property "Description" "SMD Chip Resistor, 49.9 kohm, ± 1%, 63 mW, 0402 [1005 Metric], Thick Film, General Purpose"
			(at 48.26 134.62 0)
			(effects
				(font
					(size 1.27 1.27)
				)
				(hide yes)
			)
		)
		(property "MPN" "CR0402-FX-4992GLF"
			(at 27.94 114.3 0)
			(effects
				(font
					(size 1.27 1.27)
					(thickness 0.15)
				)
				(justify left bottom)
				(hide yes)
			)
		)
		(property "Manufacturer" "Bourns"
			(at 25.4 114.3 0)
			(effects
				(font
					(size 1.27 1.27)
					(thickness 0.15)
				)
				(justify left bottom)
				(hide yes)
			)
		)
		(property "License" "Apache-2.0"
			(at 22.86 114.3 0)
			(effects
				(font
					(size 1.27 1.27)
					(thickness 0.15)
				)
				(justify left bottom)
				(hide yes)
			)
		)
		(property "Author" "Antmicro"
			(at 20.32 114.3 0)
			(effects
				(font
					(size 1.27 1.27)
					(thickness 0.15)
				)
				(justify left bottom)
				(hide yes)
			)
		)
		(property "Val" "49k9"
			(at 46.99 133.35 90)
			(effects
				(font
					(size 1.27 1.27)
					(thickness 0.15)
				)
				(justify right)
			)
		)
		(property "Tolerance" "1%"
			(at 38.1 114.3 0)
			(effects
				(font
					(size 1.27 1.27)
				)
				(justify left bottom)
				(hide yes)
			)
		)
		(pin "2"
		)
		(pin "1"
		)
		(instances
			(project "jetson-agx-thor-baseboard"
				(path ""
					(reference "R34")
					(unit 1)
				)
			)
		)
	)
	(symbol
		(lib_id "antmicroPowerMeasurement:INA219AIDCNR")
		(at 204.47 115.57 0)
		(unit 1)
		(exclude_from_sim no)
		(in_bom yes)
		(on_board yes)
		(dnp no)
		(property "Reference" "U66"
			(at 211.836 130.81 0)
			(effects
				(font
					(size 1.27 1.27)
				)
			)
		)
		(property "Value" "INA219AIDCNR"
			(at 204.47 115.57 0)
			(effects
				(font
					(size 1.27 1.27)
				)
				(hide yes)
			)
		)
		(property "Footprint" "antmicro-footprints:SOT-23-8"
			(at 204.47 115.57 0)
			(effects
				(font
					(size 1.27 1.27)
				)
				(hide yes)
			)
		)
		(property "Datasheet" "https://www.ti.com/lit/ds/symlink/ina219.pdf?ts=1713856455637&ref_url=https%253A%252F%252Fwww.mouser.es%252F"
			(at 204.47 115.57 0)
			(effects
				(font
					(size 1.27 1.27)
				)
				(hide yes)
			)
		)
		(property "Description" "Zerø-Drift, Bidirectional Current/Power Monitor With I2C Interface"
			(at 204.47 115.57 0)
			(effects
				(font
					(size 1.27 1.27)
				)
				(hide yes)
			)
		)
		(property "Manufacturer" "Texas Instruments"
			(at 204.47 115.57 0)
			(effects
				(font
					(size 1.27 1.27)
				)
				(hide yes)
			)
		)
		(property "MPN" "INA219AIDCNR"
			(at 211.836 133.35 0)
			(effects
				(font
					(size 1.27 1.27)
				)
			)
		)
		(property "Author" "Antmicro"
			(at 229.87 135.89 0)
			(effects
				(font
					(size 1.27 1.27)
					(thickness 0.15)
				)
				(justify left bottom)
				(hide yes)
			)
		)
		(property "License" "Apache-2.0"
			(at 229.87 138.43 0)
			(effects
				(font
					(size 1.27 1.27)
					(thickness 0.15)
				)
				(justify left bottom)
				(hide yes)
			)
		)
		(pin "1"
		)
		(pin "2"
		)
		(pin "5"
		)
		(pin "6"
		)
		(pin "8"
		)
		(pin "3"
		)
		(pin "7"
		)
		(pin "4"
		)
		(instances
			(project "jetson-agx-thor-baseboard"
				(path ""
					(reference "U66")
					(unit 1)
				)
			)
		)
	)
	(symbol
		(lib_id "antmicroResistors0402:R_100k_0402")
		(at 55.88 120.65 90)
		(unit 1)
		(exclude_from_sim no)
		(in_bom yes)
		(on_board yes)
		(dnp no)
		(fields_autoplaced yes)
		(property "Reference" "R29"
			(at 58.42 116.84 90)
			(effects
				(font
					(size 1.27 1.27)
					(thickness 0.15)
				)
				(justify right)
			)
		)
		(property "Value" "R_100k_0402"
			(at 68.58 100.33 0)
			(effects
				(font
					(size 1.27 1.27)
					(thickness 0.15)
				)
				(justify left bottom)
				(hide yes)
			)
		)
		(property "Footprint" "antmicro-footprints:R_0402_1005Metric"
			(at 71.12 100.33 0)
			(effects
				(font
					(size 1.27 1.27)
					(thickness 0.15)
				)
				(justify left bottom)
				(hide yes)
			)
		)
		(property "Datasheet" "https://www.bourns.com/docs/product-datasheets/cr.pdf"
			(at 73.66 100.33 0)
			(effects
				(font
					(size 1.27 1.27)
					(thickness 0.15)
				)
				(justify left bottom)
				(hide yes)
			)
		)
		(property "Description" "SMD Chip Resistor, 100 kohm, ± 1%, 62.5 mW, 0402 [1005 Metric], Thick Film, General Purpose"
			(at 86.36 100.33 0)
			(effects
				(font
					(size 1.27 1.27)
				)
				(justify left bottom)
				(hide yes)
			)
		)
		(property "MPN" "CR0402-FX-1003GLF"
			(at 76.2 100.33 0)
			(effects
				(font
					(size 1.27 1.27)
					(thickness 0.15)
				)
				(justify left bottom)
				(hide yes)
			)
		)
		(property "Manufacturer" "Bourns"
			(at 78.74 100.33 0)
			(effects
				(font
					(size 1.27 1.27)
					(thickness 0.15)
				)
				(justify left bottom)
				(hide yes)
			)
		)
		(property "License" "Apache-2.0"
			(at 81.28 100.33 0)
			(effects
				(font
					(size 1.27 1.27)
					(thickness 0.15)
				)
				(justify left bottom)
				(hide yes)
			)
		)
		(property "Author" "Antmicro"
			(at 83.82 100.33 0)
			(effects
				(font
					(size 1.27 1.27)
					(thickness 0.15)
				)
				(justify left bottom)
				(hide yes)
			)
		)
		(property "Val" "100k"
			(at 58.42 119.38 90)
			(effects
				(font
					(size 1.27 1.27)
					(thickness 0.15)
				)
				(justify right)
			)
		)
		(property "Tolerance" "1%"
			(at 66.04 100.33 0)
			(effects
				(font
					(size 1.27 1.27)
				)
				(justify left bottom)
				(hide yes)
			)
		)
		(pin "2"
		)
		(pin "1"
		)
		(instances
			(project "jetson-agx-thor-baseboard"
				(path ""
					(reference "R29")
					(unit 1)
				)
			)
		)
	)
	(symbol
		(lib_id "antmicroResistors0402:R_27R_0402")
		(at 215.9 256.54 90)
		(unit 1)
		(exclude_from_sim no)
		(in_bom yes)
		(on_board yes)
		(dnp no)
		(property "Reference" "R369"
			(at 216.916 252.7299 90)
			(effects
				(font
					(size 1.27 1.27)
				)
				(justify right)
			)
		)
		(property "Value" "R_27R_0402"
			(at 228.6 236.22 0)
			(effects
				(font
					(size 1.27 1.27)
					(thickness 0.15)
				)
				(justify left bottom)
				(hide yes)
			)
		)
		(property "Footprint" "antmicro-footprints:R_0402_1005Metric"
			(at 231.14 236.22 0)
			(effects
				(font
					(size 1.27 1.27)
					(thickness 0.15)
				)
				(justify left bottom)
				(hide yes)
			)
		)
		(property "Datasheet" "https://www.bourns.com/docs/product-datasheets/cr.pdf"
			(at 233.68 236.22 0)
			(effects
				(font
					(size 1.27 1.27)
					(thickness 0.15)
				)
				(justify left bottom)
				(hide yes)
			)
		)
		(property "Description" "SMD Chip Resistor, 27 ohm, ± 1%, 63 mW, 0402 [1005 Metric], Thick Film, General Purpose"
			(at 215.9 256.54 0)
			(effects
				(font
					(size 1.27 1.27)
				)
				(hide yes)
			)
		)
		(property "Manufacturer" "Bourns"
			(at 238.76 236.22 0)
			(effects
				(font
					(size 1.27 1.27)
					(thickness 0.15)
				)
				(justify left bottom)
				(hide yes)
			)
		)
		(property "MPN" "CR0402-FX-27R0GLF"
			(at 236.22 236.22 0)
			(effects
				(font
					(size 1.27 1.27)
					(thickness 0.15)
				)
				(justify left bottom)
				(hide yes)
			)
		)
		(property "Val" "27R"
			(at 216.916 255.27 90)
			(effects
				(font
					(size 1.27 1.27)
					(thickness 0.15)
				)
				(justify right)
			)
		)
		(property "License" "Apache-2.0"
			(at 241.3 236.22 0)
			(effects
				(font
					(size 1.27 1.27)
					(thickness 0.15)
				)
				(justify left bottom)
				(hide yes)
			)
		)
		(property "Author" "Antmicro"
			(at 243.84 236.22 0)
			(effects
				(font
					(size 1.27 1.27)
					(thickness 0.15)
				)
				(justify left bottom)
				(hide yes)
			)
		)
		(property "Tolerance" "1%"
			(at 226.06 236.22 0)
			(effects
				(font
					(size 1.27 1.27)
				)
				(justify left bottom)
				(hide yes)
			)
		)
		(pin "1"
		)
		(pin "2"
		)
		(instances
			(project "jetson-agx-thor-baseboard"
				(path ""
					(reference "R369")
					(unit 1)
				)
			)
		)
	)
	(symbol
		(lib_id "antmicropower:GND")
		(at 64.77 55.88 0)
		(unit 1)
		(exclude_from_sim no)
		(in_bom yes)
		(on_board yes)
		(dnp no)
		(property "Reference" "#PWR0494"
			(at 64.77 62.23 0)
			(effects
				(font
					(size 1.27 1.27)
				)
				(justify left bottom)
				(hide yes)
			)
		)
		(property "Value" "GND"
			(at 64.77 59.69 0)
			(effects
				(font
					(size 1.27 1.27)
					(thickness 0.15)
				)
			)
		)
		(property "Footprint" ""
			(at 73.66 63.5 0)
			(effects
				(font
					(size 1.27 1.27)
					(thickness 0.15)
				)
				(justify left bottom)
				(hide yes)
			)
		)
		(property "Datasheet" ""
			(at 73.66 68.58 0)
			(effects
				(font
					(size 1.27 1.27)
					(thickness 0.15)
				)
				(justify left bottom)
				(hide yes)
			)
		)
		(property "Description" ""
			(at 64.77 55.88 0)
			(effects
				(font
					(size 1.27 1.27)
				)
				(hide yes)
			)
		)
		(property "Author" "Antmicro"
			(at 73.66 63.5 0)
			(effects
				(font
					(size 1.27 1.27)
					(thickness 0.15)
				)
				(justify left bottom)
				(hide yes)
			)
		)
		(property "License" "Apache-2.0"
			(at 73.66 66.04 0)
			(effects
				(font
					(size 1.27 1.27)
					(thickness 0.15)
				)
				(justify left bottom)
				(hide yes)
			)
		)
		(pin "1"
		)
		(instances
			(project "jetson-agx-thor-baseboard"
				(path ""
					(reference "#PWR0494")
					(unit 1)
				)
			)
		)
	)
	(symbol
		(lib_id "antmicroCapacitorsmisc:C_22u_25V_0805")
		(at 154.94 124.46 90)
		(unit 1)
		(exclude_from_sim no)
		(in_bom yes)
		(on_board yes)
		(dnp no)
		(property "Reference" "C284"
			(at 156.718 119.3801 90)
			(effects
				(font
					(size 1.27 1.27)
					(thickness 0.15)
				)
				(justify right)
			)
		)
		(property "Value" "C_22u_25V_0805"
			(at 165.1 104.14 0)
			(effects
				(font
					(size 1.27 1.27)
					(thickness 0.15)
				)
				(justify left bottom)
				(hide yes)
			)
		)
		(property "Footprint" "antmicro-footprints:C_0805_2012Metric"
			(at 167.64 104.14 0)
			(effects
				(font
					(size 1.27 1.27)
					(thickness 0.15)
				)
				(justify left bottom)
				(hide yes)
			)
		)
		(property "Datasheet" "https://product.samsungsem.com/mlcc/CL21A226MAYNNN.do"
			(at 170.18 104.14 0)
			(effects
				(font
					(size 1.27 1.27)
					(thickness 0.15)
				)
				(justify left bottom)
				(hide yes)
			)
		)
		(property "Description" "SMT Multilayer Ceramic Capacitor, 22uF, +/-20%, 25V, X5R, 0805 [2012 Metric]"
			(at 187.96 104.14 0)
			(effects
				(font
					(size 1.27 1.27)
				)
				(justify left bottom)
				(hide yes)
			)
		)
		(property "MPN" "CL21A226MAYNNNE"
			(at 172.72 104.14 0)
			(effects
				(font
					(size 1.27 1.27)
					(thickness 0.15)
				)
				(justify left bottom)
				(hide yes)
			)
		)
		(property "Manufacturer" "Samsung Electro-Mechanics"
			(at 175.26 104.14 0)
			(effects
				(font
					(size 1.27 1.27)
					(thickness 0.15)
				)
				(justify left bottom)
				(hide yes)
			)
		)
		(property "License" "Apache-2.0"
			(at 177.8 104.14 0)
			(effects
				(font
					(size 1.27 1.27)
					(thickness 0.15)
				)
				(justify left bottom)
				(hide yes)
			)
		)
		(property "Author" "Antmicro"
			(at 180.34 104.14 0)
			(effects
				(font
					(size 1.27 1.27)
					(thickness 0.15)
				)
				(justify left bottom)
				(hide yes)
			)
		)
		(property "Val" "22u"
			(at 156.718 121.9201 90)
			(effects
				(font
					(size 1.27 1.27)
					(thickness 0.15)
				)
				(justify right)
			)
		)
		(property "Voltage" "25V"
			(at 156.718 124.46 90)
			(effects
				(font
					(size 1.27 1.27)
				)
				(justify right)
			)
		)
		(property "Dielectric" "X5R"
			(at 185.42 104.14 0)
			(effects
				(font
					(size 1.27 1.27)
				)
				(justify left bottom)
				(hide yes)
			)
		)
		(property "Public" "False"
			(at 187.96 104.14 0)
			(effects
				(font
					(size 1.27 1.27)
				)
				(justify left bottom)
				(hide yes)
			)
		)
		(pin "2"
		)
		(pin "1"
		)
		(instances
			(project "jetson-agx-thor-baseboard"
				(path ""
					(reference "C284")
					(unit 1)
				)
			)
		)
	)
	(symbol
		(lib_id "antmicropower:GND")
		(at 177.8 140.97 0)
		(unit 1)
		(exclude_from_sim no)
		(in_bom yes)
		(on_board yes)
		(dnp no)
		(property "Reference" "#PWR0591"
			(at 177.8 147.32 0)
			(effects
				(font
					(size 1.27 1.27)
				)
				(justify left bottom)
				(hide yes)
			)
		)
		(property "Value" "GND"
			(at 177.8 144.78 0)
			(effects
				(font
					(size 1.27 1.27)
					(thickness 0.15)
				)
			)
		)
		(property "Footprint" ""
			(at 186.69 148.59 0)
			(effects
				(font
					(size 1.27 1.27)
					(thickness 0.15)
				)
				(justify left bottom)
				(hide yes)
			)
		)
		(property "Datasheet" ""
			(at 186.69 153.67 0)
			(effects
				(font
					(size 1.27 1.27)
					(thickness 0.15)
				)
				(justify left bottom)
				(hide yes)
			)
		)
		(property "Description" ""
			(at 177.8 140.97 0)
			(effects
				(font
					(size 1.27 1.27)
				)
				(hide yes)
			)
		)
		(property "Author" "Antmicro"
			(at 186.69 148.59 0)
			(effects
				(font
					(size 1.27 1.27)
					(thickness 0.15)
				)
				(justify left bottom)
				(hide yes)
			)
		)
		(property "License" "Apache-2.0"
			(at 186.69 151.13 0)
			(effects
				(font
					(size 1.27 1.27)
					(thickness 0.15)
				)
				(justify left bottom)
				(hide yes)
			)
		)
		(pin "1"
		)
		(instances
			(project "jetson-agx-thor-baseboard"
				(path ""
					(reference "#PWR0591")
					(unit 1)
				)
			)
		)
	)
	(symbol
		(lib_id "antmicropower:GND")
		(at 255.27 58.42 0)
		(unit 1)
		(exclude_from_sim no)
		(in_bom yes)
		(on_board yes)
		(dnp no)
		(property "Reference" "#PWR0618"
			(at 255.27 64.77 0)
			(effects
				(font
					(size 1.27 1.27)
				)
				(justify left bottom)
				(hide yes)
			)
		)
		(property "Value" "GND"
			(at 255.27 62.23 0)
			(effects
				(font
					(size 1.27 1.27)
					(thickness 0.15)
				)
			)
		)
		(property "Footprint" ""
			(at 264.16 66.04 0)
			(effects
				(font
					(size 1.27 1.27)
					(thickness 0.15)
				)
				(justify left bottom)
				(hide yes)
			)
		)
		(property "Datasheet" ""
			(at 264.16 71.12 0)
			(effects
				(font
					(size 1.27 1.27)
					(thickness 0.15)
				)
				(justify left bottom)
				(hide yes)
			)
		)
		(property "Description" ""
			(at 255.27 58.42 0)
			(effects
				(font
					(size 1.27 1.27)
				)
				(hide yes)
			)
		)
		(property "Author" "Antmicro"
			(at 264.16 66.04 0)
			(effects
				(font
					(size 1.27 1.27)
					(thickness 0.15)
				)
				(justify left bottom)
				(hide yes)
			)
		)
		(property "License" "Apache-2.0"
			(at 264.16 68.58 0)
			(effects
				(font
					(size 1.27 1.27)
					(thickness 0.15)
				)
				(justify left bottom)
				(hide yes)
			)
		)
		(pin "1"
		)
		(instances
			(project "jetson-agx-thor-baseboard"
				(path ""
					(reference "#PWR0618")
					(unit 1)
				)
			)
		)
	)
	(symbol
		(lib_id "antmicroCapacitorsmisc:C_22u_25V_0805")
		(at 21.59 105.41 90)
		(unit 1)
		(exclude_from_sim no)
		(in_bom yes)
		(on_board yes)
		(dnp no)
		(property "Reference" "C269"
			(at 22.225 100.965 90)
			(effects
				(font
					(size 1.27 1.27)
					(thickness 0.15)
				)
				(justify right)
			)
		)
		(property "Value" "C_22u_25V_0805"
			(at 31.75 85.09 0)
			(effects
				(font
					(size 1.27 1.27)
					(thickness 0.15)
				)
				(justify left bottom)
				(hide yes)
			)
		)
		(property "Footprint" "antmicro-footprints:C_0805_2012Metric"
			(at 34.29 85.09 0)
			(effects
				(font
					(size 1.27 1.27)
					(thickness 0.15)
				)
				(justify left bottom)
				(hide yes)
			)
		)
		(property "Datasheet" "https://product.samsungsem.com/mlcc/CL21A226MAYNNN.do"
			(at 36.83 85.09 0)
			(effects
				(font
					(size 1.27 1.27)
					(thickness 0.15)
				)
				(justify left bottom)
				(hide yes)
			)
		)
		(property "Description" "SMT Multilayer Ceramic Capacitor, 22uF, +/-20%, 25V, X5R, 0805 [2012 Metric]"
			(at 21.59 105.41 0)
			(effects
				(font
					(size 1.27 1.27)
				)
				(hide yes)
			)
		)
		(property "MPN" "CL21A226MAYNNNE"
			(at 39.37 85.09 0)
			(effects
				(font
					(size 1.27 1.27)
					(thickness 0.15)
				)
				(justify left bottom)
				(hide yes)
			)
		)
		(property "Manufacturer" "Samsung Electro-Mechanics"
			(at 41.91 85.09 0)
			(effects
				(font
					(size 1.27 1.27)
					(thickness 0.15)
				)
				(justify left bottom)
				(hide yes)
			)
		)
		(property "License" "Apache-2.0"
			(at 44.45 85.09 0)
			(effects
				(font
					(size 1.27 1.27)
					(thickness 0.15)
				)
				(justify left bottom)
				(hide yes)
			)
		)
		(property "Author" "Antmicro"
			(at 46.99 85.09 0)
			(effects
				(font
					(size 1.27 1.27)
					(thickness 0.15)
				)
				(justify left bottom)
				(hide yes)
			)
		)
		(property "Val" "22u"
			(at 22.225 104.775 90)
			(effects
				(font
					(size 1.27 1.27)
					(thickness 0.15)
				)
				(justify right)
			)
		)
		(property "Voltage" "25V"
			(at 22.225 107.315 90)
			(effects
				(font
					(size 1.27 1.27)
				)
				(justify right)
			)
		)
		(property "Dielectric" "X5R"
			(at 52.07 85.09 0)
			(effects
				(font
					(size 1.27 1.27)
				)
				(justify left bottom)
				(hide yes)
			)
		)
		(property "Public" "False"
			(at 54.61 85.09 0)
			(effects
				(font
					(size 1.27 1.27)
				)
				(justify left bottom)
				(hide yes)
			)
		)
		(pin "2"
		)
		(pin "1"
		)
		(instances
			(project "jetson-agx-thor-baseboard"
				(path ""
					(reference "C269")
					(unit 1)
				)
			)
		)
	)
	(symbol
		(lib_id "antmicroResistors0402:R_499k_0402")
		(at 278.13 41.91 90)
		(unit 1)
		(exclude_from_sim no)
		(in_bom no)
		(on_board yes)
		(dnp yes)
		(property "Reference" "R12"
			(at 279.4 38.1 90)
			(effects
				(font
					(size 1.27 1.27)
					(thickness 0.15)
				)
				(justify right)
			)
		)
		(property "Value" "R_499k_0402"
			(at 290.83 21.59 0)
			(effects
				(font
					(size 1.27 1.27)
					(thickness 0.15)
				)
				(justify left bottom)
				(hide yes)
			)
		)
		(property "Footprint" "antmicro-footprints:R_0402_1005Metric"
			(at 293.37 21.59 0)
			(effects
				(font
					(size 1.27 1.27)
					(thickness 0.15)
				)
				(justify left bottom)
				(hide yes)
			)
		)
		(property "Datasheet" "https://www.mouser.com/datasheet/2/54/cr-1858361.pdf"
			(at 295.91 21.59 0)
			(effects
				(font
					(size 1.27 1.27)
					(thickness 0.15)
				)
				(justify left bottom)
				(hide yes)
			)
		)
		(property "Description" "SMD Chip Resistor, 499 kohm, ± 1%, 63 mW, 0402 [1005 Metric], Thick Film, General Purpose"
			(at 278.13 41.91 0)
			(effects
				(font
					(size 1.27 1.27)
				)
				(hide yes)
			)
		)
		(property "MPN" "CR0402-FX-4993GLF"
			(at 298.45 21.59 0)
			(effects
				(font
					(size 1.27 1.27)
					(thickness 0.15)
				)
				(justify left bottom)
				(hide yes)
			)
		)
		(property "Manufacturer" "Bourns"
			(at 300.99 21.59 0)
			(effects
				(font
					(size 1.27 1.27)
					(thickness 0.15)
				)
				(justify left bottom)
				(hide yes)
			)
		)
		(property "License" "Apache-2.0"
			(at 303.53 21.59 0)
			(effects
				(font
					(size 1.27 1.27)
					(thickness 0.15)
				)
				(justify left bottom)
				(hide yes)
			)
		)
		(property "Author" "Antmicro"
			(at 306.07 21.59 0)
			(effects
				(font
					(size 1.27 1.27)
					(thickness 0.15)
				)
				(justify left bottom)
				(hide yes)
			)
		)
		(property "Val" "499k"
			(at 279.4 40.64 90)
			(effects
				(font
					(size 1.27 1.27)
					(thickness 0.15)
				)
				(justify right)
			)
		)
		(property "Tolerance" "1%"
			(at 288.29 21.59 0)
			(effects
				(font
					(size 1.27 1.27)
				)
				(justify left bottom)
				(hide yes)
			)
		)
		(pin "2"
		)
		(pin "1"
		)
		(instances
			(project "jetson-agx-thor-baseboard"
				(path ""
					(reference "R12")
					(unit 1)
				)
			)
		)
	)
	(symbol
		(lib_id "antmicroCapacitorsmisc:C_22u_25V_0805")
		(at 168.91 175.26 90)
		(unit 1)
		(exclude_from_sim no)
		(in_bom yes)
		(on_board yes)
		(dnp no)
		(property "Reference" "C380"
			(at 170.688 170.1801 90)
			(effects
				(font
					(size 1.27 1.27)
					(thickness 0.15)
				)
				(justify right)
			)
		)
		(property "Value" "C_22u_25V_0805"
			(at 179.07 154.94 0)
			(effects
				(font
					(size 1.27 1.27)
					(thickness 0.15)
				)
				(justify left bottom)
				(hide yes)
			)
		)
		(property "Footprint" "antmicro-footprints:C_0805_2012Metric"
			(at 181.61 154.94 0)
			(effects
				(font
					(size 1.27 1.27)
					(thickness 0.15)
				)
				(justify left bottom)
				(hide yes)
			)
		)
		(property "Datasheet" "https://product.samsungsem.com/mlcc/CL21A226MAYNNN.do"
			(at 184.15 154.94 0)
			(effects
				(font
					(size 1.27 1.27)
					(thickness 0.15)
				)
				(justify left bottom)
				(hide yes)
			)
		)
		(property "Description" "SMT Multilayer Ceramic Capacitor, 22uF, +/-20%, 25V, X5R, 0805 [2012 Metric]"
			(at 201.93 154.94 0)
			(effects
				(font
					(size 1.27 1.27)
				)
				(justify left bottom)
				(hide yes)
			)
		)
		(property "MPN" "CL21A226MAYNNNE"
			(at 186.69 154.94 0)
			(effects
				(font
					(size 1.27 1.27)
					(thickness 0.15)
				)
				(justify left bottom)
				(hide yes)
			)
		)
		(property "Manufacturer" "Samsung Electro-Mechanics"
			(at 189.23 154.94 0)
			(effects
				(font
					(size 1.27 1.27)
					(thickness 0.15)
				)
				(justify left bottom)
				(hide yes)
			)
		)
		(property "License" "Apache-2.0"
			(at 191.77 154.94 0)
			(effects
				(font
					(size 1.27 1.27)
					(thickness 0.15)
				)
				(justify left bottom)
				(hide yes)
			)
		)
		(property "Author" "Antmicro"
			(at 194.31 154.94 0)
			(effects
				(font
					(size 1.27 1.27)
					(thickness 0.15)
				)
				(justify left bottom)
				(hide yes)
			)
		)
		(property "Val" "22u"
			(at 170.688 172.7201 90)
			(effects
				(font
					(size 1.27 1.27)
					(thickness 0.15)
				)
				(justify right)
			)
		)
		(property "Voltage" "25V"
			(at 170.688 175.26 90)
			(effects
				(font
					(size 1.27 1.27)
				)
				(justify right)
			)
		)
		(property "Dielectric" "X5R"
			(at 199.39 154.94 0)
			(effects
				(font
					(size 1.27 1.27)
				)
				(justify left bottom)
				(hide yes)
			)
		)
		(property "Public" "False"
			(at 201.93 154.94 0)
			(effects
				(font
					(size 1.27 1.27)
				)
				(justify left bottom)
				(hide yes)
			)
		)
		(pin "2"
		)
		(pin "1"
		)
		(instances
			(project "jetson-agx-thor-baseboard"
				(path ""
					(reference "C380")
					(unit 1)
				)
			)
		)
	)
	(symbol
		(lib_id "antmicroCapacitorsmisc:C_22u_25V_0805")
		(at 162.56 124.46 90)
		(unit 1)
		(exclude_from_sim no)
		(in_bom yes)
		(on_board yes)
		(dnp no)
		(property "Reference" "C288"
			(at 164.338 119.3801 90)
			(effects
				(font
					(size 1.27 1.27)
					(thickness 0.15)
				)
				(justify right)
			)
		)
		(property "Value" "C_22u_25V_0805"
			(at 172.72 104.14 0)
			(effects
				(font
					(size 1.27 1.27)
					(thickness 0.15)
				)
				(justify left bottom)
				(hide yes)
			)
		)
		(property "Footprint" "antmicro-footprints:C_0805_2012Metric"
			(at 175.26 104.14 0)
			(effects
				(font
					(size 1.27 1.27)
					(thickness 0.15)
				)
				(justify left bottom)
				(hide yes)
			)
		)
		(property "Datasheet" "https://product.samsungsem.com/mlcc/CL21A226MAYNNN.do"
			(at 177.8 104.14 0)
			(effects
				(font
					(size 1.27 1.27)
					(thickness 0.15)
				)
				(justify left bottom)
				(hide yes)
			)
		)
		(property "Description" "SMT Multilayer Ceramic Capacitor, 22uF, +/-20%, 25V, X5R, 0805 [2012 Metric]"
			(at 195.58 104.14 0)
			(effects
				(font
					(size 1.27 1.27)
				)
				(justify left bottom)
				(hide yes)
			)
		)
		(property "MPN" "CL21A226MAYNNNE"
			(at 180.34 104.14 0)
			(effects
				(font
					(size 1.27 1.27)
					(thickness 0.15)
				)
				(justify left bottom)
				(hide yes)
			)
		)
		(property "Manufacturer" "Samsung Electro-Mechanics"
			(at 182.88 104.14 0)
			(effects
				(font
					(size 1.27 1.27)
					(thickness 0.15)
				)
				(justify left bottom)
				(hide yes)
			)
		)
		(property "License" "Apache-2.0"
			(at 185.42 104.14 0)
			(effects
				(font
					(size 1.27 1.27)
					(thickness 0.15)
				)
				(justify left bottom)
				(hide yes)
			)
		)
		(property "Author" "Antmicro"
			(at 187.96 104.14 0)
			(effects
				(font
					(size 1.27 1.27)
					(thickness 0.15)
				)
				(justify left bottom)
				(hide yes)
			)
		)
		(property "Val" "22u"
			(at 164.338 121.9201 90)
			(effects
				(font
					(size 1.27 1.27)
					(thickness 0.15)
				)
				(justify right)
			)
		)
		(property "Voltage" "25V"
			(at 164.338 124.46 90)
			(effects
				(font
					(size 1.27 1.27)
				)
				(justify right)
			)
		)
		(property "Dielectric" "X5R"
			(at 193.04 104.14 0)
			(effects
				(font
					(size 1.27 1.27)
				)
				(justify left bottom)
				(hide yes)
			)
		)
		(property "Public" "False"
			(at 195.58 104.14 0)
			(effects
				(font
					(size 1.27 1.27)
				)
				(justify left bottom)
				(hide yes)
			)
		)
		(pin "2"
		)
		(pin "1"
		)
		(instances
			(project "jetson-agx-thor-baseboard"
				(path ""
					(reference "C288")
					(unit 1)
				)
			)
		)
	)
	(symbol
		(lib_id "antmicroResistors0402:R_73k2_0402")
		(at 143.51 218.44 90)
		(unit 1)
		(exclude_from_sim no)
		(in_bom yes)
		(on_board yes)
		(dnp no)
		(property "Reference" "R52"
			(at 144.78 214.63 90)
			(effects
				(font
					(size 1.27 1.27)
					(thickness 0.15)
				)
				(justify right)
			)
		)
		(property "Value" "R_73k2_0402"
			(at 156.21 198.12 0)
			(effects
				(font
					(size 1.27 1.27)
					(thickness 0.15)
				)
				(justify left bottom)
				(hide yes)
			)
		)
		(property "Footprint" "antmicro-footprints:R_0402_1005Metric"
			(at 158.75 198.12 0)
			(effects
				(font
					(size 1.27 1.27)
					(thickness 0.15)
				)
				(justify left bottom)
				(hide yes)
			)
		)
		(property "Datasheet" "https://www.bourns.com/docs/product-datasheets/cr.pdf"
			(at 161.29 198.12 0)
			(effects
				(font
					(size 1.27 1.27)
					(thickness 0.15)
				)
				(justify left bottom)
				(hide yes)
			)
		)
		(property "Description" "SMD Chip Resistor"
			(at 143.51 218.44 0)
			(effects
				(font
					(size 1.27 1.27)
				)
				(hide yes)
			)
		)
		(property "MPN" "CR0402-FX-7322GLF"
			(at 163.83 198.12 0)
			(effects
				(font
					(size 1.27 1.27)
					(thickness 0.15)
				)
				(justify left bottom)
				(hide yes)
			)
		)
		(property "Manufacturer" "Bourns"
			(at 166.37 198.12 0)
			(effects
				(font
					(size 1.27 1.27)
					(thickness 0.15)
				)
				(justify left bottom)
				(hide yes)
			)
		)
		(property "License" "Apache-2.0"
			(at 168.91 198.12 0)
			(effects
				(font
					(size 1.27 1.27)
					(thickness 0.15)
				)
				(justify left bottom)
				(hide yes)
			)
		)
		(property "Author" "Antmicro"
			(at 171.45 198.12 0)
			(effects
				(font
					(size 1.27 1.27)
					(thickness 0.15)
				)
				(justify left bottom)
				(hide yes)
			)
		)
		(property "Val" "73k2"
			(at 144.78 217.17 90)
			(effects
				(font
					(size 1.27 1.27)
					(thickness 0.15)
				)
				(justify right)
			)
		)
		(property "Tolerance" "1%"
			(at 153.67 198.12 0)
			(effects
				(font
					(size 1.27 1.27)
				)
				(justify left bottom)
				(hide yes)
			)
		)
		(pin "2"
		)
		(pin "1"
		)
		(instances
			(project "jetson-agx-thor-baseboard"
				(path ""
					(reference "R52")
					(unit 1)
				)
			)
		)
	)
	(symbol
		(lib_id "antmicroCapacitors0402:C_100n_0402")
		(at 48.26 219.71 270)
		(unit 1)
		(exclude_from_sim no)
		(in_bom yes)
		(on_board yes)
		(dnp no)
		(property "Reference" "C48"
			(at 48.895 220.345 90)
			(effects
				(font
					(size 1.27 1.27)
				)
				(justify left)
			)
		)
		(property "Value" "C_100n_0402"
			(at 38.1 240.03 0)
			(effects
				(font
					(size 1.27 1.27)
					(thickness 0.15)
				)
				(justify left bottom)
				(hide yes)
			)
		)
		(property "Footprint" "antmicro-footprints:C_0402_1005Metric"
			(at 35.56 240.03 0)
			(effects
				(font
					(size 1.27 1.27)
					(thickness 0.15)
				)
				(justify left bottom)
				(hide yes)
			)
		)
		(property "Datasheet" "https://www.murata.com/products/productdetail?partno=GRM155R61H104KE14%23"
			(at 33.02 240.03 0)
			(effects
				(font
					(size 1.27 1.27)
					(thickness 0.15)
				)
				(justify left bottom)
				(hide yes)
			)
		)
		(property "Description" "SMD Multilayer Ceramic Capacitor, 0.1 µF, 50 V, 0402 [1005 Metric], ± 10%, X5R, GRM Series"
			(at 48.26 219.71 0)
			(effects
				(font
					(size 1.27 1.27)
				)
				(hide yes)
			)
		)
		(property "Manufacturer" "Murata"
			(at 27.94 240.03 0)
			(effects
				(font
					(size 1.27 1.27)
					(thickness 0.15)
				)
				(justify left bottom)
				(hide yes)
			)
		)
		(property "MPN" "GRM155R61H104KE14D"
			(at 30.48 240.03 0)
			(effects
				(font
					(size 1.27 1.27)
					(thickness 0.15)
				)
				(justify left bottom)
				(hide yes)
			)
		)
		(property "Val" "100n"
			(at 48.895 224.155 90)
			(effects
				(font
					(size 1.27 1.27)
					(thickness 0.15)
				)
				(justify left)
			)
		)
		(property "License" "Apache-2.0"
			(at 25.4 240.03 0)
			(effects
				(font
					(size 1.27 1.27)
					(thickness 0.15)
				)
				(justify left bottom)
				(hide yes)
			)
		)
		(property "Author" "Antmicro"
			(at 22.86 240.03 0)
			(effects
				(font
					(size 1.27 1.27)
					(thickness 0.15)
				)
				(justify left bottom)
				(hide yes)
			)
		)
		(property "Voltage" "50V"
			(at 20.32 240.03 0)
			(effects
				(font
					(size 1.27 1.27)
				)
				(justify left bottom)
				(hide yes)
			)
		)
		(property "Dielectric" "X5R"
			(at 17.78 240.03 0)
			(effects
				(font
					(size 1.27 1.27)
				)
				(justify left bottom)
				(hide yes)
			)
		)
		(pin "1"
		)
		(pin "2"
		)
		(instances
			(project "jetson-agx-thor-baseboard"
				(path ""
					(reference "C48")
					(unit 1)
				)
			)
		)
	)
	(symbol
		(lib_id "antmicropower:GND")
		(at 64.77 121.92 0)
		(unit 1)
		(exclude_from_sim no)
		(in_bom yes)
		(on_board yes)
		(dnp no)
		(property "Reference" "#PWR0548"
			(at 64.77 128.27 0)
			(effects
				(font
					(size 1.27 1.27)
				)
				(justify left bottom)
				(hide yes)
			)
		)
		(property "Value" "GND"
			(at 64.77 125.73 0)
			(effects
				(font
					(size 1.27 1.27)
					(thickness 0.15)
				)
			)
		)
		(property "Footprint" ""
			(at 73.66 129.54 0)
			(effects
				(font
					(size 1.27 1.27)
					(thickness 0.15)
				)
				(justify left bottom)
				(hide yes)
			)
		)
		(property "Datasheet" ""
			(at 73.66 134.62 0)
			(effects
				(font
					(size 1.27 1.27)
					(thickness 0.15)
				)
				(justify left bottom)
				(hide yes)
			)
		)
		(property "Description" ""
			(at 64.77 121.92 0)
			(effects
				(font
					(size 1.27 1.27)
				)
				(hide yes)
			)
		)
		(property "Author" "Antmicro"
			(at 73.66 129.54 0)
			(effects
				(font
					(size 1.27 1.27)
					(thickness 0.15)
				)
				(justify left bottom)
				(hide yes)
			)
		)
		(property "License" "Apache-2.0"
			(at 73.66 132.08 0)
			(effects
				(font
					(size 1.27 1.27)
					(thickness 0.15)
				)
				(justify left bottom)
				(hide yes)
			)
		)
		(pin "1"
		)
		(instances
			(project "jetson-agx-thor-baseboard"
				(path ""
					(reference "#PWR0548")
					(unit 1)
				)
			)
		)
	)
	(symbol
		(lib_id "antmicroCapacitors0402:C_100n_0402")
		(at 50.8 160.02 270)
		(unit 1)
		(exclude_from_sim no)
		(in_bom yes)
		(on_board yes)
		(dnp no)
		(property "Reference" "C374"
			(at 51.308 160.782 90)
			(effects
				(font
					(size 1.27 1.27)
				)
				(justify left)
			)
		)
		(property "Value" "C_100n_0402"
			(at 40.64 180.34 0)
			(effects
				(font
					(size 1.27 1.27)
					(thickness 0.15)
				)
				(justify left bottom)
				(hide yes)
			)
		)
		(property "Footprint" "antmicro-footprints:C_0402_1005Metric"
			(at 38.1 180.34 0)
			(effects
				(font
					(size 1.27 1.27)
					(thickness 0.15)
				)
				(justify left bottom)
				(hide yes)
			)
		)
		(property "Datasheet" "https://www.murata.com/products/productdetail?partno=GRM155R61H104KE14%23"
			(at 35.56 180.34 0)
			(effects
				(font
					(size 1.27 1.27)
					(thickness 0.15)
				)
				(justify left bottom)
				(hide yes)
			)
		)
		(property "Description" "SMD Multilayer Ceramic Capacitor, 0.1 µF, 50 V, 0402 [1005 Metric], ± 10%, X5R, GRM Series"
			(at 50.8 160.02 0)
			(effects
				(font
					(size 1.27 1.27)
				)
				(hide yes)
			)
		)
		(property "Manufacturer" "Murata"
			(at 30.48 180.34 0)
			(effects
				(font
					(size 1.27 1.27)
					(thickness 0.15)
				)
				(justify left bottom)
				(hide yes)
			)
		)
		(property "MPN" "GRM155R61H104KE14D"
			(at 33.02 180.34 0)
			(effects
				(font
					(size 1.27 1.27)
					(thickness 0.15)
				)
				(justify left bottom)
				(hide yes)
			)
		)
		(property "Val" "100n"
			(at 51.308 164.592 90)
			(effects
				(font
					(size 1.27 1.27)
					(thickness 0.15)
				)
				(justify left)
			)
		)
		(property "License" "Apache-2.0"
			(at 27.94 180.34 0)
			(effects
				(font
					(size 1.27 1.27)
					(thickness 0.15)
				)
				(justify left bottom)
				(hide yes)
			)
		)
		(property "Author" "Antmicro"
			(at 25.4 180.34 0)
			(effects
				(font
					(size 1.27 1.27)
					(thickness 0.15)
				)
				(justify left bottom)
				(hide yes)
			)
		)
		(property "Voltage" "50V"
			(at 51.308 167.1319 90)
			(effects
				(font
					(size 1.27 1.27)
				)
				(justify left)
			)
		)
		(property "Dielectric" "X5R"
			(at 20.32 180.34 0)
			(effects
				(font
					(size 1.27 1.27)
				)
				(justify left bottom)
				(hide yes)
			)
		)
		(pin "1"
		)
		(pin "2"
		)
		(instances
			(project "jetson-agx-thor-baseboard"
				(path ""
					(reference "C374")
					(unit 1)
				)
			)
		)
	)
	(symbol
		(lib_id "antmicropower:GND")
		(at 177.8 74.93 0)
		(unit 1)
		(exclude_from_sim no)
		(in_bom yes)
		(on_board yes)
		(dnp no)
		(property "Reference" "#PWR0596"
			(at 177.8 81.28 0)
			(effects
				(font
					(size 1.27 1.27)
				)
				(justify left bottom)
				(hide yes)
			)
		)
		(property "Value" "GND"
			(at 177.8 78.74 0)
			(effects
				(font
					(size 1.27 1.27)
					(thickness 0.15)
				)
			)
		)
		(property "Footprint" ""
			(at 186.69 82.55 0)
			(effects
				(font
					(size 1.27 1.27)
					(thickness 0.15)
				)
				(justify left bottom)
				(hide yes)
			)
		)
		(property "Datasheet" ""
			(at 186.69 87.63 0)
			(effects
				(font
					(size 1.27 1.27)
					(thickness 0.15)
				)
				(justify left bottom)
				(hide yes)
			)
		)
		(property "Description" ""
			(at 177.8 74.93 0)
			(effects
				(font
					(size 1.27 1.27)
				)
				(hide yes)
			)
		)
		(property "Author" "Antmicro"
			(at 186.69 82.55 0)
			(effects
				(font
					(size 1.27 1.27)
					(thickness 0.15)
				)
				(justify left bottom)
				(hide yes)
			)
		)
		(property "License" "Apache-2.0"
			(at 186.69 85.09 0)
			(effects
				(font
					(size 1.27 1.27)
					(thickness 0.15)
				)
				(justify left bottom)
				(hide yes)
			)
		)
		(pin "1"
		)
		(instances
			(project "jetson-agx-thor-baseboard"
				(path ""
					(reference "#PWR0596")
					(unit 1)
				)
			)
		)
	)
	(symbol
		(lib_id "antmicroCapacitorsmisc:C_22u_25V_0805")
		(at 170.18 124.46 90)
		(unit 1)
		(exclude_from_sim no)
		(in_bom yes)
		(on_board yes)
		(dnp no)
		(property "Reference" "C292"
			(at 171.958 119.3801 90)
			(effects
				(font
					(size 1.27 1.27)
					(thickness 0.15)
				)
				(justify right)
			)
		)
		(property "Value" "C_22u_25V_0805"
			(at 180.34 104.14 0)
			(effects
				(font
					(size 1.27 1.27)
					(thickness 0.15)
				)
				(justify left bottom)
				(hide yes)
			)
		)
		(property "Footprint" "antmicro-footprints:C_0805_2012Metric"
			(at 182.88 104.14 0)
			(effects
				(font
					(size 1.27 1.27)
					(thickness 0.15)
				)
				(justify left bottom)
				(hide yes)
			)
		)
		(property "Datasheet" "https://product.samsungsem.com/mlcc/CL21A226MAYNNN.do"
			(at 185.42 104.14 0)
			(effects
				(font
					(size 1.27 1.27)
					(thickness 0.15)
				)
				(justify left bottom)
				(hide yes)
			)
		)
		(property "Description" "SMT Multilayer Ceramic Capacitor, 22uF, +/-20%, 25V, X5R, 0805 [2012 Metric]"
			(at 203.2 104.14 0)
			(effects
				(font
					(size 1.27 1.27)
				)
				(justify left bottom)
				(hide yes)
			)
		)
		(property "MPN" "CL21A226MAYNNNE"
			(at 187.96 104.14 0)
			(effects
				(font
					(size 1.27 1.27)
					(thickness 0.15)
				)
				(justify left bottom)
				(hide yes)
			)
		)
		(property "Manufacturer" "Samsung Electro-Mechanics"
			(at 190.5 104.14 0)
			(effects
				(font
					(size 1.27 1.27)
					(thickness 0.15)
				)
				(justify left bottom)
				(hide yes)
			)
		)
		(property "License" "Apache-2.0"
			(at 193.04 104.14 0)
			(effects
				(font
					(size 1.27 1.27)
					(thickness 0.15)
				)
				(justify left bottom)
				(hide yes)
			)
		)
		(property "Author" "Antmicro"
			(at 195.58 104.14 0)
			(effects
				(font
					(size 1.27 1.27)
					(thickness 0.15)
				)
				(justify left bottom)
				(hide yes)
			)
		)
		(property "Val" "22u"
			(at 171.958 121.9201 90)
			(effects
				(font
					(size 1.27 1.27)
					(thickness 0.15)
				)
				(justify right)
			)
		)
		(property "Voltage" "25V"
			(at 171.958 124.46 90)
			(effects
				(font
					(size 1.27 1.27)
				)
				(justify right)
			)
		)
		(property "Dielectric" "X5R"
			(at 200.66 104.14 0)
			(effects
				(font
					(size 1.27 1.27)
				)
				(justify left bottom)
				(hide yes)
			)
		)
		(property "Public" "False"
			(at 203.2 104.14 0)
			(effects
				(font
					(size 1.27 1.27)
				)
				(justify left bottom)
				(hide yes)
			)
		)
		(pin "2"
		)
		(pin "1"
		)
		(instances
			(project "jetson-agx-thor-baseboard"
				(path ""
					(reference "C292")
					(unit 1)
				)
			)
		)
	)
	(symbol
		(lib_id "antmicroResistors0402:R_10k_0402")
		(at 143.51 273.05 90)
		(unit 1)
		(exclude_from_sim no)
		(in_bom yes)
		(on_board yes)
		(dnp no)
		(property "Reference" "R55"
			(at 144.78 269.24 90)
			(effects
				(font
					(size 1.27 1.27)
					(thickness 0.15)
				)
				(justify right)
			)
		)
		(property "Value" "R_10k_0402"
			(at 156.21 252.73 0)
			(effects
				(font
					(size 1.27 1.27)
					(thickness 0.15)
				)
				(justify left bottom)
				(hide yes)
			)
		)
		(property "Footprint" "antmicro-footprints:R_0402_1005Metric"
			(at 158.75 252.73 0)
			(effects
				(font
					(size 1.27 1.27)
					(thickness 0.15)
				)
				(justify left bottom)
				(hide yes)
			)
		)
		(property "Datasheet" "https://www.bourns.com/docs/product-datasheets/cr.pdf"
			(at 161.29 252.73 0)
			(effects
				(font
					(size 1.27 1.27)
					(thickness 0.15)
				)
				(justify left bottom)
				(hide yes)
			)
		)
		(property "Description" "SMD Chip Resistor, 10 kohm, ± 1%, 62.5 mW, 0402 [1005 Metric], Thick Film, General Purpose"
			(at 143.51 273.05 0)
			(effects
				(font
					(size 1.27 1.27)
				)
				(hide yes)
			)
		)
		(property "MPN" "CR0402-FX-1002GLF"
			(at 163.83 252.73 0)
			(effects
				(font
					(size 1.27 1.27)
					(thickness 0.15)
				)
				(justify left bottom)
				(hide yes)
			)
		)
		(property "Manufacturer" "Bourns"
			(at 166.37 252.73 0)
			(effects
				(font
					(size 1.27 1.27)
					(thickness 0.15)
				)
				(justify left bottom)
				(hide yes)
			)
		)
		(property "License" "Apache-2.0"
			(at 168.91 252.73 0)
			(effects
				(font
					(size 1.27 1.27)
					(thickness 0.15)
				)
				(justify left bottom)
				(hide yes)
			)
		)
		(property "Author" "Antmicro"
			(at 171.45 252.73 0)
			(effects
				(font
					(size 1.27 1.27)
					(thickness 0.15)
				)
				(justify left bottom)
				(hide yes)
			)
		)
		(property "Val" "10k"
			(at 144.78 271.78 90)
			(effects
				(font
					(size 1.27 1.27)
					(thickness 0.15)
				)
				(justify right)
			)
		)
		(property "Tolerance" "1%"
			(at 153.67 252.73 0)
			(effects
				(font
					(size 1.27 1.27)
				)
				(justify left bottom)
				(hide yes)
			)
		)
		(pin "2"
		)
		(pin "1"
		)
		(instances
			(project "jetson-agx-thor-baseboard"
				(path ""
					(reference "R55")
					(unit 1)
				)
			)
		)
	)
	(symbol
		(lib_id "antmicropower:GND")
		(at 21.59 232.41 0)
		(unit 1)
		(exclude_from_sim no)
		(in_bom yes)
		(on_board yes)
		(dnp no)
		(property "Reference" "#PWR0604"
			(at 21.59 238.76 0)
			(effects
				(font
					(size 1.27 1.27)
				)
				(justify left bottom)
				(hide yes)
			)
		)
		(property "Value" "GND"
			(at 21.59 236.22 0)
			(effects
				(font
					(size 1.27 1.27)
					(thickness 0.15)
				)
			)
		)
		(property "Footprint" ""
			(at 30.48 240.03 0)
			(effects
				(font
					(size 1.27 1.27)
					(thickness 0.15)
				)
				(justify left bottom)
				(hide yes)
			)
		)
		(property "Datasheet" ""
			(at 30.48 245.11 0)
			(effects
				(font
					(size 1.27 1.27)
					(thickness 0.15)
				)
				(justify left bottom)
				(hide yes)
			)
		)
		(property "Description" ""
			(at 21.59 232.41 0)
			(effects
				(font
					(size 1.27 1.27)
				)
				(hide yes)
			)
		)
		(property "Author" "Antmicro"
			(at 30.48 240.03 0)
			(effects
				(font
					(size 1.27 1.27)
					(thickness 0.15)
				)
				(justify left bottom)
				(hide yes)
			)
		)
		(property "License" "Apache-2.0"
			(at 30.48 242.57 0)
			(effects
				(font
					(size 1.27 1.27)
					(thickness 0.15)
				)
				(justify left bottom)
				(hide yes)
			)
		)
		(pin "1"
		)
		(instances
			(project "jetson-agx-thor-baseboard"
				(path ""
					(reference "#PWR0604")
					(unit 1)
				)
			)
		)
	)
	(symbol
		(lib_id "antmicropower:+3V3_AON")
		(at 48.26 128.27 0)
		(unit 1)
		(exclude_from_sim no)
		(in_bom yes)
		(on_board yes)
		(dnp no)
		(property "Reference" "#PWR0147"
			(at 48.26 132.08 0)
			(effects
				(font
					(size 1.27 1.27)
				)
				(hide yes)
			)
		)
		(property "Value" "+3V3_AON"
			(at 48.26 123.19 0)
			(effects
				(font
					(size 1.27 1.27)
				)
			)
		)
		(property "Footprint" ""
			(at 48.26 128.27 0)
			(effects
				(font
					(size 1.27 1.27)
				)
				(hide yes)
			)
		)
		(property "Datasheet" ""
			(at 48.26 128.27 0)
			(effects
				(font
					(size 1.27 1.27)
				)
				(hide yes)
			)
		)
		(property "Description" ""
			(at 48.26 128.27 0)
			(effects
				(font
					(size 1.27 1.27)
				)
				(hide yes)
			)
		)
		(pin "1"
		)
		(instances
			(project "jetson-agx-thor-baseboard"
				(path ""
					(reference "#PWR0147")
					(unit 1)
				)
			)
		)
	)
	(symbol
		(lib_id "antmicropower:GND")
		(at 170.18 279.4 0)
		(unit 1)
		(exclude_from_sim no)
		(in_bom yes)
		(on_board yes)
		(dnp no)
		(property "Reference" "#PWR0146"
			(at 170.18 285.75 0)
			(effects
				(font
					(size 1.27 1.27)
				)
				(justify left bottom)
				(hide yes)
			)
		)
		(property "Value" "GND"
			(at 170.18 283.21 0)
			(effects
				(font
					(size 1.27 1.27)
					(thickness 0.15)
				)
			)
		)
		(property "Footprint" ""
			(at 179.07 287.02 0)
			(effects
				(font
					(size 1.27 1.27)
					(thickness 0.15)
				)
				(justify left bottom)
				(hide yes)
			)
		)
		(property "Datasheet" ""
			(at 179.07 292.1 0)
			(effects
				(font
					(size 1.27 1.27)
					(thickness 0.15)
				)
				(justify left bottom)
				(hide yes)
			)
		)
		(property "Description" ""
			(at 170.18 279.4 0)
			(effects
				(font
					(size 1.27 1.27)
				)
				(hide yes)
			)
		)
		(property "Author" "Antmicro"
			(at 179.07 287.02 0)
			(effects
				(font
					(size 1.27 1.27)
					(thickness 0.15)
				)
				(justify left bottom)
				(hide yes)
			)
		)
		(property "License" "Apache-2.0"
			(at 179.07 289.56 0)
			(effects
				(font
					(size 1.27 1.27)
					(thickness 0.15)
				)
				(justify left bottom)
				(hide yes)
			)
		)
		(pin "1"
		)
		(instances
			(project "jetson-agx-thor-baseboard"
				(path ""
					(reference "#PWR0146")
					(unit 1)
				)
			)
		)
	)
	(symbol
		(lib_id "antmicropower:GND")
		(at 162.56 140.97 0)
		(unit 1)
		(exclude_from_sim no)
		(in_bom yes)
		(on_board yes)
		(dnp no)
		(property "Reference" "#PWR0589"
			(at 162.56 147.32 0)
			(effects
				(font
					(size 1.27 1.27)
				)
				(justify left bottom)
				(hide yes)
			)
		)
		(property "Value" "GND"
			(at 162.56 144.78 0)
			(effects
				(font
					(size 1.27 1.27)
					(thickness 0.15)
				)
			)
		)
		(property "Footprint" ""
			(at 171.45 148.59 0)
			(effects
				(font
					(size 1.27 1.27)
					(thickness 0.15)
				)
				(justify left bottom)
				(hide yes)
			)
		)
		(property "Datasheet" ""
			(at 171.45 153.67 0)
			(effects
				(font
					(size 1.27 1.27)
					(thickness 0.15)
				)
				(justify left bottom)
				(hide yes)
			)
		)
		(property "Description" ""
			(at 162.56 140.97 0)
			(effects
				(font
					(size 1.27 1.27)
				)
				(hide yes)
			)
		)
		(property "Author" "Antmicro"
			(at 171.45 148.59 0)
			(effects
				(font
					(size 1.27 1.27)
					(thickness 0.15)
				)
				(justify left bottom)
				(hide yes)
			)
		)
		(property "License" "Apache-2.0"
			(at 171.45 151.13 0)
			(effects
				(font
					(size 1.27 1.27)
					(thickness 0.15)
				)
				(justify left bottom)
				(hide yes)
			)
		)
		(pin "1"
		)
		(instances
			(project "jetson-agx-thor-baseboard"
				(path ""
					(reference "#PWR0589")
					(unit 1)
				)
			)
		)
	)
	(symbol
		(lib_id "antmicroResistors0402:R_49k9_0402")
		(at 16.51 179.07 270)
		(mirror x)
		(unit 1)
		(exclude_from_sim no)
		(in_bom yes)
		(on_board yes)
		(dnp no)
		(property "Reference" "R75"
			(at 17.78 175.26 90)
			(effects
				(font
					(size 1.27 1.27)
					(thickness 0.15)
				)
				(justify left)
			)
		)
		(property "Value" "R_49k9_0402"
			(at 3.81 158.75 0)
			(effects
				(font
					(size 1.27 1.27)
					(thickness 0.15)
				)
				(justify left bottom)
				(hide yes)
			)
		)
		(property "Footprint" "antmicro-footprints:R_0402_1005Metric"
			(at 1.27 158.75 0)
			(effects
				(font
					(size 1.27 1.27)
					(thickness 0.15)
				)
				(justify left bottom)
				(hide yes)
			)
		)
		(property "Datasheet" "https://www.bourns.com/docs/product-datasheets/cr.pdf"
			(at -1.27 158.75 0)
			(effects
				(font
					(size 1.27 1.27)
					(thickness 0.15)
				)
				(justify left bottom)
				(hide yes)
			)
		)
		(property "Description" "SMD Chip Resistor, 49.9 kohm, ± 1%, 63 mW, 0402 [1005 Metric], Thick Film, General Purpose"
			(at 16.51 179.07 0)
			(effects
				(font
					(size 1.27 1.27)
				)
				(hide yes)
			)
		)
		(property "MPN" "CR0402-FX-4992GLF"
			(at -3.81 158.75 0)
			(effects
				(font
					(size 1.27 1.27)
					(thickness 0.15)
				)
				(justify left bottom)
				(hide yes)
			)
		)
		(property "Manufacturer" "Bourns"
			(at -6.35 158.75 0)
			(effects
				(font
					(size 1.27 1.27)
					(thickness 0.15)
				)
				(justify left bottom)
				(hide yes)
			)
		)
		(property "License" "Apache-2.0"
			(at -8.89 158.75 0)
			(effects
				(font
					(size 1.27 1.27)
					(thickness 0.15)
				)
				(justify left bottom)
				(hide yes)
			)
		)
		(property "Author" "Antmicro"
			(at -11.43 158.75 0)
			(effects
				(font
					(size 1.27 1.27)
					(thickness 0.15)
				)
				(justify left bottom)
				(hide yes)
			)
		)
		(property "Val" "49k9"
			(at 17.78 177.8 90)
			(effects
				(font
					(size 1.27 1.27)
					(thickness 0.15)
				)
				(justify left)
			)
		)
		(property "Tolerance" "1%"
			(at 6.35 158.75 0)
			(effects
				(font
					(size 1.27 1.27)
				)
				(justify left bottom)
				(hide yes)
			)
		)
		(pin "2"
		)
		(pin "1"
		)
		(instances
			(project "jetson-agx-thor-baseboard"
				(path ""
					(reference "R75")
					(unit 1)
				)
			)
		)
	)
	(symbol
		(lib_id "antmicroResistors0402:R_499k_0402")
		(at 55.88 278.13 90)
		(unit 1)
		(exclude_from_sim no)
		(in_bom yes)
		(on_board yes)
		(dnp no)
		(property "Reference" "R39"
			(at 57.15 274.32 90)
			(effects
				(font
					(size 1.27 1.27)
					(thickness 0.15)
				)
				(justify right)
			)
		)
		(property "Value" "R_499k_0402"
			(at 68.58 257.81 0)
			(effects
				(font
					(size 1.27 1.27)
					(thickness 0.15)
				)
				(justify left bottom)
				(hide yes)
			)
		)
		(property "Footprint" "antmicro-footprints:R_0402_1005Metric"
			(at 71.12 257.81 0)
			(effects
				(font
					(size 1.27 1.27)
					(thickness 0.15)
				)
				(justify left bottom)
				(hide yes)
			)
		)
		(property "Datasheet" "https://www.mouser.com/datasheet/2/54/cr-1858361.pdf"
			(at 73.66 257.81 0)
			(effects
				(font
					(size 1.27 1.27)
					(thickness 0.15)
				)
				(justify left bottom)
				(hide yes)
			)
		)
		(property "Description" "SMD Chip Resistor, 499 kohm, ± 1%, 63 mW, 0402 [1005 Metric], Thick Film, General Purpose"
			(at 55.88 278.13 0)
			(effects
				(font
					(size 1.27 1.27)
				)
				(hide yes)
			)
		)
		(property "MPN" "CR0402-FX-4993GLF"
			(at 76.2 257.81 0)
			(effects
				(font
					(size 1.27 1.27)
					(thickness 0.15)
				)
				(justify left bottom)
				(hide yes)
			)
		)
		(property "Manufacturer" "Bourns"
			(at 78.74 257.81 0)
			(effects
				(font
					(size 1.27 1.27)
					(thickness 0.15)
				)
				(justify left bottom)
				(hide yes)
			)
		)
		(property "License" "Apache-2.0"
			(at 81.28 257.81 0)
			(effects
				(font
					(size 1.27 1.27)
					(thickness 0.15)
				)
				(justify left bottom)
				(hide yes)
			)
		)
		(property "Author" "Antmicro"
			(at 83.82 257.81 0)
			(effects
				(font
					(size 1.27 1.27)
					(thickness 0.15)
				)
				(justify left bottom)
				(hide yes)
			)
		)
		(property "Val" "499k"
			(at 57.15 276.86 90)
			(effects
				(font
					(size 1.27 1.27)
					(thickness 0.15)
				)
				(justify right)
			)
		)
		(property "Tolerance" "1%"
			(at 66.04 257.81 0)
			(effects
				(font
					(size 1.27 1.27)
				)
				(justify left bottom)
				(hide yes)
			)
		)
		(pin "2"
		)
		(pin "1"
		)
		(instances
			(project "jetson-agx-thor-baseboard"
				(path ""
					(reference "R39")
					(unit 1)
				)
			)
		)
	)
	(symbol
		(lib_id "antmicroFixedInductors:L_1u_20A_Bourns-SRP6050CA")
		(at 134.62 212.09 0)
		(unit 1)
		(exclude_from_sim no)
		(in_bom yes)
		(on_board yes)
		(dnp no)
		(fields_autoplaced yes)
		(property "Reference" "L1"
			(at 137.16 207.01 0)
			(effects
				(font
					(size 1.27 1.27)
					(thickness 0.15)
				)
			)
		)
		(property "Value" "L_1u_20A_Bourns-SRP6050CA"
			(at 148.59 214.63 0)
			(effects
				(font
					(size 1.27 1.27)
					(thickness 0.15)
				)
				(justify left bottom)
				(hide yes)
			)
		)
		(property "Footprint" "antmicro-footprints:L_Bourns-SRP6050CA"
			(at 148.59 219.71 0)
			(effects
				(font
					(size 1.27 1.27)
					(thickness 0.15)
				)
				(justify left bottom)
				(hide yes)
			)
		)
		(property "Datasheet" "https://www.bourns.com/docs/Product-Datasheets/SRP6050CA.pdf"
			(at 148.59 222.25 0)
			(effects
				(font
					(size 1.27 1.27)
					(thickness 0.15)
				)
				(justify left bottom)
				(hide yes)
			)
		)
		(property "Description" "Power Inductor (SMT), 1 µH, 20 A, Shielded, 23 A, SRP6050CA"
			(at 134.62 212.09 0)
			(effects
				(font
					(size 1.27 1.27)
				)
				(hide yes)
			)
		)
		(property "Val" "1u/20A"
			(at 137.16 209.55 0)
			(effects
				(font
					(size 1.27 1.27)
					(thickness 0.15)
				)
			)
		)
		(property "Manufacturer" "Bourns"
			(at 148.59 224.79 0)
			(effects
				(font
					(size 1.27 1.27)
					(thickness 0.15)
				)
				(justify left bottom)
				(hide yes)
			)
		)
		(property "MPN" "SRP6050CA-1R0M"
			(at 148.59 227.33 0)
			(effects
				(font
					(size 1.27 1.27)
					(thickness 0.15)
				)
				(justify left bottom)
				(hide yes)
			)
		)
		(property "ISat" "23 A"
			(at 148.59 228.6 0)
			(effects
				(font
					(size 1.27 1.27)
				)
				(justify left)
				(hide yes)
			)
		)
		(property "IMax" "20 A"
			(at 148.59 232.41 0)
			(effects
				(font
					(size 1.27 1.27)
					(thickness 0.15)
				)
				(justify left bottom)
				(hide yes)
			)
		)
		(property "Size" "6.6x6.4"
			(at 148.59 234.95 0)
			(effects
				(font
					(size 1.27 1.27)
					(thickness 0.15)
				)
				(justify left bottom)
				(hide yes)
			)
		)
		(property "Author" "Antmicro"
			(at 148.59 237.49 0)
			(effects
				(font
					(size 1.27 1.27)
					(thickness 0.15)
				)
				(justify left bottom)
				(hide yes)
			)
		)
		(property "License" "Apache-2.0"
			(at 148.59 240.03 0)
			(effects
				(font
					(size 1.27 1.27)
					(thickness 0.15)
				)
				(justify left bottom)
				(hide yes)
			)
		)
		(pin "2"
		)
		(pin "1"
		)
		(instances
			(project "jetson-agx-thor-baseboard"
				(path ""
					(reference "L1")
					(unit 1)
				)
			)
		)
	)
	(symbol
		(lib_id "antmicroCapacitorsmisc:C_22u_25V_0805")
		(at 185.42 139.7 90)
		(unit 1)
		(exclude_from_sim no)
		(in_bom yes)
		(on_board yes)
		(dnp no)
		(property "Reference" "C303"
			(at 187.198 134.6201 90)
			(effects
				(font
					(size 1.27 1.27)
					(thickness 0.15)
				)
				(justify right)
			)
		)
		(property "Value" "C_22u_25V_0805"
			(at 195.58 119.38 0)
			(effects
				(font
					(size 1.27 1.27)
					(thickness 0.15)
				)
				(justify left bottom)
				(hide yes)
			)
		)
		(property "Footprint" "antmicro-footprints:C_0805_2012Metric"
			(at 198.12 119.38 0)
			(effects
				(font
					(size 1.27 1.27)
					(thickness 0.15)
				)
				(justify left bottom)
				(hide yes)
			)
		)
		(property "Datasheet" "https://product.samsungsem.com/mlcc/CL21A226MAYNNN.do"
			(at 200.66 119.38 0)
			(effects
				(font
					(size 1.27 1.27)
					(thickness 0.15)
				)
				(justify left bottom)
				(hide yes)
			)
		)
		(property "Description" "SMT Multilayer Ceramic Capacitor, 22uF, +/-20%, 25V, X5R, 0805 [2012 Metric]"
			(at 218.44 119.38 0)
			(effects
				(font
					(size 1.27 1.27)
				)
				(justify left bottom)
				(hide yes)
			)
		)
		(property "MPN" "CL21A226MAYNNNE"
			(at 203.2 119.38 0)
			(effects
				(font
					(size 1.27 1.27)
					(thickness 0.15)
				)
				(justify left bottom)
				(hide yes)
			)
		)
		(property "Manufacturer" "Samsung Electro-Mechanics"
			(at 205.74 119.38 0)
			(effects
				(font
					(size 1.27 1.27)
					(thickness 0.15)
				)
				(justify left bottom)
				(hide yes)
			)
		)
		(property "License" "Apache-2.0"
			(at 208.28 119.38 0)
			(effects
				(font
					(size 1.27 1.27)
					(thickness 0.15)
				)
				(justify left bottom)
				(hide yes)
			)
		)
		(property "Author" "Antmicro"
			(at 210.82 119.38 0)
			(effects
				(font
					(size 1.27 1.27)
					(thickness 0.15)
				)
				(justify left bottom)
				(hide yes)
			)
		)
		(property "Val" "22u"
			(at 187.198 137.1601 90)
			(effects
				(font
					(size 1.27 1.27)
					(thickness 0.15)
				)
				(justify right)
			)
		)
		(property "Voltage" "25V"
			(at 187.198 139.7 90)
			(effects
				(font
					(size 1.27 1.27)
				)
				(justify right)
			)
		)
		(property "Dielectric" "X5R"
			(at 215.9 119.38 0)
			(effects
				(font
					(size 1.27 1.27)
				)
				(justify left bottom)
				(hide yes)
			)
		)
		(property "Public" "False"
			(at 218.44 119.38 0)
			(effects
				(font
					(size 1.27 1.27)
				)
				(justify left bottom)
				(hide yes)
			)
		)
		(pin "2"
		)
		(pin "1"
		)
		(instances
			(project "jetson-agx-thor-baseboard"
				(path ""
					(reference "C303")
					(unit 1)
				)
			)
		)
	)
	(symbol
		(lib_id "antmicropower:GND")
		(at 40.64 41.91 0)
		(unit 1)
		(exclude_from_sim no)
		(in_bom yes)
		(on_board yes)
		(dnp no)
		(property "Reference" "#PWR084"
			(at 40.64 48.26 0)
			(effects
				(font
					(size 1.27 1.27)
				)
				(justify left bottom)
				(hide yes)
			)
		)
		(property "Value" "GND"
			(at 40.64 45.72 0)
			(effects
				(font
					(size 1.27 1.27)
					(thickness 0.15)
				)
			)
		)
		(property "Footprint" ""
			(at 49.53 49.53 0)
			(effects
				(font
					(size 1.27 1.27)
					(thickness 0.15)
				)
				(justify left bottom)
				(hide yes)
			)
		)
		(property "Datasheet" ""
			(at 49.53 54.61 0)
			(effects
				(font
					(size 1.27 1.27)
					(thickness 0.15)
				)
				(justify left bottom)
				(hide yes)
			)
		)
		(property "Description" ""
			(at 40.64 41.91 0)
			(effects
				(font
					(size 1.27 1.27)
				)
				(hide yes)
			)
		)
		(property "Author" "Antmicro"
			(at 49.53 49.53 0)
			(effects
				(font
					(size 1.27 1.27)
					(thickness 0.15)
				)
				(justify left bottom)
				(hide yes)
			)
		)
		(property "License" "Apache-2.0"
			(at 49.53 52.07 0)
			(effects
				(font
					(size 1.27 1.27)
					(thickness 0.15)
				)
				(justify left bottom)
				(hide yes)
			)
		)
		(pin "1"
		)
		(instances
			(project "jetson-agx-thor-baseboard"
				(path ""
					(reference "#PWR084")
					(unit 1)
				)
			)
		)
	)
	(symbol
		(lib_id "antmicroCapacitorsmisc:C_22u_25V_0805")
		(at 255.27 43.18 90)
		(unit 1)
		(exclude_from_sim no)
		(in_bom yes)
		(on_board yes)
		(dnp no)
		(property "Reference" "C28"
			(at 257.302 38.1 90)
			(effects
				(font
					(size 1.27 1.27)
				)
				(justify right)
			)
		)
		(property "Value" "C_22u_25V_0805"
			(at 265.43 22.86 0)
			(effects
				(font
					(size 1.27 1.27)
					(thickness 0.15)
				)
				(justify left bottom)
				(hide yes)
			)
		)
		(property "Footprint" "antmicro-footprints:C_0805_2012Metric"
			(at 267.97 22.86 0)
			(effects
				(font
					(size 1.27 1.27)
					(thickness 0.15)
				)
				(justify left bottom)
				(hide yes)
			)
		)
		(property "Datasheet" "https://product.samsungsem.com/mlcc/CL21A226MAYNNN.do"
			(at 270.51 22.86 0)
			(effects
				(font
					(size 1.27 1.27)
					(thickness 0.15)
				)
				(justify left bottom)
				(hide yes)
			)
		)
		(property "Description" "SMT Multilayer Ceramic Capacitor, 22uF, +/-20%, 25V, X5R, 0805 [2012 Metric]"
			(at 255.27 43.18 0)
			(effects
				(font
					(size 1.27 1.27)
				)
				(hide yes)
			)
		)
		(property "Manufacturer" "Samsung Electro-Mechanics"
			(at 275.59 22.86 0)
			(effects
				(font
					(size 1.27 1.27)
					(thickness 0.15)
				)
				(justify left bottom)
				(hide yes)
			)
		)
		(property "MPN" "CL21A226MAYNNNE"
			(at 273.05 22.86 0)
			(effects
				(font
					(size 1.27 1.27)
					(thickness 0.15)
				)
				(justify left bottom)
				(hide yes)
			)
		)
		(property "Val" "22u"
			(at 257.302 40.6401 90)
			(effects
				(font
					(size 1.27 1.27)
					(thickness 0.15)
				)
				(justify right)
			)
		)
		(property "License" "Apache-2.0"
			(at 278.13 22.86 0)
			(effects
				(font
					(size 1.27 1.27)
					(thickness 0.15)
				)
				(justify left bottom)
				(hide yes)
			)
		)
		(property "Author" "Antmicro"
			(at 280.67 22.86 0)
			(effects
				(font
					(size 1.27 1.27)
					(thickness 0.15)
				)
				(justify left bottom)
				(hide yes)
			)
		)
		(property "Voltage" "25V"
			(at 257.302 43.18 90)
			(effects
				(font
					(size 1.27 1.27)
				)
				(justify right)
			)
		)
		(property "Dielectric" "X5R"
			(at 285.75 22.86 0)
			(effects
				(font
					(size 1.27 1.27)
				)
				(justify left bottom)
				(hide yes)
			)
		)
		(property "Public" "False"
			(at 288.29 22.86 0)
			(effects
				(font
					(size 1.27 1.27)
				)
				(justify left bottom)
				(hide yes)
			)
		)
		(pin "1"
		)
		(pin "2"
		)
		(instances
			(project "jetson-agx-thor-baseboard"
				(path ""
					(reference "C28")
					(unit 1)
				)
			)
		)
	)
	(symbol
		(lib_id "antmicroResistors0402:R_27R_0402")
		(at 198.12 209.55 270)
		(mirror x)
		(unit 1)
		(exclude_from_sim no)
		(in_bom yes)
		(on_board yes)
		(dnp no)
		(property "Reference" "R315"
			(at 196.85 205.7399 90)
			(effects
				(font
					(size 1.27 1.27)
				)
				(justify right)
			)
		)
		(property "Value" "R_27R_0402"
			(at 185.42 189.23 0)
			(effects
				(font
					(size 1.27 1.27)
					(thickness 0.15)
				)
				(justify left bottom)
				(hide yes)
			)
		)
		(property "Footprint" "antmicro-footprints:R_0402_1005Metric"
			(at 182.88 189.23 0)
			(effects
				(font
					(size 1.27 1.27)
					(thickness 0.15)
				)
				(justify left bottom)
				(hide yes)
			)
		)
		(property "Datasheet" "https://www.bourns.com/docs/product-datasheets/cr.pdf"
			(at 180.34 189.23 0)
			(effects
				(font
					(size 1.27 1.27)
					(thickness 0.15)
				)
				(justify left bottom)
				(hide yes)
			)
		)
		(property "Description" "SMD Chip Resistor, 27 ohm, ± 1%, 63 mW, 0402 [1005 Metric], Thick Film, General Purpose"
			(at 198.12 209.55 0)
			(effects
				(font
					(size 1.27 1.27)
				)
				(hide yes)
			)
		)
		(property "Manufacturer" "Bourns"
			(at 175.26 189.23 0)
			(effects
				(font
					(size 1.27 1.27)
					(thickness 0.15)
				)
				(justify left bottom)
				(hide yes)
			)
		)
		(property "MPN" "CR0402-FX-27R0GLF"
			(at 177.8 189.23 0)
			(effects
				(font
					(size 1.27 1.27)
					(thickness 0.15)
				)
				(justify left bottom)
				(hide yes)
			)
		)
		(property "Val" "27R"
			(at 196.85 208.28 90)
			(effects
				(font
					(size 1.27 1.27)
					(thickness 0.15)
				)
				(justify right)
			)
		)
		(property "License" "Apache-2.0"
			(at 172.72 189.23 0)
			(effects
				(font
					(size 1.27 1.27)
					(thickness 0.15)
				)
				(justify left bottom)
				(hide yes)
			)
		)
		(property "Author" "Antmicro"
			(at 170.18 189.23 0)
			(effects
				(font
					(size 1.27 1.27)
					(thickness 0.15)
				)
				(justify left bottom)
				(hide yes)
			)
		)
		(property "Tolerance" "1%"
			(at 187.96 189.23 0)
			(effects
				(font
					(size 1.27 1.27)
				)
				(justify left bottom)
				(hide yes)
			)
		)
		(pin "1"
		)
		(pin "2"
		)
		(instances
			(project "jetson-agx-thor-baseboard"
				(path ""
					(reference "R315")
					(unit 1)
				)
			)
		)
	)
	(symbol
		(lib_id "antmicroCapacitors0402:C_100n_0402")
		(at 129.54 207.01 180)
		(unit 1)
		(exclude_from_sim no)
		(in_bom yes)
		(on_board yes)
		(dnp no)
		(fields_autoplaced yes)
		(property "Reference" "C59"
			(at 126.9936 200.66 0)
			(effects
				(font
					(size 1.27 1.27)
				)
			)
		)
		(property "Value" "C_100n_0402"
			(at 109.22 196.85 0)
			(effects
				(font
					(size 1.27 1.27)
					(thickness 0.15)
				)
				(justify left bottom)
				(hide yes)
			)
		)
		(property "Footprint" "antmicro-footprints:C_0402_1005Metric"
			(at 109.22 194.31 0)
			(effects
				(font
					(size 1.27 1.27)
					(thickness 0.15)
				)
				(justify left bottom)
				(hide yes)
			)
		)
		(property "Datasheet" "https://www.murata.com/products/productdetail?partno=GRM155R61H104KE14%23"
			(at 109.22 191.77 0)
			(effects
				(font
					(size 1.27 1.27)
					(thickness 0.15)
				)
				(justify left bottom)
				(hide yes)
			)
		)
		(property "Description" "SMD Multilayer Ceramic Capacitor, 0.1 µF, 50 V, 0402 [1005 Metric], ± 10%, X5R, GRM Series"
			(at 129.54 207.01 0)
			(effects
				(font
					(size 1.27 1.27)
				)
				(hide yes)
			)
		)
		(property "Manufacturer" "Murata"
			(at 109.22 186.69 0)
			(effects
				(font
					(size 1.27 1.27)
					(thickness 0.15)
				)
				(justify left bottom)
				(hide yes)
			)
		)
		(property "MPN" "GRM155R61H104KE14D"
			(at 109.22 189.23 0)
			(effects
				(font
					(size 1.27 1.27)
					(thickness 0.15)
				)
				(justify left bottom)
				(hide yes)
			)
		)
		(property "Val" "100n"
			(at 126.9936 203.2 0)
			(effects
				(font
					(size 1.27 1.27)
					(thickness 0.15)
				)
			)
		)
		(property "License" "Apache-2.0"
			(at 109.22 184.15 0)
			(effects
				(font
					(size 1.27 1.27)
					(thickness 0.15)
				)
				(justify left bottom)
				(hide yes)
			)
		)
		(property "Author" "Antmicro"
			(at 109.22 181.61 0)
			(effects
				(font
					(size 1.27 1.27)
					(thickness 0.15)
				)
				(justify left bottom)
				(hide yes)
			)
		)
		(property "Voltage" "50V"
			(at 109.22 179.07 0)
			(effects
				(font
					(size 1.27 1.27)
				)
				(justify left bottom)
				(hide yes)
			)
		)
		(property "Dielectric" "X5R"
			(at 109.22 176.53 0)
			(effects
				(font
					(size 1.27 1.27)
				)
				(justify left bottom)
				(hide yes)
			)
		)
		(pin "1"
		)
		(pin "2"
		)
		(instances
			(project "jetson-agx-thor-baseboard"
				(path ""
					(reference "C59")
					(unit 1)
				)
			)
		)
	)
	(symbol
		(lib_id "antmicroPowerMeasurement:INA219AIDCNR")
		(at 199.39 266.7 0)
		(unit 1)
		(exclude_from_sim no)
		(in_bom yes)
		(on_board yes)
		(dnp no)
		(property "Reference" "U60"
			(at 207.01 261.62 0)
			(effects
				(font
					(size 1.27 1.27)
				)
			)
		)
		(property "Value" "INA219AIDCNR"
			(at 199.39 266.7 0)
			(effects
				(font
					(size 1.27 1.27)
				)
				(hide yes)
			)
		)
		(property "Footprint" "antmicro-footprints:SOT-23-8"
			(at 199.39 266.7 0)
			(effects
				(font
					(size 1.27 1.27)
				)
				(hide yes)
			)
		)
		(property "Datasheet" "https://www.ti.com/lit/ds/symlink/ina219.pdf?ts=1713856455637&ref_url=https%253A%252F%252Fwww.mouser.es%252F"
			(at 199.39 266.7 0)
			(effects
				(font
					(size 1.27 1.27)
				)
				(hide yes)
			)
		)
		(property "Description" "Zerø-Drift, Bidirectional Current/Power Monitor With I2C Interface"
			(at 199.39 266.7 0)
			(effects
				(font
					(size 1.27 1.27)
				)
				(hide yes)
			)
		)
		(property "Manufacturer" "Texas Instruments"
			(at 199.39 266.7 0)
			(effects
				(font
					(size 1.27 1.27)
				)
				(hide yes)
			)
		)
		(property "MPN" "INA219AIDCNR"
			(at 207.01 264.16 0)
			(effects
				(font
					(size 1.27 1.27)
				)
			)
		)
		(property "Author" "Antmicro"
			(at 224.79 287.02 0)
			(effects
				(font
					(size 1.27 1.27)
					(thickness 0.15)
				)
				(justify left bottom)
				(hide yes)
			)
		)
		(property "License" "Apache-2.0"
			(at 224.79 289.56 0)
			(effects
				(font
					(size 1.27 1.27)
					(thickness 0.15)
				)
				(justify left bottom)
				(hide yes)
			)
		)
		(pin "1"
		)
		(pin "2"
		)
		(pin "5"
		)
		(pin "6"
		)
		(pin "8"
		)
		(pin "3"
		)
		(pin "7"
		)
		(pin "4"
		)
		(instances
			(project "jetson-agx-thor-baseboard"
				(path ""
					(reference "U60")
					(unit 1)
				)
			)
		)
	)
	(symbol
		(lib_id "antmicroCapacitorsmisc:C_22u_25V_0805")
		(at 34.29 39.37 90)
		(unit 1)
		(exclude_from_sim no)
		(in_bom yes)
		(on_board yes)
		(dnp no)
		(property "Reference" "C241"
			(at 34.925 34.925 90)
			(effects
				(font
					(size 1.27 1.27)
					(thickness 0.15)
				)
				(justify right)
			)
		)
		(property "Value" "C_22u_25V_0805"
			(at 44.45 19.05 0)
			(effects
				(font
					(size 1.27 1.27)
					(thickness 0.15)
				)
				(justify left bottom)
				(hide yes)
			)
		)
		(property "Footprint" "antmicro-footprints:C_0805_2012Metric"
			(at 46.99 19.05 0)
			(effects
				(font
					(size 1.27 1.27)
					(thickness 0.15)
				)
				(justify left bottom)
				(hide yes)
			)
		)
		(property "Datasheet" "https://product.samsungsem.com/mlcc/CL21A226MAYNNN.do"
			(at 49.53 19.05 0)
			(effects
				(font
					(size 1.27 1.27)
					(thickness 0.15)
				)
				(justify left bottom)
				(hide yes)
			)
		)
		(property "Description" "SMT Multilayer Ceramic Capacitor, 22uF, +/-20%, 25V, X5R, 0805 [2012 Metric]"
			(at 34.29 39.37 0)
			(effects
				(font
					(size 1.27 1.27)
				)
				(hide yes)
			)
		)
		(property "MPN" "CL21A226MAYNNNE"
			(at 52.07 19.05 0)
			(effects
				(font
					(size 1.27 1.27)
					(thickness 0.15)
				)
				(justify left bottom)
				(hide yes)
			)
		)
		(property "Manufacturer" "Samsung Electro-Mechanics"
			(at 54.61 19.05 0)
			(effects
				(font
					(size 1.27 1.27)
					(thickness 0.15)
				)
				(justify left bottom)
				(hide yes)
			)
		)
		(property "License" "Apache-2.0"
			(at 57.15 19.05 0)
			(effects
				(font
					(size 1.27 1.27)
					(thickness 0.15)
				)
				(justify left bottom)
				(hide yes)
			)
		)
		(property "Author" "Antmicro"
			(at 59.69 19.05 0)
			(effects
				(font
					(size 1.27 1.27)
					(thickness 0.15)
				)
				(justify left bottom)
				(hide yes)
			)
		)
		(property "Val" "22u"
			(at 34.925 38.735 90)
			(effects
				(font
					(size 1.27 1.27)
					(thickness 0.15)
				)
				(justify right)
			)
		)
		(property "Voltage" "25V"
			(at 34.925 41.275 90)
			(effects
				(font
					(size 1.27 1.27)
				)
				(justify right)
			)
		)
		(property "Dielectric" "X5R"
			(at 64.77 19.05 0)
			(effects
				(font
					(size 1.27 1.27)
				)
				(justify left bottom)
				(hide yes)
			)
		)
		(property "Public" "False"
			(at 67.31 19.05 0)
			(effects
				(font
					(size 1.27 1.27)
				)
				(justify left bottom)
				(hide yes)
			)
		)
		(pin "2"
		)
		(pin "1"
		)
		(instances
			(project "jetson-agx-thor-baseboard"
				(path ""
					(reference "C241")
					(unit 1)
				)
			)
		)
	)
	(symbol
		(lib_id "antmicroResistors0402:R_499k_0402")
		(at 55.88 105.41 90)
		(unit 1)
		(exclude_from_sim no)
		(in_bom no)
		(on_board yes)
		(dnp yes)
		(property "Reference" "R23"
			(at 57.15 101.6 90)
			(effects
				(font
					(size 1.27 1.27)
					(thickness 0.15)
				)
				(justify right)
			)
		)
		(property "Value" "R_499k_0402"
			(at 68.58 85.09 0)
			(effects
				(font
					(size 1.27 1.27)
					(thickness 0.15)
				)
				(justify left bottom)
				(hide yes)
			)
		)
		(property "Footprint" "antmicro-footprints:R_0402_1005Metric"
			(at 71.12 85.09 0)
			(effects
				(font
					(size 1.27 1.27)
					(thickness 0.15)
				)
				(justify left bottom)
				(hide yes)
			)
		)
		(property "Datasheet" "https://www.mouser.com/datasheet/2/54/cr-1858361.pdf"
			(at 73.66 85.09 0)
			(effects
				(font
					(size 1.27 1.27)
					(thickness 0.15)
				)
				(justify left bottom)
				(hide yes)
			)
		)
		(property "Description" "SMD Chip Resistor, 499 kohm, ± 1%, 63 mW, 0402 [1005 Metric], Thick Film, General Purpose"
			(at 55.88 105.41 0)
			(effects
				(font
					(size 1.27 1.27)
				)
				(hide yes)
			)
		)
		(property "MPN" "CR0402-FX-4993GLF"
			(at 76.2 85.09 0)
			(effects
				(font
					(size 1.27 1.27)
					(thickness 0.15)
				)
				(justify left bottom)
				(hide yes)
			)
		)
		(property "Manufacturer" "Bourns"
			(at 78.74 85.09 0)
			(effects
				(font
					(size 1.27 1.27)
					(thickness 0.15)
				)
				(justify left bottom)
				(hide yes)
			)
		)
		(property "License" "Apache-2.0"
			(at 81.28 85.09 0)
			(effects
				(font
					(size 1.27 1.27)
					(thickness 0.15)
				)
				(justify left bottom)
				(hide yes)
			)
		)
		(property "Author" "Antmicro"
			(at 83.82 85.09 0)
			(effects
				(font
					(size 1.27 1.27)
					(thickness 0.15)
				)
				(justify left bottom)
				(hide yes)
			)
		)
		(property "Val" "499k"
			(at 57.15 104.14 90)
			(effects
				(font
					(size 1.27 1.27)
					(thickness 0.15)
				)
				(justify right)
			)
		)
		(property "Tolerance" "1%"
			(at 66.04 85.09 0)
			(effects
				(font
					(size 1.27 1.27)
				)
				(justify left bottom)
				(hide yes)
			)
		)
		(pin "2"
		)
		(pin "1"
		)
		(instances
			(project "jetson-agx-thor-baseboard"
				(path ""
					(reference "R23")
					(unit 1)
				)
			)
		)
	)
	(symbol
		(lib_id "antmicropower:GND")
		(at 83.82 121.92 0)
		(unit 1)
		(exclude_from_sim no)
		(in_bom yes)
		(on_board yes)
		(dnp no)
		(property "Reference" "#PWR0550"
			(at 83.82 128.27 0)
			(effects
				(font
					(size 1.27 1.27)
				)
				(justify left bottom)
				(hide yes)
			)
		)
		(property "Value" "GND"
			(at 83.82 125.73 0)
			(effects
				(font
					(size 1.27 1.27)
					(thickness 0.15)
				)
			)
		)
		(property "Footprint" ""
			(at 92.71 129.54 0)
			(effects
				(font
					(size 1.27 1.27)
					(thickness 0.15)
				)
				(justify left bottom)
				(hide yes)
			)
		)
		(property "Datasheet" ""
			(at 92.71 134.62 0)
			(effects
				(font
					(size 1.27 1.27)
					(thickness 0.15)
				)
				(justify left bottom)
				(hide yes)
			)
		)
		(property "Description" ""
			(at 83.82 121.92 0)
			(effects
				(font
					(size 1.27 1.27)
				)
				(hide yes)
			)
		)
		(property "Author" "Antmicro"
			(at 92.71 129.54 0)
			(effects
				(font
					(size 1.27 1.27)
					(thickness 0.15)
				)
				(justify left bottom)
				(hide yes)
			)
		)
		(property "License" "Apache-2.0"
			(at 92.71 132.08 0)
			(effects
				(font
					(size 1.27 1.27)
					(thickness 0.15)
				)
				(justify left bottom)
				(hide yes)
			)
		)
		(pin "1"
		)
		(instances
			(project "jetson-agx-thor-baseboard"
				(path ""
					(reference "#PWR0550")
					(unit 1)
				)
			)
		)
	)
	(symbol
		(lib_id "antmicropower:GND")
		(at 185.42 59.69 0)
		(unit 1)
		(exclude_from_sim no)
		(in_bom yes)
		(on_board yes)
		(dnp no)
		(property "Reference" "#PWR0585"
			(at 185.42 66.04 0)
			(effects
				(font
					(size 1.27 1.27)
				)
				(justify left bottom)
				(hide yes)
			)
		)
		(property "Value" "GND"
			(at 185.42 63.5 0)
			(effects
				(font
					(size 1.27 1.27)
					(thickness 0.15)
				)
			)
		)
		(property "Footprint" ""
			(at 194.31 67.31 0)
			(effects
				(font
					(size 1.27 1.27)
					(thickness 0.15)
				)
				(justify left bottom)
				(hide yes)
			)
		)
		(property "Datasheet" ""
			(at 194.31 72.39 0)
			(effects
				(font
					(size 1.27 1.27)
					(thickness 0.15)
				)
				(justify left bottom)
				(hide yes)
			)
		)
		(property "Description" ""
			(at 185.42 59.69 0)
			(effects
				(font
					(size 1.27 1.27)
				)
				(hide yes)
			)
		)
		(property "Author" "Antmicro"
			(at 194.31 67.31 0)
			(effects
				(font
					(size 1.27 1.27)
					(thickness 0.15)
				)
				(justify left bottom)
				(hide yes)
			)
		)
		(property "License" "Apache-2.0"
			(at 194.31 69.85 0)
			(effects
				(font
					(size 1.27 1.27)
					(thickness 0.15)
				)
				(justify left bottom)
				(hide yes)
			)
		)
		(pin "1"
		)
		(instances
			(project "jetson-agx-thor-baseboard"
				(path ""
					(reference "#PWR0585")
					(unit 1)
				)
			)
		)
	)
	(symbol
		(lib_id "antmicroCapacitorsmisc:C_22u_25V_0805")
		(at 177.8 124.46 90)
		(unit 1)
		(exclude_from_sim no)
		(in_bom yes)
		(on_board yes)
		(dnp no)
		(property "Reference" "C296"
			(at 179.578 119.3801 90)
			(effects
				(font
					(size 1.27 1.27)
					(thickness 0.15)
				)
				(justify right)
			)
		)
		(property "Value" "C_22u_25V_0805"
			(at 187.96 104.14 0)
			(effects
				(font
					(size 1.27 1.27)
					(thickness 0.15)
				)
				(justify left bottom)
				(hide yes)
			)
		)
		(property "Footprint" "antmicro-footprints:C_0805_2012Metric"
			(at 190.5 104.14 0)
			(effects
				(font
					(size 1.27 1.27)
					(thickness 0.15)
				)
				(justify left bottom)
				(hide yes)
			)
		)
		(property "Datasheet" "https://product.samsungsem.com/mlcc/CL21A226MAYNNN.do"
			(at 193.04 104.14 0)
			(effects
				(font
					(size 1.27 1.27)
					(thickness 0.15)
				)
				(justify left bottom)
				(hide yes)
			)
		)
		(property "Description" "SMT Multilayer Ceramic Capacitor, 22uF, +/-20%, 25V, X5R, 0805 [2012 Metric]"
			(at 210.82 104.14 0)
			(effects
				(font
					(size 1.27 1.27)
				)
				(justify left bottom)
				(hide yes)
			)
		)
		(property "MPN" "CL21A226MAYNNNE"
			(at 195.58 104.14 0)
			(effects
				(font
					(size 1.27 1.27)
					(thickness 0.15)
				)
				(justify left bottom)
				(hide yes)
			)
		)
		(property "Manufacturer" "Samsung Electro-Mechanics"
			(at 198.12 104.14 0)
			(effects
				(font
					(size 1.27 1.27)
					(thickness 0.15)
				)
				(justify left bottom)
				(hide yes)
			)
		)
		(property "License" "Apache-2.0"
			(at 200.66 104.14 0)
			(effects
				(font
					(size 1.27 1.27)
					(thickness 0.15)
				)
				(justify left bottom)
				(hide yes)
			)
		)
		(property "Author" "Antmicro"
			(at 203.2 104.14 0)
			(effects
				(font
					(size 1.27 1.27)
					(thickness 0.15)
				)
				(justify left bottom)
				(hide yes)
			)
		)
		(property "Val" "22u"
			(at 179.578 121.9201 90)
			(effects
				(font
					(size 1.27 1.27)
					(thickness 0.15)
				)
				(justify right)
			)
		)
		(property "Voltage" "25V"
			(at 179.578 124.46 90)
			(effects
				(font
					(size 1.27 1.27)
				)
				(justify right)
			)
		)
		(property "Dielectric" "X5R"
			(at 208.28 104.14 0)
			(effects
				(font
					(size 1.27 1.27)
				)
				(justify left bottom)
				(hide yes)
			)
		)
		(property "Public" "False"
			(at 210.82 104.14 0)
			(effects
				(font
					(size 1.27 1.27)
				)
				(justify left bottom)
				(hide yes)
			)
		)
		(pin "2"
		)
		(pin "1"
		)
		(instances
			(project "jetson-agx-thor-baseboard"
				(path ""
					(reference "C296")
					(unit 1)
				)
			)
		)
	)
	(symbol
		(lib_id "antmicropower:GND")
		(at 34.29 232.41 0)
		(unit 1)
		(exclude_from_sim no)
		(in_bom yes)
		(on_board yes)
		(dnp no)
		(property "Reference" "#PWR093"
			(at 34.29 238.76 0)
			(effects
				(font
					(size 1.27 1.27)
				)
				(justify left bottom)
				(hide yes)
			)
		)
		(property "Value" "GND"
			(at 34.29 236.22 0)
			(effects
				(font
					(size 1.27 1.27)
					(thickness 0.15)
				)
			)
		)
		(property "Footprint" ""
			(at 43.18 240.03 0)
			(effects
				(font
					(size 1.27 1.27)
					(thickness 0.15)
				)
				(justify left bottom)
				(hide yes)
			)
		)
		(property "Datasheet" ""
			(at 43.18 245.11 0)
			(effects
				(font
					(size 1.27 1.27)
					(thickness 0.15)
				)
				(justify left bottom)
				(hide yes)
			)
		)
		(property "Description" ""
			(at 34.29 232.41 0)
			(effects
				(font
					(size 1.27 1.27)
				)
				(hide yes)
			)
		)
		(property "Author" "Antmicro"
			(at 43.18 240.03 0)
			(effects
				(font
					(size 1.27 1.27)
					(thickness 0.15)
				)
				(justify left bottom)
				(hide yes)
			)
		)
		(property "License" "Apache-2.0"
			(at 43.18 242.57 0)
			(effects
				(font
					(size 1.27 1.27)
					(thickness 0.15)
				)
				(justify left bottom)
				(hide yes)
			)
		)
		(pin "1"
		)
		(instances
			(project "jetson-agx-thor-baseboard"
				(path ""
					(reference "#PWR093")
					(unit 1)
				)
			)
		)
	)
	(symbol
		(lib_id "antmicroCapacitorsmisc:C_22u_25V_0805")
		(at 177.8 58.42 90)
		(unit 1)
		(exclude_from_sim no)
		(in_bom yes)
		(on_board yes)
		(dnp no)
		(property "Reference" "C260"
			(at 179.324 53.3401 90)
			(effects
				(font
					(size 1.27 1.27)
					(thickness 0.15)
				)
				(justify right)
			)
		)
		(property "Value" "C_22u_25V_0805"
			(at 187.96 38.1 0)
			(effects
				(font
					(size 1.27 1.27)
					(thickness 0.15)
				)
				(justify left bottom)
				(hide yes)
			)
		)
		(property "Footprint" "antmicro-footprints:C_0805_2012Metric"
			(at 190.5 38.1 0)
			(effects
				(font
					(size 1.27 1.27)
					(thickness 0.15)
				)
				(justify left bottom)
				(hide yes)
			)
		)
		(property "Datasheet" "https://product.samsungsem.com/mlcc/CL21A226MAYNNN.do"
			(at 193.04 38.1 0)
			(effects
				(font
					(size 1.27 1.27)
					(thickness 0.15)
				)
				(justify left bottom)
				(hide yes)
			)
		)
		(property "Description" "SMT Multilayer Ceramic Capacitor, 22uF, +/-20%, 25V, X5R, 0805 [2012 Metric]"
			(at 210.82 38.1 0)
			(effects
				(font
					(size 1.27 1.27)
				)
				(justify left bottom)
				(hide yes)
			)
		)
		(property "MPN" "CL21A226MAYNNNE"
			(at 195.58 38.1 0)
			(effects
				(font
					(size 1.27 1.27)
					(thickness 0.15)
				)
				(justify left bottom)
				(hide yes)
			)
		)
		(property "Manufacturer" "Samsung Electro-Mechanics"
			(at 198.12 38.1 0)
			(effects
				(font
					(size 1.27 1.27)
					(thickness 0.15)
				)
				(justify left bottom)
				(hide yes)
			)
		)
		(property "License" "Apache-2.0"
			(at 200.66 38.1 0)
			(effects
				(font
					(size 1.27 1.27)
					(thickness 0.15)
				)
				(justify left bottom)
				(hide yes)
			)
		)
		(property "Author" "Antmicro"
			(at 203.2 38.1 0)
			(effects
				(font
					(size 1.27 1.27)
					(thickness 0.15)
				)
				(justify left bottom)
				(hide yes)
			)
		)
		(property "Val" "22u"
			(at 179.324 55.8801 90)
			(effects
				(font
					(size 1.27 1.27)
					(thickness 0.15)
				)
				(justify right)
			)
		)
		(property "Voltage" "25V"
			(at 179.324 58.42 90)
			(effects
				(font
					(size 1.27 1.27)
				)
				(justify right)
			)
		)
		(property "Dielectric" "X5R"
			(at 208.28 38.1 0)
			(effects
				(font
					(size 1.27 1.27)
				)
				(justify left bottom)
				(hide yes)
			)
		)
		(property "Public" "False"
			(at 210.82 38.1 0)
			(effects
				(font
					(size 1.27 1.27)
				)
				(justify left bottom)
				(hide yes)
			)
		)
		(pin "2"
		)
		(pin "1"
		)
		(instances
			(project "jetson-agx-thor-baseboard"
				(path ""
					(reference "C260")
					(unit 1)
				)
			)
		)
	)
	(symbol
		(lib_id "antmicroCapacitorsmisc:C_22u_25V_0805")
		(at 185.42 124.46 90)
		(unit 1)
		(exclude_from_sim no)
		(in_bom yes)
		(on_board yes)
		(dnp no)
		(property "Reference" "C302"
			(at 187.198 119.3801 90)
			(effects
				(font
					(size 1.27 1.27)
					(thickness 0.15)
				)
				(justify right)
			)
		)
		(property "Value" "C_22u_25V_0805"
			(at 195.58 104.14 0)
			(effects
				(font
					(size 1.27 1.27)
					(thickness 0.15)
				)
				(justify left bottom)
				(hide yes)
			)
		)
		(property "Footprint" "antmicro-footprints:C_0805_2012Metric"
			(at 198.12 104.14 0)
			(effects
				(font
					(size 1.27 1.27)
					(thickness 0.15)
				)
				(justify left bottom)
				(hide yes)
			)
		)
		(property "Datasheet" "https://product.samsungsem.com/mlcc/CL21A226MAYNNN.do"
			(at 200.66 104.14 0)
			(effects
				(font
					(size 1.27 1.27)
					(thickness 0.15)
				)
				(justify left bottom)
				(hide yes)
			)
		)
		(property "Description" "SMT Multilayer Ceramic Capacitor, 22uF, +/-20%, 25V, X5R, 0805 [2012 Metric]"
			(at 218.44 104.14 0)
			(effects
				(font
					(size 1.27 1.27)
				)
				(justify left bottom)
				(hide yes)
			)
		)
		(property "MPN" "CL21A226MAYNNNE"
			(at 203.2 104.14 0)
			(effects
				(font
					(size 1.27 1.27)
					(thickness 0.15)
				)
				(justify left bottom)
				(hide yes)
			)
		)
		(property "Manufacturer" "Samsung Electro-Mechanics"
			(at 205.74 104.14 0)
			(effects
				(font
					(size 1.27 1.27)
					(thickness 0.15)
				)
				(justify left bottom)
				(hide yes)
			)
		)
		(property "License" "Apache-2.0"
			(at 208.28 104.14 0)
			(effects
				(font
					(size 1.27 1.27)
					(thickness 0.15)
				)
				(justify left bottom)
				(hide yes)
			)
		)
		(property "Author" "Antmicro"
			(at 210.82 104.14 0)
			(effects
				(font
					(size 1.27 1.27)
					(thickness 0.15)
				)
				(justify left bottom)
				(hide yes)
			)
		)
		(property "Val" "22u"
			(at 187.198 121.9201 90)
			(effects
				(font
					(size 1.27 1.27)
					(thickness 0.15)
				)
				(justify right)
			)
		)
		(property "Voltage" "25V"
			(at 187.198 124.46 90)
			(effects
				(font
					(size 1.27 1.27)
				)
				(justify right)
			)
		)
		(property "Dielectric" "X5R"
			(at 215.9 104.14 0)
			(effects
				(font
					(size 1.27 1.27)
				)
				(justify left bottom)
				(hide yes)
			)
		)
		(property "Public" "False"
			(at 218.44 104.14 0)
			(effects
				(font
					(size 1.27 1.27)
				)
				(justify left bottom)
				(hide yes)
			)
		)
		(pin "2"
		)
		(pin "1"
		)
		(instances
			(project "jetson-agx-thor-baseboard"
				(path ""
					(reference "C302")
					(unit 1)
				)
			)
		)
	)
	(symbol
		(lib_id "antmicroCapacitorsmisc:C_22u_25V_0805")
		(at 154.94 58.42 270)
		(mirror x)
		(unit 1)
		(exclude_from_sim no)
		(in_bom yes)
		(on_board yes)
		(dnp no)
		(property "Reference" "C257"
			(at 156.464 53.3401 90)
			(effects
				(font
					(size 1.27 1.27)
					(thickness 0.15)
				)
				(justify left)
			)
		)
		(property "Value" "C_22u_25V_0805"
			(at 144.78 38.1 0)
			(effects
				(font
					(size 1.27 1.27)
					(thickness 0.15)
				)
				(justify left bottom)
				(hide yes)
			)
		)
		(property "Footprint" "antmicro-footprints:C_0805_2012Metric"
			(at 142.24 38.1 0)
			(effects
				(font
					(size 1.27 1.27)
					(thickness 0.15)
				)
				(justify left bottom)
				(hide yes)
			)
		)
		(property "Datasheet" "https://product.samsungsem.com/mlcc/CL21A226MAYNNN.do"
			(at 139.7 38.1 0)
			(effects
				(font
					(size 1.27 1.27)
					(thickness 0.15)
				)
				(justify left bottom)
				(hide yes)
			)
		)
		(property "Description" "SMT Multilayer Ceramic Capacitor, 22uF, +/-20%, 25V, X5R, 0805 [2012 Metric]"
			(at 121.92 38.1 0)
			(effects
				(font
					(size 1.27 1.27)
				)
				(justify left bottom)
				(hide yes)
			)
		)
		(property "MPN" "CL21A226MAYNNNE"
			(at 137.16 38.1 0)
			(effects
				(font
					(size 1.27 1.27)
					(thickness 0.15)
				)
				(justify left bottom)
				(hide yes)
			)
		)
		(property "Manufacturer" "Samsung Electro-Mechanics"
			(at 134.62 38.1 0)
			(effects
				(font
					(size 1.27 1.27)
					(thickness 0.15)
				)
				(justify left bottom)
				(hide yes)
			)
		)
		(property "License" "Apache-2.0"
			(at 132.08 38.1 0)
			(effects
				(font
					(size 1.27 1.27)
					(thickness 0.15)
				)
				(justify left bottom)
				(hide yes)
			)
		)
		(property "Author" "Antmicro"
			(at 129.54 38.1 0)
			(effects
				(font
					(size 1.27 1.27)
					(thickness 0.15)
				)
				(justify left bottom)
				(hide yes)
			)
		)
		(property "Val" "22u"
			(at 156.464 55.8801 90)
			(effects
				(font
					(size 1.27 1.27)
					(thickness 0.15)
				)
				(justify left)
			)
		)
		(property "Voltage" "25V"
			(at 156.464 58.42 90)
			(effects
				(font
					(size 1.27 1.27)
				)
				(justify left)
			)
		)
		(property "Dielectric" "X5R"
			(at 124.46 38.1 0)
			(effects
				(font
					(size 1.27 1.27)
				)
				(justify left bottom)
				(hide yes)
			)
		)
		(property "Public" "False"
			(at 121.92 38.1 0)
			(effects
				(font
					(size 1.27 1.27)
				)
				(justify left bottom)
				(hide yes)
			)
		)
		(pin "2"
		)
		(pin "1"
		)
		(instances
			(project "jetson-agx-thor-baseboard"
				(path ""
					(reference "C257")
					(unit 1)
				)
			)
		)
	)
	(symbol
		(lib_id "antmicroResistors0402:R_100k_0402")
		(at 55.88 54.61 90)
		(unit 1)
		(exclude_from_sim no)
		(in_bom yes)
		(on_board yes)
		(dnp no)
		(fields_autoplaced yes)
		(property "Reference" "R20"
			(at 58.42 50.8 90)
			(effects
				(font
					(size 1.27 1.27)
					(thickness 0.15)
				)
				(justify right)
			)
		)
		(property "Value" "R_100k_0402"
			(at 68.58 34.29 0)
			(effects
				(font
					(size 1.27 1.27)
					(thickness 0.15)
				)
				(justify left bottom)
				(hide yes)
			)
		)
		(property "Footprint" "antmicro-footprints:R_0402_1005Metric"
			(at 71.12 34.29 0)
			(effects
				(font
					(size 1.27 1.27)
					(thickness 0.15)
				)
				(justify left bottom)
				(hide yes)
			)
		)
		(property "Datasheet" "https://www.bourns.com/docs/product-datasheets/cr.pdf"
			(at 73.66 34.29 0)
			(effects
				(font
					(size 1.27 1.27)
					(thickness 0.15)
				)
				(justify left bottom)
				(hide yes)
			)
		)
		(property "Description" "SMD Chip Resistor, 100 kohm, ± 1%, 62.5 mW, 0402 [1005 Metric], Thick Film, General Purpose"
			(at 86.36 34.29 0)
			(effects
				(font
					(size 1.27 1.27)
				)
				(justify left bottom)
				(hide yes)
			)
		)
		(property "MPN" "CR0402-FX-1003GLF"
			(at 76.2 34.29 0)
			(effects
				(font
					(size 1.27 1.27)
					(thickness 0.15)
				)
				(justify left bottom)
				(hide yes)
			)
		)
		(property "Manufacturer" "Bourns"
			(at 78.74 34.29 0)
			(effects
				(font
					(size 1.27 1.27)
					(thickness 0.15)
				)
				(justify left bottom)
				(hide yes)
			)
		)
		(property "License" "Apache-2.0"
			(at 81.28 34.29 0)
			(effects
				(font
					(size 1.27 1.27)
					(thickness 0.15)
				)
				(justify left bottom)
				(hide yes)
			)
		)
		(property "Author" "Antmicro"
			(at 83.82 34.29 0)
			(effects
				(font
					(size 1.27 1.27)
					(thickness 0.15)
				)
				(justify left bottom)
				(hide yes)
			)
		)
		(property "Val" "100k"
			(at 58.42 53.34 90)
			(effects
				(font
					(size 1.27 1.27)
					(thickness 0.15)
				)
				(justify right)
			)
		)
		(property "Tolerance" "1%"
			(at 66.04 34.29 0)
			(effects
				(font
					(size 1.27 1.27)
				)
				(justify left bottom)
				(hide yes)
			)
		)
		(pin "2"
		)
		(pin "1"
		)
		(instances
			(project "jetson-agx-thor-baseboard"
				(path ""
					(reference "R20")
					(unit 1)
				)
			)
		)
	)
	(symbol
		(lib_id "antmicroResistors0402:R_15k_0402")
		(at 336.55 130.81 90)
		(unit 1)
		(exclude_from_sim no)
		(in_bom yes)
		(on_board yes)
		(dnp no)
		(fields_autoplaced yes)
		(property "Reference" "R318"
			(at 339.09 127 90)
			(effects
				(font
					(size 1.27 1.27)
					(thickness 0.15)
				)
				(justify right)
			)
		)
		(property "Value" "R_15k_0402"
			(at 349.25 110.49 0)
			(effects
				(font
					(size 1.27 1.27)
					(thickness 0.15)
				)
				(justify left bottom)
				(hide yes)
			)
		)
		(property "Footprint" "antmicro-footprints:R_0402_1005Metric"
			(at 351.79 110.49 0)
			(effects
				(font
					(size 1.27 1.27)
					(thickness 0.15)
				)
				(justify left bottom)
				(hide yes)
			)
		)
		(property "Datasheet" "https://www.bourns.com/docs/product-datasheets/cr.pdf"
			(at 354.33 110.49 0)
			(effects
				(font
					(size 1.27 1.27)
					(thickness 0.15)
				)
				(justify left bottom)
				(hide yes)
			)
		)
		(property "Description" "SMD Chip Resistor, 15 kohm, ± 1%, 62.5 mW, 0402 [1005 Metric], Thick Film, General Purpose"
			(at 336.55 130.81 0)
			(effects
				(font
					(size 1.27 1.27)
				)
				(hide yes)
			)
		)
		(property "MPN" "CR0402-FX-1502GLF"
			(at 356.87 110.49 0)
			(effects
				(font
					(size 1.27 1.27)
					(thickness 0.15)
				)
				(justify left bottom)
				(hide yes)
			)
		)
		(property "Manufacturer" "Bourns"
			(at 359.41 110.49 0)
			(effects
				(font
					(size 1.27 1.27)
					(thickness 0.15)
				)
				(justify left bottom)
				(hide yes)
			)
		)
		(property "License" "Apache-2.0"
			(at 361.95 110.49 0)
			(effects
				(font
					(size 1.27 1.27)
					(thickness 0.15)
				)
				(justify left bottom)
				(hide yes)
			)
		)
		(property "Author" "Antmicro"
			(at 364.49 110.49 0)
			(effects
				(font
					(size 1.27 1.27)
					(thickness 0.15)
				)
				(justify left bottom)
				(hide yes)
			)
		)
		(property "Val" "15k"
			(at 339.09 129.54 90)
			(effects
				(font
					(size 1.27 1.27)
					(thickness 0.15)
				)
				(justify right)
			)
		)
		(property "Tolerance" "1%"
			(at 346.71 110.49 0)
			(effects
				(font
					(size 1.27 1.27)
				)
				(justify left bottom)
				(hide yes)
			)
		)
		(pin "1"
		)
		(pin "2"
		)
		(instances
			(project "jetson-agx-thor-baseboard"
				(path ""
					(reference "R318")
					(unit 1)
				)
			)
		)
	)
	(symbol
		(lib_id "antmicroCapacitors0402:C_100n_0402")
		(at 48.26 266.7 270)
		(unit 1)
		(exclude_from_sim no)
		(in_bom yes)
		(on_board yes)
		(dnp no)
		(property "Reference" "C49"
			(at 48.895 267.335 90)
			(effects
				(font
					(size 1.27 1.27)
				)
				(justify left)
			)
		)
		(property "Value" "C_100n_0402"
			(at 38.1 287.02 0)
			(effects
				(font
					(size 1.27 1.27)
					(thickness 0.15)
				)
				(justify left bottom)
				(hide yes)
			)
		)
		(property "Footprint" "antmicro-footprints:C_0402_1005Metric"
			(at 35.56 287.02 0)
			(effects
				(font
					(size 1.27 1.27)
					(thickness 0.15)
				)
				(justify left bottom)
				(hide yes)
			)
		)
		(property "Datasheet" "https://www.murata.com/products/productdetail?partno=GRM155R61H104KE14%23"
			(at 33.02 287.02 0)
			(effects
				(font
					(size 1.27 1.27)
					(thickness 0.15)
				)
				(justify left bottom)
				(hide yes)
			)
		)
		(property "Description" "SMD Multilayer Ceramic Capacitor, 0.1 µF, 50 V, 0402 [1005 Metric], ± 10%, X5R, GRM Series"
			(at 48.26 266.7 0)
			(effects
				(font
					(size 1.27 1.27)
				)
				(hide yes)
			)
		)
		(property "Manufacturer" "Murata"
			(at 27.94 287.02 0)
			(effects
				(font
					(size 1.27 1.27)
					(thickness 0.15)
				)
				(justify left bottom)
				(hide yes)
			)
		)
		(property "MPN" "GRM155R61H104KE14D"
			(at 30.48 287.02 0)
			(effects
				(font
					(size 1.27 1.27)
					(thickness 0.15)
				)
				(justify left bottom)
				(hide yes)
			)
		)
		(property "Val" "100n"
			(at 48.895 271.145 90)
			(effects
				(font
					(size 1.27 1.27)
					(thickness 0.15)
				)
				(justify left)
			)
		)
		(property "License" "Apache-2.0"
			(at 25.4 287.02 0)
			(effects
				(font
					(size 1.27 1.27)
					(thickness 0.15)
				)
				(justify left bottom)
				(hide yes)
			)
		)
		(property "Author" "Antmicro"
			(at 22.86 287.02 0)
			(effects
				(font
					(size 1.27 1.27)
					(thickness 0.15)
				)
				(justify left bottom)
				(hide yes)
			)
		)
		(property "Voltage" "50V"
			(at 20.32 287.02 0)
			(effects
				(font
					(size 1.27 1.27)
				)
				(justify left bottom)
				(hide yes)
			)
		)
		(property "Dielectric" "X5R"
			(at 17.78 287.02 0)
			(effects
				(font
					(size 1.27 1.27)
				)
				(justify left bottom)
				(hide yes)
			)
		)
		(pin "1"
		)
		(pin "2"
		)
		(instances
			(project "jetson-agx-thor-baseboard"
				(path ""
					(reference "C49")
					(unit 1)
				)
			)
		)
	)
	(symbol
		(lib_id "antmicroCapacitorsmisc:C_22u_25V_0805")
		(at 24.13 165.1 90)
		(unit 1)
		(exclude_from_sim no)
		(in_bom yes)
		(on_board yes)
		(dnp no)
		(property "Reference" "C370"
			(at 24.765 160.655 90)
			(effects
				(font
					(size 1.27 1.27)
					(thickness 0.15)
				)
				(justify right)
			)
		)
		(property "Value" "C_22u_25V_0805"
			(at 34.29 144.78 0)
			(effects
				(font
					(size 1.27 1.27)
					(thickness 0.15)
				)
				(justify left bottom)
				(hide yes)
			)
		)
		(property "Footprint" "antmicro-footprints:C_0805_2012Metric"
			(at 36.83 144.78 0)
			(effects
				(font
					(size 1.27 1.27)
					(thickness 0.15)
				)
				(justify left bottom)
				(hide yes)
			)
		)
		(property "Datasheet" "https://product.samsungsem.com/mlcc/CL21A226MAYNNN.do"
			(at 39.37 144.78 0)
			(effects
				(font
					(size 1.27 1.27)
					(thickness 0.15)
				)
				(justify left bottom)
				(hide yes)
			)
		)
		(property "Description" "SMT Multilayer Ceramic Capacitor, 22uF, +/-20%, 25V, X5R, 0805 [2012 Metric]"
			(at 24.13 165.1 0)
			(effects
				(font
					(size 1.27 1.27)
				)
				(hide yes)
			)
		)
		(property "MPN" "CL21A226MAYNNNE"
			(at 41.91 144.78 0)
			(effects
				(font
					(size 1.27 1.27)
					(thickness 0.15)
				)
				(justify left bottom)
				(hide yes)
			)
		)
		(property "Manufacturer" "Samsung Electro-Mechanics"
			(at 44.45 144.78 0)
			(effects
				(font
					(size 1.27 1.27)
					(thickness 0.15)
				)
				(justify left bottom)
				(hide yes)
			)
		)
		(property "License" "Apache-2.0"
			(at 46.99 144.78 0)
			(effects
				(font
					(size 1.27 1.27)
					(thickness 0.15)
				)
				(justify left bottom)
				(hide yes)
			)
		)
		(property "Author" "Antmicro"
			(at 49.53 144.78 0)
			(effects
				(font
					(size 1.27 1.27)
					(thickness 0.15)
				)
				(justify left bottom)
				(hide yes)
			)
		)
		(property "Val" "22u"
			(at 24.765 164.465 90)
			(effects
				(font
					(size 1.27 1.27)
					(thickness 0.15)
				)
				(justify right)
			)
		)
		(property "Voltage" "25V"
			(at 24.765 167.005 90)
			(effects
				(font
					(size 1.27 1.27)
				)
				(justify right)
			)
		)
		(property "Dielectric" "X5R"
			(at 54.61 144.78 0)
			(effects
				(font
					(size 1.27 1.27)
				)
				(justify left bottom)
				(hide yes)
			)
		)
		(property "Public" "False"
			(at 57.15 144.78 0)
			(effects
				(font
					(size 1.27 1.27)
				)
				(justify left bottom)
				(hide yes)
			)
		)
		(pin "2"
		)
		(pin "1"
		)
		(instances
			(project "jetson-agx-thor-baseboard"
				(path ""
					(reference "C370")
					(unit 1)
				)
			)
		)
	)
	(symbol
		(lib_id "antmicroCapacitors0603:C_22u_16V_0603")
		(at 275.59 190.5 90)
		(unit 1)
		(exclude_from_sim no)
		(in_bom yes)
		(on_board yes)
		(dnp no)
		(property "Reference" "C76"
			(at 278.13 185.4135 90)
			(effects
				(font
					(size 1.27 1.27)
					(thickness 0.15)
				)
				(justify right)
			)
		)
		(property "Value" "C_22u_16V_0603"
			(at 285.75 170.18 0)
			(effects
				(font
					(size 1.27 1.27)
					(thickness 0.15)
				)
				(justify left bottom)
				(hide yes)
			)
		)
		(property "Footprint" "antmicro-footprints:C_0603_1608Metric_EIA"
			(at 288.29 170.18 0)
			(effects
				(font
					(size 1.27 1.27)
					(thickness 0.15)
				)
				(justify left bottom)
				(hide yes)
			)
		)
		(property "Datasheet" "https://product.samsungsem.com/mlcc/CL10A226MO7JZN.do"
			(at 290.83 170.18 0)
			(effects
				(font
					(size 1.27 1.27)
					(thickness 0.15)
				)
				(justify left bottom)
				(hide yes)
			)
		)
		(property "Description" "SMD Multilayer Ceramic Capacitor"
			(at 275.59 190.5 0)
			(effects
				(font
					(size 1.27 1.27)
				)
				(hide yes)
			)
		)
		(property "MPN" "CL10A226MO7JZNC"
			(at 293.37 170.18 0)
			(effects
				(font
					(size 1.27 1.27)
					(thickness 0.15)
				)
				(justify left bottom)
				(hide yes)
			)
		)
		(property "Manufacturer" "Samsung Electro-Mechanics"
			(at 295.91 170.18 0)
			(effects
				(font
					(size 1.27 1.27)
					(thickness 0.15)
				)
				(justify left bottom)
				(hide yes)
			)
		)
		(property "License" "Apache-2.0"
			(at 298.45 170.18 0)
			(effects
				(font
					(size 1.27 1.27)
					(thickness 0.15)
				)
				(justify left bottom)
				(hide yes)
			)
		)
		(property "Author" "Antmicro"
			(at 300.99 170.18 0)
			(effects
				(font
					(size 1.27 1.27)
					(thickness 0.15)
				)
				(justify left bottom)
				(hide yes)
			)
		)
		(property "Val" "22u"
			(at 278.13 187.9535 90)
			(effects
				(font
					(size 1.27 1.27)
					(thickness 0.15)
				)
				(justify right)
			)
		)
		(property "Voltage" "16V"
			(at 278.13 190.4935 90)
			(effects
				(font
					(size 1.27 1.27)
				)
				(justify right)
				(hide yes)
			)
		)
		(property "Dielectric" ""
			(at 306.07 170.18 0)
			(effects
				(font
					(size 1.27 1.27)
				)
				(justify left bottom)
				(hide yes)
			)
		)
		(property "Public" "False"
			(at 308.61 170.18 0)
			(effects
				(font
					(size 1.27 1.27)
				)
				(justify left bottom)
				(hide yes)
			)
		)
		(pin "2"
		)
		(pin "1"
		)
		(instances
			(project "jetson-agx-thor-baseboard"
				(path ""
					(reference "C76")
					(unit 1)
				)
			)
		)
	)
	(symbol
		(lib_id "antmicroCapacitorsmisc:C_22u_25V_0805")
		(at 177.8 43.18 90)
		(unit 1)
		(exclude_from_sim no)
		(in_bom yes)
		(on_board yes)
		(dnp no)
		(property "Reference" "C250"
			(at 179.324 38.1001 90)
			(effects
				(font
					(size 1.27 1.27)
					(thickness 0.15)
				)
				(justify right)
			)
		)
		(property "Value" "C_22u_25V_0805"
			(at 187.96 22.86 0)
			(effects
				(font
					(size 1.27 1.27)
					(thickness 0.15)
				)
				(justify left bottom)
				(hide yes)
			)
		)
		(property "Footprint" "antmicro-footprints:C_0805_2012Metric"
			(at 190.5 22.86 0)
			(effects
				(font
					(size 1.27 1.27)
					(thickness 0.15)
				)
				(justify left bottom)
				(hide yes)
			)
		)
		(property "Datasheet" "https://product.samsungsem.com/mlcc/CL21A226MAYNNN.do"
			(at 193.04 22.86 0)
			(effects
				(font
					(size 1.27 1.27)
					(thickness 0.15)
				)
				(justify left bottom)
				(hide yes)
			)
		)
		(property "Description" "SMT Multilayer Ceramic Capacitor, 22uF, +/-20%, 25V, X5R, 0805 [2012 Metric]"
			(at 210.82 22.86 0)
			(effects
				(font
					(size 1.27 1.27)
				)
				(justify left bottom)
				(hide yes)
			)
		)
		(property "MPN" "CL21A226MAYNNNE"
			(at 195.58 22.86 0)
			(effects
				(font
					(size 1.27 1.27)
					(thickness 0.15)
				)
				(justify left bottom)
				(hide yes)
			)
		)
		(property "Manufacturer" "Samsung Electro-Mechanics"
			(at 198.12 22.86 0)
			(effects
				(font
					(size 1.27 1.27)
					(thickness 0.15)
				)
				(justify left bottom)
				(hide yes)
			)
		)
		(property "License" "Apache-2.0"
			(at 200.66 22.86 0)
			(effects
				(font
					(size 1.27 1.27)
					(thickness 0.15)
				)
				(justify left bottom)
				(hide yes)
			)
		)
		(property "Author" "Antmicro"
			(at 203.2 22.86 0)
			(effects
				(font
					(size 1.27 1.27)
					(thickness 0.15)
				)
				(justify left bottom)
				(hide yes)
			)
		)
		(property "Val" "22u"
			(at 179.324 40.6401 90)
			(effects
				(font
					(size 1.27 1.27)
					(thickness 0.15)
				)
				(justify right)
			)
		)
		(property "Voltage" "25V"
			(at 179.324 43.18 90)
			(effects
				(font
					(size 1.27 1.27)
				)
				(justify right)
			)
		)
		(property "Dielectric" "X5R"
			(at 208.28 22.86 0)
			(effects
				(font
					(size 1.27 1.27)
				)
				(justify left bottom)
				(hide yes)
			)
		)
		(property "Public" "False"
			(at 210.82 22.86 0)
			(effects
				(font
					(size 1.27 1.27)
				)
				(justify left bottom)
				(hide yes)
			)
		)
		(pin "2"
		)
		(pin "1"
		)
		(instances
			(project "jetson-agx-thor-baseboard"
				(path ""
					(reference "C250")
					(unit 1)
				)
			)
		)
	)
	(symbol
		(lib_id "antmicroCapacitorsmisc:C_22u_25V_0805")
		(at 154.94 139.7 270)
		(mirror x)
		(unit 1)
		(exclude_from_sim no)
		(in_bom yes)
		(on_board yes)
		(dnp no)
		(property "Reference" "C285"
			(at 156.718 134.6201 90)
			(effects
				(font
					(size 1.27 1.27)
					(thickness 0.15)
				)
				(justify left)
			)
		)
		(property "Value" "C_22u_25V_0805"
			(at 144.78 119.38 0)
			(effects
				(font
					(size 1.27 1.27)
					(thickness 0.15)
				)
				(justify left bottom)
				(hide yes)
			)
		)
		(property "Footprint" "antmicro-footprints:C_0805_2012Metric"
			(at 142.24 119.38 0)
			(effects
				(font
					(size 1.27 1.27)
					(thickness 0.15)
				)
				(justify left bottom)
				(hide yes)
			)
		)
		(property "Datasheet" "https://product.samsungsem.com/mlcc/CL21A226MAYNNN.do"
			(at 139.7 119.38 0)
			(effects
				(font
					(size 1.27 1.27)
					(thickness 0.15)
				)
				(justify left bottom)
				(hide yes)
			)
		)
		(property "Description" "SMT Multilayer Ceramic Capacitor, 22uF, +/-20%, 25V, X5R, 0805 [2012 Metric]"
			(at 121.92 119.38 0)
			(effects
				(font
					(size 1.27 1.27)
				)
				(justify left bottom)
				(hide yes)
			)
		)
		(property "MPN" "CL21A226MAYNNNE"
			(at 137.16 119.38 0)
			(effects
				(font
					(size 1.27 1.27)
					(thickness 0.15)
				)
				(justify left bottom)
				(hide yes)
			)
		)
		(property "Manufacturer" "Samsung Electro-Mechanics"
			(at 134.62 119.38 0)
			(effects
				(font
					(size 1.27 1.27)
					(thickness 0.15)
				)
				(justify left bottom)
				(hide yes)
			)
		)
		(property "License" "Apache-2.0"
			(at 132.08 119.38 0)
			(effects
				(font
					(size 1.27 1.27)
					(thickness 0.15)
				)
				(justify left bottom)
				(hide yes)
			)
		)
		(property "Author" "Antmicro"
			(at 129.54 119.38 0)
			(effects
				(font
					(size 1.27 1.27)
					(thickness 0.15)
				)
				(justify left bottom)
				(hide yes)
			)
		)
		(property "Val" "22u"
			(at 156.718 137.1601 90)
			(effects
				(font
					(size 1.27 1.27)
					(thickness 0.15)
				)
				(justify left)
			)
		)
		(property "Voltage" "25V"
			(at 156.718 139.7 90)
			(effects
				(font
					(size 1.27 1.27)
				)
				(justify left)
			)
		)
		(property "Dielectric" "X5R"
			(at 124.46 119.38 0)
			(effects
				(font
					(size 1.27 1.27)
				)
				(justify left bottom)
				(hide yes)
			)
		)
		(property "Public" "False"
			(at 121.92 119.38 0)
			(effects
				(font
					(size 1.27 1.27)
				)
				(justify left bottom)
				(hide yes)
			)
		)
		(pin "2"
		)
		(pin "1"
		)
		(instances
			(project "jetson-agx-thor-baseboard"
				(path ""
					(reference "C285")
					(unit 1)
				)
			)
		)
	)
	(symbol
		(lib_id "antmicropower:GND")
		(at 365.76 196.85 0)
		(unit 1)
		(exclude_from_sim no)
		(in_bom yes)
		(on_board yes)
		(dnp no)
		(property "Reference" "#PWR060"
			(at 374.65 199.39 0)
			(effects
				(font
					(size 1.27 1.27)
					(thickness 0.15)
				)
				(justify left bottom)
				(hide yes)
			)
		)
		(property "Value" "GND"
			(at 365.76 200.66 0)
			(effects
				(font
					(size 1.27 1.27)
					(thickness 0.15)
				)
			)
		)
		(property "Footprint" ""
			(at 374.65 204.47 0)
			(effects
				(font
					(size 1.27 1.27)
					(thickness 0.15)
				)
				(justify left bottom)
				(hide yes)
			)
		)
		(property "Datasheet" ""
			(at 374.65 209.55 0)
			(effects
				(font
					(size 1.27 1.27)
					(thickness 0.15)
				)
				(justify left bottom)
				(hide yes)
			)
		)
		(property "Description" ""
			(at 365.76 196.85 0)
			(effects
				(font
					(size 1.27 1.27)
				)
				(hide yes)
			)
		)
		(property "Author" "Antmicro"
			(at 374.65 204.47 0)
			(effects
				(font
					(size 1.27 1.27)
					(thickness 0.15)
				)
				(justify left bottom)
				(hide yes)
			)
		)
		(property "License" "Apache-2.0"
			(at 374.65 207.01 0)
			(effects
				(font
					(size 1.27 1.27)
					(thickness 0.15)
				)
				(justify left bottom)
				(hide yes)
			)
		)
		(pin "1"
		)
		(instances
			(project "jetson-agx-thor-baseboard"
				(path ""
					(reference "#PWR060")
					(unit 1)
				)
			)
		)
	)
	(symbol
		(lib_id "antmicropower:+3V3_AON")
		(at 222.25 179.07 0)
		(unit 1)
		(exclude_from_sim no)
		(in_bom yes)
		(on_board yes)
		(dnp no)
		(fields_autoplaced yes)
		(property "Reference" "#PWR0658"
			(at 222.25 182.88 0)
			(effects
				(font
					(size 1.27 1.27)
				)
				(hide yes)
			)
		)
		(property "Value" "+3V3_AON"
			(at 222.25 173.99 0)
			(effects
				(font
					(size 1.27 1.27)
				)
			)
		)
		(property "Footprint" ""
			(at 222.25 179.07 0)
			(effects
				(font
					(size 1.27 1.27)
				)
				(hide yes)
			)
		)
		(property "Datasheet" ""
			(at 222.25 179.07 0)
			(effects
				(font
					(size 1.27 1.27)
				)
				(hide yes)
			)
		)
		(property "Description" ""
			(at 222.25 179.07 0)
			(effects
				(font
					(size 1.27 1.27)
				)
				(hide yes)
			)
		)
		(pin "1"
		)
		(instances
			(project "jetson-agx-thor-baseboard"
				(path ""
					(reference "#PWR0658")
					(unit 1)
				)
			)
		)
	)
	(symbol
		(lib_id "antmicropower:GND")
		(at 55.88 232.41 0)
		(unit 1)
		(exclude_from_sim no)
		(in_bom yes)
		(on_board yes)
		(dnp no)
		(property "Reference" "#PWR0102"
			(at 55.88 238.76 0)
			(effects
				(font
					(size 1.27 1.27)
				)
				(justify left bottom)
				(hide yes)
			)
		)
		(property "Value" "GND"
			(at 55.88 236.22 0)
			(effects
				(font
					(size 1.27 1.27)
					(thickness 0.15)
				)
			)
		)
		(property "Footprint" ""
			(at 64.77 240.03 0)
			(effects
				(font
					(size 1.27 1.27)
					(thickness 0.15)
				)
				(justify left bottom)
				(hide yes)
			)
		)
		(property "Datasheet" ""
			(at 64.77 245.11 0)
			(effects
				(font
					(size 1.27 1.27)
					(thickness 0.15)
				)
				(justify left bottom)
				(hide yes)
			)
		)
		(property "Description" ""
			(at 55.88 232.41 0)
			(effects
				(font
					(size 1.27 1.27)
				)
				(hide yes)
			)
		)
		(property "Author" "Antmicro"
			(at 64.77 240.03 0)
			(effects
				(font
					(size 1.27 1.27)
					(thickness 0.15)
				)
				(justify left bottom)
				(hide yes)
			)
		)
		(property "License" "Apache-2.0"
			(at 64.77 242.57 0)
			(effects
				(font
					(size 1.27 1.27)
					(thickness 0.15)
				)
				(justify left bottom)
				(hide yes)
			)
		)
		(pin "1"
		)
		(instances
			(project "jetson-agx-thor-baseboard"
				(path ""
					(reference "#PWR0102")
					(unit 1)
				)
			)
		)
	)
	(symbol
		(lib_id "antmicropower:GND")
		(at 27.94 107.95 0)
		(unit 1)
		(exclude_from_sim no)
		(in_bom yes)
		(on_board yes)
		(dnp no)
		(property "Reference" "#PWR0603"
			(at 27.94 114.3 0)
			(effects
				(font
					(size 1.27 1.27)
				)
				(justify left bottom)
				(hide yes)
			)
		)
		(property "Value" "GND"
			(at 27.94 111.76 0)
			(effects
				(font
					(size 1.27 1.27)
					(thickness 0.15)
				)
			)
		)
		(property "Footprint" ""
			(at 36.83 115.57 0)
			(effects
				(font
					(size 1.27 1.27)
					(thickness 0.15)
				)
				(justify left bottom)
				(hide yes)
			)
		)
		(property "Datasheet" ""
			(at 36.83 120.65 0)
			(effects
				(font
					(size 1.27 1.27)
					(thickness 0.15)
				)
				(justify left bottom)
				(hide yes)
			)
		)
		(property "Description" ""
			(at 27.94 107.95 0)
			(effects
				(font
					(size 1.27 1.27)
				)
				(hide yes)
			)
		)
		(property "Author" "Antmicro"
			(at 36.83 115.57 0)
			(effects
				(font
					(size 1.27 1.27)
					(thickness 0.15)
				)
				(justify left bottom)
				(hide yes)
			)
		)
		(property "License" "Apache-2.0"
			(at 36.83 118.11 0)
			(effects
				(font
					(size 1.27 1.27)
					(thickness 0.15)
				)
				(justify left bottom)
				(hide yes)
			)
		)
		(pin "1"
		)
		(instances
			(project "jetson-agx-thor-baseboard"
				(path ""
					(reference "#PWR0603")
					(unit 1)
				)
			)
		)
	)
	(symbol
		(lib_id "antmicroResistorsmisc:R_0R001_0805")
		(at 209.55 35.56 0)
		(unit 1)
		(exclude_from_sim no)
		(in_bom yes)
		(on_board yes)
		(dnp no)
		(property "Reference" "R65"
			(at 212.09 30.48 0)
			(effects
				(font
					(size 1.27 1.27)
					(thickness 0.15)
				)
			)
		)
		(property "Value" "R_0R001_0805"
			(at 229.87 48.26 0)
			(effects
				(font
					(size 1.27 1.27)
					(thickness 0.15)
				)
				(justify left bottom)
				(hide yes)
			)
		)
		(property "Footprint" "antmicro-footprints:R_0805_2012Metric"
			(at 229.87 50.8 0)
			(effects
				(font
					(size 1.27 1.27)
					(thickness 0.15)
				)
				(justify left bottom)
				(hide yes)
			)
		)
		(property "Datasheet" "https://www.eaton.com/content/dam/eaton/products/electronic-components/resources/data-sheet/eaton-msma-automotive-smd-current-sense-resistor-metal-strip-data-sheet-elx1179.pdf"
			(at 229.87 53.34 0)
			(effects
				(font
					(size 1.27 1.27)
					(thickness 0.15)
				)
				(justify left bottom)
				(hide yes)
			)
		)
		(property "Description" "Current Sense Resistors - SMD MSMA, 0805 SIZE, 1/2 Watt, 1 mohm, 50 TCR MnCu Metal AEC-Q"
			(at 209.55 35.56 0)
			(effects
				(font
					(size 1.27 1.27)
				)
				(hide yes)
			)
		)
		(property "MPN" "MSMA0805R0010FSM"
			(at 229.87 55.88 0)
			(effects
				(font
					(size 1.27 1.27)
					(thickness 0.15)
				)
				(justify left bottom)
				(hide yes)
			)
		)
		(property "Manufacturer" "Eaton"
			(at 229.87 58.42 0)
			(effects
				(font
					(size 1.27 1.27)
					(thickness 0.15)
				)
				(justify left bottom)
				(hide yes)
			)
		)
		(property "License" "Apache-2.0"
			(at 229.87 60.96 0)
			(effects
				(font
					(size 1.27 1.27)
					(thickness 0.15)
				)
				(justify left bottom)
				(hide yes)
			)
		)
		(property "Author" "Antmicro"
			(at 229.87 63.5 0)
			(effects
				(font
					(size 1.27 1.27)
					(thickness 0.15)
				)
				(justify left bottom)
				(hide yes)
			)
		)
		(property "Val" "0R001"
			(at 212.09 33.02 0)
			(effects
				(font
					(size 1.27 1.27)
					(thickness 0.15)
				)
			)
		)
		(property "Tolerance" "1%"
			(at 229.87 45.72 0)
			(effects
				(font
					(size 1.27 1.27)
				)
				(justify left bottom)
				(hide yes)
			)
		)
		(property "Public" "False"
			(at 229.87 66.04 0)
			(effects
				(font
					(size 1.27 1.27)
				)
				(justify left bottom)
				(hide yes)
			)
		)
		(pin "2"
		)
		(pin "1"
		)
		(instances
			(project "jetson-agx-thor-baseboard"
				(path ""
					(reference "R65")
					(unit 1)
				)
			)
		)
	)
	(symbol
		(lib_id "antmicropower:+3V3_AON")
		(at 198.12 63.5 0)
		(unit 1)
		(exclude_from_sim no)
		(in_bom yes)
		(on_board yes)
		(dnp no)
		(property "Reference" "#PWR0144"
			(at 198.12 67.31 0)
			(effects
				(font
					(size 1.27 1.27)
				)
				(hide yes)
			)
		)
		(property "Value" "+3V3_AON"
			(at 198.12 59.69 0)
			(effects
				(font
					(size 1.27 1.27)
				)
			)
		)
		(property "Footprint" ""
			(at 198.12 63.5 0)
			(effects
				(font
					(size 1.27 1.27)
				)
				(hide yes)
			)
		)
		(property "Datasheet" ""
			(at 198.12 63.5 0)
			(effects
				(font
					(size 1.27 1.27)
				)
				(hide yes)
			)
		)
		(property "Description" ""
			(at 198.12 63.5 0)
			(effects
				(font
					(size 1.27 1.27)
				)
				(hide yes)
			)
		)
		(pin "1"
		)
		(instances
			(project "jetson-agx-thor-baseboard"
				(path ""
					(reference "#PWR0144")
					(unit 1)
				)
			)
		)
	)
	(symbol
		(lib_id "antmicropower:GND")
		(at 299.72 194.31 0)
		(unit 1)
		(exclude_from_sim no)
		(in_bom yes)
		(on_board yes)
		(dnp no)
		(property "Reference" "#PWR053"
			(at 308.61 196.85 0)
			(effects
				(font
					(size 1.27 1.27)
					(thickness 0.15)
				)
				(justify left bottom)
				(hide yes)
			)
		)
		(property "Value" "GND"
			(at 299.72 198.12 0)
			(effects
				(font
					(size 1.27 1.27)
					(thickness 0.15)
				)
			)
		)
		(property "Footprint" ""
			(at 308.61 201.93 0)
			(effects
				(font
					(size 1.27 1.27)
					(thickness 0.15)
				)
				(justify left bottom)
				(hide yes)
			)
		)
		(property "Datasheet" ""
			(at 308.61 207.01 0)
			(effects
				(font
					(size 1.27 1.27)
					(thickness 0.15)
				)
				(justify left bottom)
				(hide yes)
			)
		)
		(property "Description" ""
			(at 299.72 194.31 0)
			(effects
				(font
					(size 1.27 1.27)
				)
				(hide yes)
			)
		)
		(property "Author" "Antmicro"
			(at 308.61 201.93 0)
			(effects
				(font
					(size 1.27 1.27)
					(thickness 0.15)
				)
				(justify left bottom)
				(hide yes)
			)
		)
		(property "License" "Apache-2.0"
			(at 308.61 204.47 0)
			(effects
				(font
					(size 1.27 1.27)
					(thickness 0.15)
				)
				(justify left bottom)
				(hide yes)
			)
		)
		(pin "1"
		)
		(instances
			(project "jetson-agx-thor-baseboard"
				(path ""
					(reference "#PWR053")
					(unit 1)
				)
			)
		)
	)
	(symbol
		(lib_id "antmicropower:+3V3_AON")
		(at 193.04 232.41 0)
		(unit 1)
		(exclude_from_sim no)
		(in_bom yes)
		(on_board yes)
		(dnp no)
		(property "Reference" "#PWR0530"
			(at 193.04 236.22 0)
			(effects
				(font
					(size 1.27 1.27)
				)
				(hide yes)
			)
		)
		(property "Value" "+3V3_AON"
			(at 191.77 228.6 0)
			(effects
				(font
					(size 1.27 1.27)
				)
			)
		)
		(property "Footprint" ""
			(at 193.04 232.41 0)
			(effects
				(font
					(size 1.27 1.27)
				)
				(hide yes)
			)
		)
		(property "Datasheet" ""
			(at 193.04 232.41 0)
			(effects
				(font
					(size 1.27 1.27)
				)
				(hide yes)
			)
		)
		(property "Description" ""
			(at 193.04 232.41 0)
			(effects
				(font
					(size 1.27 1.27)
				)
				(hide yes)
			)
		)
		(pin "1"
		)
		(instances
			(project "jetson-agx-thor-baseboard"
				(path ""
					(reference "#PWR0530")
					(unit 1)
				)
			)
		)
	)
	(symbol
		(lib_id "antmicroCapacitorsmisc:C_22u_25V_0805")
		(at 383.54 62.23 90)
		(unit 1)
		(exclude_from_sim no)
		(in_bom yes)
		(on_board yes)
		(dnp no)
		(property "Reference" "C307"
			(at 386.08 57.1435 90)
			(effects
				(font
					(size 1.27 1.27)
				)
				(justify right)
			)
		)
		(property "Value" "C_22u_25V_0805"
			(at 393.7 41.91 0)
			(effects
				(font
					(size 1.27 1.27)
					(thickness 0.15)
				)
				(justify left bottom)
				(hide yes)
			)
		)
		(property "Footprint" "antmicro-footprints:C_0805_2012Metric"
			(at 396.24 41.91 0)
			(effects
				(font
					(size 1.27 1.27)
					(thickness 0.15)
				)
				(justify left bottom)
				(hide yes)
			)
		)
		(property "Datasheet" "https://product.samsungsem.com/mlcc/CL21A226MAYNNN.do"
			(at 398.78 41.91 0)
			(effects
				(font
					(size 1.27 1.27)
					(thickness 0.15)
				)
				(justify left bottom)
				(hide yes)
			)
		)
		(property "Description" "SMT Multilayer Ceramic Capacitor, 22uF, +/-20%, 25V, X5R, 0805 [2012 Metric]"
			(at 383.54 62.23 0)
			(effects
				(font
					(size 1.27 1.27)
				)
				(hide yes)
			)
		)
		(property "Manufacturer" "Samsung Electro-Mechanics"
			(at 403.86 41.91 0)
			(effects
				(font
					(size 1.27 1.27)
					(thickness 0.15)
				)
				(justify left bottom)
				(hide yes)
			)
		)
		(property "MPN" "CL21A226MAYNNNE"
			(at 401.32 41.91 0)
			(effects
				(font
					(size 1.27 1.27)
					(thickness 0.15)
				)
				(justify left bottom)
				(hide yes)
			)
		)
		(property "Val" "22u"
			(at 386.08 59.6836 90)
			(effects
				(font
					(size 1.27 1.27)
					(thickness 0.15)
				)
				(justify right)
			)
		)
		(property "License" "Apache-2.0"
			(at 406.4 41.91 0)
			(effects
				(font
					(size 1.27 1.27)
					(thickness 0.15)
				)
				(justify left bottom)
				(hide yes)
			)
		)
		(property "Author" "Antmicro"
			(at 408.94 41.91 0)
			(effects
				(font
					(size 1.27 1.27)
					(thickness 0.15)
				)
				(justify left bottom)
				(hide yes)
			)
		)
		(property "Voltage" "25V"
			(at 386.08 62.2235 90)
			(effects
				(font
					(size 1.27 1.27)
				)
				(justify right)
			)
		)
		(property "Dielectric" "X5R"
			(at 414.02 41.91 0)
			(effects
				(font
					(size 1.27 1.27)
				)
				(justify left bottom)
				(hide yes)
			)
		)
		(property "Public" "False"
			(at 416.56 41.91 0)
			(effects
				(font
					(size 1.27 1.27)
				)
				(justify left bottom)
				(hide yes)
			)
		)
		(pin "1"
		)
		(pin "2"
		)
		(instances
			(project "jetson-agx-thor-baseboard"
				(path ""
					(reference "C307")
					(unit 1)
				)
			)
		)
	)
	(symbol
		(lib_id "antmicropower:GND")
		(at 215.9 234.95 0)
		(unit 1)
		(exclude_from_sim no)
		(in_bom yes)
		(on_board yes)
		(dnp no)
		(property "Reference" "#PWR0526"
			(at 224.79 237.49 0)
			(effects
				(font
					(size 1.27 1.27)
					(thickness 0.15)
				)
				(justify left bottom)
				(hide yes)
			)
		)
		(property "Value" "GND"
			(at 219.71 236.728 0)
			(effects
				(font
					(size 1.27 1.27)
					(thickness 0.15)
				)
			)
		)
		(property "Footprint" ""
			(at 224.79 242.57 0)
			(effects
				(font
					(size 1.27 1.27)
					(thickness 0.15)
				)
				(justify left bottom)
				(hide yes)
			)
		)
		(property "Datasheet" ""
			(at 224.79 247.65 0)
			(effects
				(font
					(size 1.27 1.27)
					(thickness 0.15)
				)
				(justify left bottom)
				(hide yes)
			)
		)
		(property "Description" ""
			(at 215.9 234.95 0)
			(effects
				(font
					(size 1.27 1.27)
				)
				(hide yes)
			)
		)
		(property "Author" "Antmicro"
			(at 224.79 242.57 0)
			(effects
				(font
					(size 1.27 1.27)
					(thickness 0.15)
				)
				(justify left bottom)
				(hide yes)
			)
		)
		(property "License" "Apache-2.0"
			(at 224.79 245.11 0)
			(effects
				(font
					(size 1.27 1.27)
					(thickness 0.15)
				)
				(justify left bottom)
				(hide yes)
			)
		)
		(pin "1"
		)
		(instances
			(project "jetson-agx-thor-baseboard"
				(path ""
					(reference "#PWR0526")
					(unit 1)
				)
			)
		)
	)
	(symbol
		(lib_id "antmicropower:GND")
		(at 83.82 55.88 0)
		(unit 1)
		(exclude_from_sim no)
		(in_bom yes)
		(on_board yes)
		(dnp no)
		(property "Reference" "#PWR0531"
			(at 83.82 62.23 0)
			(effects
				(font
					(size 1.27 1.27)
				)
				(justify left bottom)
				(hide yes)
			)
		)
		(property "Value" "GND"
			(at 83.82 59.69 0)
			(effects
				(font
					(size 1.27 1.27)
					(thickness 0.15)
				)
			)
		)
		(property "Footprint" ""
			(at 92.71 63.5 0)
			(effects
				(font
					(size 1.27 1.27)
					(thickness 0.15)
				)
				(justify left bottom)
				(hide yes)
			)
		)
		(property "Datasheet" ""
			(at 92.71 68.58 0)
			(effects
				(font
					(size 1.27 1.27)
					(thickness 0.15)
				)
				(justify left bottom)
				(hide yes)
			)
		)
		(property "Description" ""
			(at 83.82 55.88 0)
			(effects
				(font
					(size 1.27 1.27)
				)
				(hide yes)
			)
		)
		(property "Author" "Antmicro"
			(at 92.71 63.5 0)
			(effects
				(font
					(size 1.27 1.27)
					(thickness 0.15)
				)
				(justify left bottom)
				(hide yes)
			)
		)
		(property "License" "Apache-2.0"
			(at 92.71 66.04 0)
			(effects
				(font
					(size 1.27 1.27)
					(thickness 0.15)
				)
				(justify left bottom)
				(hide yes)
			)
		)
		(pin "1"
		)
		(instances
			(project "jetson-agx-thor-baseboard"
				(path ""
					(reference "#PWR0531")
					(unit 1)
				)
			)
		)
	)
	(symbol
		(lib_id "antmicropower:GND")
		(at 83.82 279.4 0)
		(unit 1)
		(exclude_from_sim no)
		(in_bom yes)
		(on_board yes)
		(dnp no)
		(property "Reference" "#PWR0114"
			(at 83.82 285.75 0)
			(effects
				(font
					(size 1.27 1.27)
				)
				(justify left bottom)
				(hide yes)
			)
		)
		(property "Value" "GND"
			(at 83.82 283.21 0)
			(effects
				(font
					(size 1.27 1.27)
					(thickness 0.15)
				)
			)
		)
		(property "Footprint" ""
			(at 92.71 287.02 0)
			(effects
				(font
					(size 1.27 1.27)
					(thickness 0.15)
				)
				(justify left bottom)
				(hide yes)
			)
		)
		(property "Datasheet" ""
			(at 92.71 292.1 0)
			(effects
				(font
					(size 1.27 1.27)
					(thickness 0.15)
				)
				(justify left bottom)
				(hide yes)
			)
		)
		(property "Description" ""
			(at 83.82 279.4 0)
			(effects
				(font
					(size 1.27 1.27)
				)
				(hide yes)
			)
		)
		(property "Author" "Antmicro"
			(at 92.71 287.02 0)
			(effects
				(font
					(size 1.27 1.27)
					(thickness 0.15)
				)
				(justify left bottom)
				(hide yes)
			)
		)
		(property "License" "Apache-2.0"
			(at 92.71 289.56 0)
			(effects
				(font
					(size 1.27 1.27)
					(thickness 0.15)
				)
				(justify left bottom)
				(hide yes)
			)
		)
		(pin "1"
		)
		(instances
			(project "jetson-agx-thor-baseboard"
				(path ""
					(reference "#PWR0114")
					(unit 1)
				)
			)
		)
	)
	(symbol
		(lib_id "antmicroCapacitors0402:C_4u7_25V_0402")
		(at 83.82 231.14 90)
		(unit 1)
		(exclude_from_sim no)
		(in_bom yes)
		(on_board yes)
		(dnp no)
		(property "Reference" "C55"
			(at 84.455 226.695 90)
			(effects
				(font
					(size 1.27 1.27)
					(thickness 0.15)
				)
				(justify right)
			)
		)
		(property "Value" "C_4u7_25V_0402"
			(at 93.98 210.82 0)
			(effects
				(font
					(size 1.27 1.27)
					(thickness 0.15)
				)
				(justify left bottom)
				(hide yes)
			)
		)
		(property "Footprint" "antmicro-footprints:C_0402_1005Metric"
			(at 96.52 210.82 0)
			(effects
				(font
					(size 1.27 1.27)
					(thickness 0.15)
				)
				(justify left bottom)
				(hide yes)
			)
		)
		(property "Datasheet" "https://www.murata.com/products/productdetail?partno=GRM155C61E475ME15%23"
			(at 99.06 210.82 0)
			(effects
				(font
					(size 1.27 1.27)
					(thickness 0.15)
				)
				(justify left bottom)
				(hide yes)
			)
		)
		(property "Description" "SMD Multilayer Ceramic Capacitor"
			(at 83.82 231.14 0)
			(effects
				(font
					(size 1.27 1.27)
				)
				(hide yes)
			)
		)
		(property "MPN" "GRM155C61E475ME15J"
			(at 101.6 210.82 0)
			(effects
				(font
					(size 1.27 1.27)
					(thickness 0.15)
				)
				(justify left bottom)
				(hide yes)
			)
		)
		(property "Manufacturer" "Murata"
			(at 104.14 210.82 0)
			(effects
				(font
					(size 1.27 1.27)
					(thickness 0.15)
				)
				(justify left bottom)
				(hide yes)
			)
		)
		(property "License" "Apache-2.0"
			(at 106.68 210.82 0)
			(effects
				(font
					(size 1.27 1.27)
					(thickness 0.15)
				)
				(justify left bottom)
				(hide yes)
			)
		)
		(property "Author" "Antmicro"
			(at 109.22 210.82 0)
			(effects
				(font
					(size 1.27 1.27)
					(thickness 0.15)
				)
				(justify left bottom)
				(hide yes)
			)
		)
		(property "Val" "4u7"
			(at 84.455 230.505 90)
			(effects
				(font
					(size 1.27 1.27)
					(thickness 0.15)
				)
				(justify right)
			)
		)
		(property "Voltage" "25V"
			(at 111.76 210.82 0)
			(effects
				(font
					(size 1.27 1.27)
				)
				(justify left bottom)
				(hide yes)
			)
		)
		(property "Dielectric" "X5S"
			(at 114.3 210.82 0)
			(effects
				(font
					(size 1.27 1.27)
				)
				(justify left bottom)
				(hide yes)
			)
		)
		(pin "2"
		)
		(pin "1"
		)
		(instances
			(project "jetson-agx-thor-baseboard"
				(path ""
					(reference "C55")
					(unit 1)
				)
			)
		)
	)
	(symbol
		(lib_id "antmicropower:GND")
		(at 271.78 58.42 0)
		(unit 1)
		(exclude_from_sim no)
		(in_bom yes)
		(on_board yes)
		(dnp no)
		(property "Reference" "#PWR051"
			(at 271.78 64.77 0)
			(effects
				(font
					(size 1.27 1.27)
				)
				(justify left bottom)
				(hide yes)
			)
		)
		(property "Value" "GND"
			(at 271.78 62.23 0)
			(effects
				(font
					(size 1.27 1.27)
					(thickness 0.15)
				)
			)
		)
		(property "Footprint" ""
			(at 280.67 66.04 0)
			(effects
				(font
					(size 1.27 1.27)
					(thickness 0.15)
				)
				(justify left bottom)
				(hide yes)
			)
		)
		(property "Datasheet" ""
			(at 280.67 71.12 0)
			(effects
				(font
					(size 1.27 1.27)
					(thickness 0.15)
				)
				(justify left bottom)
				(hide yes)
			)
		)
		(property "Description" ""
			(at 271.78 58.42 0)
			(effects
				(font
					(size 1.27 1.27)
				)
				(hide yes)
			)
		)
		(property "Author" "Antmicro"
			(at 280.67 66.04 0)
			(effects
				(font
					(size 1.27 1.27)
					(thickness 0.15)
				)
				(justify left bottom)
				(hide yes)
			)
		)
		(property "License" "Apache-2.0"
			(at 280.67 68.58 0)
			(effects
				(font
					(size 1.27 1.27)
					(thickness 0.15)
				)
				(justify left bottom)
				(hide yes)
			)
		)
		(pin "1"
		)
		(instances
			(project "jetson-agx-thor-baseboard"
				(path ""
					(reference "#PWR051")
					(unit 1)
				)
			)
		)
	)
	(symbol
		(lib_id "antmicroCapacitorsmisc:C_22u_25V_0805")
		(at 40.64 271.78 90)
		(unit 1)
		(exclude_from_sim no)
		(in_bom yes)
		(on_board yes)
		(dnp no)
		(property "Reference" "C46"
			(at 41.275 267.335 90)
			(effects
				(font
					(size 1.27 1.27)
					(thickness 0.15)
				)
				(justify right)
			)
		)
		(property "Value" "C_22u_25V_0805"
			(at 50.8 251.46 0)
			(effects
				(font
					(size 1.27 1.27)
					(thickness 0.15)
				)
				(justify left bottom)
				(hide yes)
			)
		)
		(property "Footprint" "antmicro-footprints:C_0805_2012Metric"
			(at 53.34 251.46 0)
			(effects
				(font
					(size 1.27 1.27)
					(thickness 0.15)
				)
				(justify left bottom)
				(hide yes)
			)
		)
		(property "Datasheet" "https://product.samsungsem.com/mlcc/CL21A226MAYNNN.do"
			(at 55.88 251.46 0)
			(effects
				(font
					(size 1.27 1.27)
					(thickness 0.15)
				)
				(justify left bottom)
				(hide yes)
			)
		)
		(property "Description" "SMT Multilayer Ceramic Capacitor, 22uF, +/-20%, 25V, X5R, 0805 [2012 Metric]"
			(at 40.64 271.78 0)
			(effects
				(font
					(size 1.27 1.27)
				)
				(hide yes)
			)
		)
		(property "MPN" "CL21A226MAYNNNE"
			(at 58.42 251.46 0)
			(effects
				(font
					(size 1.27 1.27)
					(thickness 0.15)
				)
				(justify left bottom)
				(hide yes)
			)
		)
		(property "Manufacturer" "Samsung Electro-Mechanics"
			(at 60.96 251.46 0)
			(effects
				(font
					(size 1.27 1.27)
					(thickness 0.15)
				)
				(justify left bottom)
				(hide yes)
			)
		)
		(property "License" "Apache-2.0"
			(at 63.5 251.46 0)
			(effects
				(font
					(size 1.27 1.27)
					(thickness 0.15)
				)
				(justify left bottom)
				(hide yes)
			)
		)
		(property "Author" "Antmicro"
			(at 66.04 251.46 0)
			(effects
				(font
					(size 1.27 1.27)
					(thickness 0.15)
				)
				(justify left bottom)
				(hide yes)
			)
		)
		(property "Val" "22u"
			(at 41.275 271.145 90)
			(effects
				(font
					(size 1.27 1.27)
					(thickness 0.15)
				)
				(justify right)
			)
		)
		(property "Voltage" "25V"
			(at 41.275 273.05 90)
			(effects
				(font
					(size 1.27 1.27)
				)
				(justify right)
			)
		)
		(property "Dielectric" "X5R"
			(at 71.12 251.46 0)
			(effects
				(font
					(size 1.27 1.27)
				)
				(justify left bottom)
				(hide yes)
			)
		)
		(property "Public" "False"
			(at 73.66 251.46 0)
			(effects
				(font
					(size 1.27 1.27)
				)
				(justify left bottom)
				(hide yes)
			)
		)
		(pin "1"
		)
		(pin "2"
		)
		(instances
			(project "jetson-agx-thor-baseboard"
				(path ""
					(reference "C46")
					(unit 1)
				)
			)
		)
	)
	(symbol
		(lib_id "antmicropower:GND")
		(at 115.57 185.42 0)
		(unit 1)
		(exclude_from_sim no)
		(in_bom yes)
		(on_board yes)
		(dnp no)
		(property "Reference" "#PWR0759"
			(at 115.57 191.77 0)
			(effects
				(font
					(size 1.27 1.27)
				)
				(justify left bottom)
				(hide yes)
			)
		)
		(property "Value" "GND"
			(at 115.57 189.23 0)
			(effects
				(font
					(size 1.27 1.27)
					(thickness 0.15)
				)
			)
		)
		(property "Footprint" ""
			(at 124.46 193.04 0)
			(effects
				(font
					(size 1.27 1.27)
					(thickness 0.15)
				)
				(justify left bottom)
				(hide yes)
			)
		)
		(property "Datasheet" ""
			(at 124.46 198.12 0)
			(effects
				(font
					(size 1.27 1.27)
					(thickness 0.15)
				)
				(justify left bottom)
				(hide yes)
			)
		)
		(property "Description" ""
			(at 115.57 185.42 0)
			(effects
				(font
					(size 1.27 1.27)
				)
				(hide yes)
			)
		)
		(property "Author" "Antmicro"
			(at 124.46 193.04 0)
			(effects
				(font
					(size 1.27 1.27)
					(thickness 0.15)
				)
				(justify left bottom)
				(hide yes)
			)
		)
		(property "License" "Apache-2.0"
			(at 124.46 195.58 0)
			(effects
				(font
					(size 1.27 1.27)
					(thickness 0.15)
				)
				(justify left bottom)
				(hide yes)
			)
		)
		(pin "1"
		)
		(instances
			(project "jetson-agx-thor-baseboard"
				(path ""
					(reference "#PWR0759")
					(unit 1)
				)
			)
		)
	)
	(symbol
		(lib_id "antmicropower:GND")
		(at 383.54 63.5 0)
		(mirror y)
		(unit 1)
		(exclude_from_sim no)
		(in_bom yes)
		(on_board yes)
		(dnp no)
		(property "Reference" "#PWR0616"
			(at 383.54 69.85 0)
			(effects
				(font
					(size 1.27 1.27)
				)
				(justify left bottom)
				(hide yes)
			)
		)
		(property "Value" "GND"
			(at 383.54 67.31 0)
			(effects
				(font
					(size 1.27 1.27)
					(thickness 0.15)
				)
			)
		)
		(property "Footprint" ""
			(at 374.65 71.12 0)
			(effects
				(font
					(size 1.27 1.27)
					(thickness 0.15)
				)
				(justify left bottom)
				(hide yes)
			)
		)
		(property "Datasheet" ""
			(at 374.65 76.2 0)
			(effects
				(font
					(size 1.27 1.27)
					(thickness 0.15)
				)
				(justify left bottom)
				(hide yes)
			)
		)
		(property "Description" ""
			(at 383.54 63.5 0)
			(effects
				(font
					(size 1.27 1.27)
				)
				(hide yes)
			)
		)
		(property "Author" "Antmicro"
			(at 374.65 71.12 0)
			(effects
				(font
					(size 1.27 1.27)
					(thickness 0.15)
				)
				(justify left bottom)
				(hide yes)
			)
		)
		(property "License" "Apache-2.0"
			(at 374.65 73.66 0)
			(effects
				(font
					(size 1.27 1.27)
					(thickness 0.15)
				)
				(justify left bottom)
				(hide yes)
			)
		)
		(pin "1"
		)
		(instances
			(project "jetson-agx-thor-baseboard"
				(path ""
					(reference "#PWR0616")
					(unit 1)
				)
			)
		)
	)
	(symbol
		(lib_id "antmicroCapacitors0402:C_100n_0402")
		(at 215.9 231.14 90)
		(unit 1)
		(exclude_from_sim no)
		(in_bom yes)
		(on_board yes)
		(dnp no)
		(property "Reference" "C197"
			(at 218.44 227.3235 90)
			(effects
				(font
					(size 1.27 1.27)
					(thickness 0.15)
				)
				(justify right)
			)
		)
		(property "Value" "C_100n_0402"
			(at 226.06 210.82 0)
			(effects
				(font
					(size 1.27 1.27)
					(thickness 0.15)
				)
				(justify left bottom)
				(hide yes)
			)
		)
		(property "Footprint" "antmicro-footprints:C_0402_1005Metric"
			(at 228.6 210.82 0)
			(effects
				(font
					(size 1.27 1.27)
					(thickness 0.15)
				)
				(justify left bottom)
				(hide yes)
			)
		)
		(property "Datasheet" "https://www.murata.com/products/productdetail?partno=GRM155R61H104KE14%23"
			(at 231.14 210.82 0)
			(effects
				(font
					(size 1.27 1.27)
					(thickness 0.15)
				)
				(justify left bottom)
				(hide yes)
			)
		)
		(property "Description" "SMD Multilayer Ceramic Capacitor, 0.1 µF, 50 V, 0402 [1005 Metric], ± 10%, X5R, GRM Series"
			(at 215.9 231.14 0)
			(effects
				(font
					(size 1.27 1.27)
				)
				(hide yes)
			)
		)
		(property "MPN" "GRM155R61H104KE14D"
			(at 233.68 210.82 0)
			(effects
				(font
					(size 1.27 1.27)
					(thickness 0.15)
				)
				(justify left bottom)
				(hide yes)
			)
		)
		(property "Manufacturer" "Murata"
			(at 236.22 210.82 0)
			(effects
				(font
					(size 1.27 1.27)
					(thickness 0.15)
				)
				(justify left bottom)
				(hide yes)
			)
		)
		(property "License" "Apache-2.0"
			(at 238.76 210.82 0)
			(effects
				(font
					(size 1.27 1.27)
					(thickness 0.15)
				)
				(justify left bottom)
				(hide yes)
			)
		)
		(property "Author" "Antmicro"
			(at 241.3 210.82 0)
			(effects
				(font
					(size 1.27 1.27)
					(thickness 0.15)
				)
				(justify left bottom)
				(hide yes)
			)
		)
		(property "Val" "100n"
			(at 218.44 229.8635 90)
			(effects
				(font
					(size 1.27 1.27)
					(thickness 0.15)
				)
				(justify right)
			)
		)
		(property "Voltage" "50V"
			(at 243.84 210.82 0)
			(effects
				(font
					(size 1.27 1.27)
				)
				(justify left bottom)
				(hide yes)
			)
		)
		(property "Dielectric" "X5R"
			(at 246.38 210.82 0)
			(effects
				(font
					(size 1.27 1.27)
				)
				(justify left bottom)
				(hide yes)
			)
		)
		(property "Public" "False"
			(at 248.92 210.82 0)
			(effects
				(font
					(size 1.27 1.27)
				)
				(justify left bottom)
				(hide yes)
			)
		)
		(pin "1"
		)
		(pin "2"
		)
		(instances
			(project "jetson-agx-thor-baseboard"
				(path ""
					(reference "C197")
					(unit 1)
				)
			)
		)
	)
	(symbol
		(lib_id "antmicroCapacitorsmisc:C_22u_25V_0805")
		(at 162.56 139.7 90)
		(unit 1)
		(exclude_from_sim no)
		(in_bom yes)
		(on_board yes)
		(dnp no)
		(property "Reference" "C289"
			(at 164.338 134.6201 90)
			(effects
				(font
					(size 1.27 1.27)
					(thickness 0.15)
				)
				(justify right)
			)
		)
		(property "Value" "C_22u_25V_0805"
			(at 172.72 119.38 0)
			(effects
				(font
					(size 1.27 1.27)
					(thickness 0.15)
				)
				(justify left bottom)
				(hide yes)
			)
		)
		(property "Footprint" "antmicro-footprints:C_0805_2012Metric"
			(at 175.26 119.38 0)
			(effects
				(font
					(size 1.27 1.27)
					(thickness 0.15)
				)
				(justify left bottom)
				(hide yes)
			)
		)
		(property "Datasheet" "https://product.samsungsem.com/mlcc/CL21A226MAYNNN.do"
			(at 177.8 119.38 0)
			(effects
				(font
					(size 1.27 1.27)
					(thickness 0.15)
				)
				(justify left bottom)
				(hide yes)
			)
		)
		(property "Description" "SMT Multilayer Ceramic Capacitor, 22uF, +/-20%, 25V, X5R, 0805 [2012 Metric]"
			(at 195.58 119.38 0)
			(effects
				(font
					(size 1.27 1.27)
				)
				(justify left bottom)
				(hide yes)
			)
		)
		(property "MPN" "CL21A226MAYNNNE"
			(at 180.34 119.38 0)
			(effects
				(font
					(size 1.27 1.27)
					(thickness 0.15)
				)
				(justify left bottom)
				(hide yes)
			)
		)
		(property "Manufacturer" "Samsung Electro-Mechanics"
			(at 182.88 119.38 0)
			(effects
				(font
					(size 1.27 1.27)
					(thickness 0.15)
				)
				(justify left bottom)
				(hide yes)
			)
		)
		(property "License" "Apache-2.0"
			(at 185.42 119.38 0)
			(effects
				(font
					(size 1.27 1.27)
					(thickness 0.15)
				)
				(justify left bottom)
				(hide yes)
			)
		)
		(property "Author" "Antmicro"
			(at 187.96 119.38 0)
			(effects
				(font
					(size 1.27 1.27)
					(thickness 0.15)
				)
				(justify left bottom)
				(hide yes)
			)
		)
		(property "Val" "22u"
			(at 164.338 137.1601 90)
			(effects
				(font
					(size 1.27 1.27)
					(thickness 0.15)
				)
				(justify right)
			)
		)
		(property "Voltage" "25V"
			(at 164.338 139.7 90)
			(effects
				(font
					(size 1.27 1.27)
				)
				(justify right)
			)
		)
		(property "Dielectric" "X5R"
			(at 193.04 119.38 0)
			(effects
				(font
					(size 1.27 1.27)
				)
				(justify left bottom)
				(hide yes)
			)
		)
		(property "Public" "False"
			(at 195.58 119.38 0)
			(effects
				(font
					(size 1.27 1.27)
				)
				(justify left bottom)
				(hide yes)
			)
		)
		(pin "2"
		)
		(pin "1"
		)
		(instances
			(project "jetson-agx-thor-baseboard"
				(path ""
					(reference "C289")
					(unit 1)
				)
			)
		)
	)
	(symbol
		(lib_id "antmicropower:+3V3_AON")
		(at 222.25 270.51 0)
		(unit 1)
		(exclude_from_sim no)
		(in_bom yes)
		(on_board yes)
		(dnp no)
		(fields_autoplaced yes)
		(property "Reference" "#PWR0529"
			(at 222.25 274.32 0)
			(effects
				(font
					(size 1.27 1.27)
				)
				(hide yes)
			)
		)
		(property "Value" "+3V3_AON"
			(at 222.25 265.43 0)
			(effects
				(font
					(size 1.27 1.27)
				)
			)
		)
		(property "Footprint" ""
			(at 222.25 270.51 0)
			(effects
				(font
					(size 1.27 1.27)
				)
				(hide yes)
			)
		)
		(property "Datasheet" ""
			(at 222.25 270.51 0)
			(effects
				(font
					(size 1.27 1.27)
				)
				(hide yes)
			)
		)
		(property "Description" ""
			(at 222.25 270.51 0)
			(effects
				(font
					(size 1.27 1.27)
				)
				(hide yes)
			)
		)
		(pin "1"
		)
		(instances
			(project "jetson-agx-thor-baseboard"
				(path ""
					(reference "#PWR0529")
					(unit 1)
				)
			)
		)
	)
	(symbol
		(lib_id "antmicropower:GND")
		(at 24.13 167.64 0)
		(unit 1)
		(exclude_from_sim no)
		(in_bom yes)
		(on_board yes)
		(dnp no)
		(property "Reference" "#PWR0746"
			(at 24.13 173.99 0)
			(effects
				(font
					(size 1.27 1.27)
				)
				(justify left bottom)
				(hide yes)
			)
		)
		(property "Value" "GND"
			(at 24.13 171.45 0)
			(effects
				(font
					(size 1.27 1.27)
					(thickness 0.15)
				)
			)
		)
		(property "Footprint" ""
			(at 33.02 175.26 0)
			(effects
				(font
					(size 1.27 1.27)
					(thickness 0.15)
				)
				(justify left bottom)
				(hide yes)
			)
		)
		(property "Datasheet" ""
			(at 33.02 180.34 0)
			(effects
				(font
					(size 1.27 1.27)
					(thickness 0.15)
				)
				(justify left bottom)
				(hide yes)
			)
		)
		(property "Description" ""
			(at 24.13 167.64 0)
			(effects
				(font
					(size 1.27 1.27)
				)
				(hide yes)
			)
		)
		(property "Author" "Antmicro"
			(at 33.02 175.26 0)
			(effects
				(font
					(size 1.27 1.27)
					(thickness 0.15)
				)
				(justify left bottom)
				(hide yes)
			)
		)
		(property "License" "Apache-2.0"
			(at 33.02 177.8 0)
			(effects
				(font
					(size 1.27 1.27)
					(thickness 0.15)
				)
				(justify left bottom)
				(hide yes)
			)
		)
		(pin "1"
		)
		(instances
			(project "jetson-agx-thor-baseboard"
				(path ""
					(reference "#PWR0746")
					(unit 1)
				)
			)
		)
	)
	(symbol
		(lib_id "antmicroCapacitorsmisc:C_22u_25V_0805")
		(at 162.56 73.66 90)
		(unit 1)
		(exclude_from_sim no)
		(in_bom yes)
		(on_board yes)
		(dnp no)
		(property "Reference" "C286"
			(at 164.084 68.5801 90)
			(effects
				(font
					(size 1.27 1.27)
					(thickness 0.15)
				)
				(justify right)
			)
		)
		(property "Value" "C_22u_25V_0805"
			(at 172.72 53.34 0)
			(effects
				(font
					(size 1.27 1.27)
					(thickness 0.15)
				)
				(justify left bottom)
				(hide yes)
			)
		)
		(property "Footprint" "antmicro-footprints:C_0805_2012Metric"
			(at 175.26 53.34 0)
			(effects
				(font
					(size 1.27 1.27)
					(thickness 0.15)
				)
				(justify left bottom)
				(hide yes)
			)
		)
		(property "Datasheet" "https://product.samsungsem.com/mlcc/CL21A226MAYNNN.do"
			(at 177.8 53.34 0)
			(effects
				(font
					(size 1.27 1.27)
					(thickness 0.15)
				)
				(justify left bottom)
				(hide yes)
			)
		)
		(property "Description" "SMT Multilayer Ceramic Capacitor, 22uF, +/-20%, 25V, X5R, 0805 [2012 Metric]"
			(at 195.58 53.34 0)
			(effects
				(font
					(size 1.27 1.27)
				)
				(justify left bottom)
				(hide yes)
			)
		)
		(property "MPN" "CL21A226MAYNNNE"
			(at 180.34 53.34 0)
			(effects
				(font
					(size 1.27 1.27)
					(thickness 0.15)
				)
				(justify left bottom)
				(hide yes)
			)
		)
		(property "Manufacturer" "Samsung Electro-Mechanics"
			(at 182.88 53.34 0)
			(effects
				(font
					(size 1.27 1.27)
					(thickness 0.15)
				)
				(justify left bottom)
				(hide yes)
			)
		)
		(property "License" "Apache-2.0"
			(at 185.42 53.34 0)
			(effects
				(font
					(size 1.27 1.27)
					(thickness 0.15)
				)
				(justify left bottom)
				(hide yes)
			)
		)
		(property "Author" "Antmicro"
			(at 187.96 53.34 0)
			(effects
				(font
					(size 1.27 1.27)
					(thickness 0.15)
				)
				(justify left bottom)
				(hide yes)
			)
		)
		(property "Val" "22u"
			(at 164.084 71.1201 90)
			(effects
				(font
					(size 1.27 1.27)
					(thickness 0.15)
				)
				(justify right)
			)
		)
		(property "Voltage" "25V"
			(at 164.084 73.66 90)
			(effects
				(font
					(size 1.27 1.27)
				)
				(justify right)
			)
		)
		(property "Dielectric" "X5R"
			(at 193.04 53.34 0)
			(effects
				(font
					(size 1.27 1.27)
				)
				(justify left bottom)
				(hide yes)
			)
		)
		(property "Public" "False"
			(at 195.58 53.34 0)
			(effects
				(font
					(size 1.27 1.27)
				)
				(justify left bottom)
				(hide yes)
			)
		)
		(pin "2"
		)
		(pin "1"
		)
		(instances
			(project "jetson-agx-thor-baseboard"
				(path ""
					(reference "C286")
					(unit 1)
				)
			)
		)
	)
	(symbol
		(lib_id "antmicroResistors0402:R_10k_0402")
		(at 143.51 226.06 90)
		(unit 1)
		(exclude_from_sim no)
		(in_bom yes)
		(on_board yes)
		(dnp no)
		(property "Reference" "R53"
			(at 144.78 222.25 90)
			(effects
				(font
					(size 1.27 1.27)
					(thickness 0.15)
				)
				(justify right)
			)
		)
		(property "Value" "R_10k_0402"
			(at 156.21 205.74 0)
			(effects
				(font
					(size 1.27 1.27)
					(thickness 0.15)
				)
				(justify left bottom)
				(hide yes)
			)
		)
		(property "Footprint" "antmicro-footprints:R_0402_1005Metric"
			(at 158.75 205.74 0)
			(effects
				(font
					(size 1.27 1.27)
					(thickness 0.15)
				)
				(justify left bottom)
				(hide yes)
			)
		)
		(property "Datasheet" "https://www.bourns.com/docs/product-datasheets/cr.pdf"
			(at 161.29 205.74 0)
			(effects
				(font
					(size 1.27 1.27)
					(thickness 0.15)
				)
				(justify left bottom)
				(hide yes)
			)
		)
		(property "Description" "SMD Chip Resistor, 10 kohm, ± 1%, 62.5 mW, 0402 [1005 Metric], Thick Film, General Purpose"
			(at 143.51 226.06 0)
			(effects
				(font
					(size 1.27 1.27)
				)
				(hide yes)
			)
		)
		(property "MPN" "CR0402-FX-1002GLF"
			(at 163.83 205.74 0)
			(effects
				(font
					(size 1.27 1.27)
					(thickness 0.15)
				)
				(justify left bottom)
				(hide yes)
			)
		)
		(property "Manufacturer" "Bourns"
			(at 166.37 205.74 0)
			(effects
				(font
					(size 1.27 1.27)
					(thickness 0.15)
				)
				(justify left bottom)
				(hide yes)
			)
		)
		(property "License" "Apache-2.0"
			(at 168.91 205.74 0)
			(effects
				(font
					(size 1.27 1.27)
					(thickness 0.15)
				)
				(justify left bottom)
				(hide yes)
			)
		)
		(property "Author" "Antmicro"
			(at 171.45 205.74 0)
			(effects
				(font
					(size 1.27 1.27)
					(thickness 0.15)
				)
				(justify left bottom)
				(hide yes)
			)
		)
		(property "Val" "10k"
			(at 144.78 224.79 90)
			(effects
				(font
					(size 1.27 1.27)
					(thickness 0.15)
				)
				(justify right)
			)
		)
		(property "Tolerance" "1%"
			(at 153.67 205.74 0)
			(effects
				(font
					(size 1.27 1.27)
				)
				(justify left bottom)
				(hide yes)
			)
		)
		(pin "2"
		)
		(pin "1"
		)
		(instances
			(project "jetson-agx-thor-baseboard"
				(path ""
					(reference "R53")
					(unit 1)
				)
			)
		)
	)
	(symbol
		(lib_id "antmicroCapacitors0603:C_22u_16V_0603")
		(at 154.94 273.05 90)
		(unit 1)
		(exclude_from_sim no)
		(in_bom yes)
		(on_board yes)
		(dnp no)
		(property "Reference" "C64"
			(at 155.575 268.605 90)
			(effects
				(font
					(size 1.27 1.27)
				)
				(justify right)
			)
		)
		(property "Value" "C_22u_16V_0603"
			(at 165.1 252.73 0)
			(effects
				(font
					(size 1.27 1.27)
					(thickness 0.15)
				)
				(justify left bottom)
				(hide yes)
			)
		)
		(property "Footprint" "antmicro-footprints:C_0603_1608Metric_EIA"
			(at 167.64 252.73 0)
			(effects
				(font
					(size 1.27 1.27)
					(thickness 0.15)
				)
				(justify left bottom)
				(hide yes)
			)
		)
		(property "Datasheet" "https://product.samsungsem.com/mlcc/CL10A226MO7JZN.do"
			(at 170.18 252.73 0)
			(effects
				(font
					(size 1.27 1.27)
					(thickness 0.15)
				)
				(justify left bottom)
				(hide yes)
			)
		)
		(property "Description" "SMD Multilayer Ceramic Capacitor"
			(at 154.94 273.05 0)
			(effects
				(font
					(size 1.27 1.27)
				)
				(hide yes)
			)
		)
		(property "Manufacturer" "Samsung Electro-Mechanics"
			(at 175.26 252.73 0)
			(effects
				(font
					(size 1.27 1.27)
					(thickness 0.15)
				)
				(justify left bottom)
				(hide yes)
			)
		)
		(property "MPN" "CL10A226MO7JZNC"
			(at 172.72 252.73 0)
			(effects
				(font
					(size 1.27 1.27)
					(thickness 0.15)
				)
				(justify left bottom)
				(hide yes)
			)
		)
		(property "Val" "22u"
			(at 155.575 272.415 90)
			(effects
				(font
					(size 1.27 1.27)
					(thickness 0.15)
				)
				(justify right)
			)
		)
		(property "License" "Apache-2.0"
			(at 177.8 252.73 0)
			(effects
				(font
					(size 1.27 1.27)
					(thickness 0.15)
				)
				(justify left bottom)
				(hide yes)
			)
		)
		(property "Author" "Antmicro"
			(at 180.34 252.73 0)
			(effects
				(font
					(size 1.27 1.27)
					(thickness 0.15)
				)
				(justify left bottom)
				(hide yes)
			)
		)
		(property "Voltage" "16V"
			(at 182.88 252.73 0)
			(effects
				(font
					(size 1.27 1.27)
				)
				(justify left bottom)
				(hide yes)
			)
		)
		(property "Dielectric" ""
			(at 185.42 252.73 0)
			(effects
				(font
					(size 1.27 1.27)
				)
				(justify left bottom)
				(hide yes)
			)
		)
		(pin "1"
		)
		(pin "2"
		)
		(instances
			(project "jetson-agx-thor-baseboard"
				(path ""
					(reference "C64")
					(unit 1)
				)
			)
		)
	)
	(symbol
		(lib_id "antmicroResistors0402:R_27R_0402")
		(at 220.98 41.91 90)
		(unit 1)
		(exclude_from_sim no)
		(in_bom yes)
		(on_board yes)
		(dnp no)
		(fields_autoplaced yes)
		(property "Reference" "R370"
			(at 223.52 38.0999 90)
			(effects
				(font
					(size 1.27 1.27)
				)
				(justify right)
			)
		)
		(property "Value" "R_27R_0402"
			(at 233.68 21.59 0)
			(effects
				(font
					(size 1.27 1.27)
					(thickness 0.15)
				)
				(justify left bottom)
				(hide yes)
			)
		)
		(property "Footprint" "antmicro-footprints:R_0402_1005Metric"
			(at 236.22 21.59 0)
			(effects
				(font
					(size 1.27 1.27)
					(thickness 0.15)
				)
				(justify left bottom)
				(hide yes)
			)
		)
		(property "Datasheet" "https://www.bourns.com/docs/product-datasheets/cr.pdf"
			(at 238.76 21.59 0)
			(effects
				(font
					(size 1.27 1.27)
					(thickness 0.15)
				)
				(justify left bottom)
				(hide yes)
			)
		)
		(property "Description" "SMD Chip Resistor, 27 ohm, ± 1%, 63 mW, 0402 [1005 Metric], Thick Film, General Purpose"
			(at 220.98 41.91 0)
			(effects
				(font
					(size 1.27 1.27)
				)
				(hide yes)
			)
		)
		(property "Manufacturer" "Bourns"
			(at 243.84 21.59 0)
			(effects
				(font
					(size 1.27 1.27)
					(thickness 0.15)
				)
				(justify left bottom)
				(hide yes)
			)
		)
		(property "MPN" "CR0402-FX-27R0GLF"
			(at 241.3 21.59 0)
			(effects
				(font
					(size 1.27 1.27)
					(thickness 0.15)
				)
				(justify left bottom)
				(hide yes)
			)
		)
		(property "Val" "27R"
			(at 223.52 40.64 90)
			(effects
				(font
					(size 1.27 1.27)
					(thickness 0.15)
				)
				(justify right)
			)
		)
		(property "License" "Apache-2.0"
			(at 246.38 21.59 0)
			(effects
				(font
					(size 1.27 1.27)
					(thickness 0.15)
				)
				(justify left bottom)
				(hide yes)
			)
		)
		(property "Author" "Antmicro"
			(at 248.92 21.59 0)
			(effects
				(font
					(size 1.27 1.27)
					(thickness 0.15)
				)
				(justify left bottom)
				(hide yes)
			)
		)
		(property "Tolerance" "1%"
			(at 231.14 21.59 0)
			(effects
				(font
					(size 1.27 1.27)
				)
				(justify left bottom)
				(hide yes)
			)
		)
		(pin "1"
		)
		(pin "2"
		)
		(instances
			(project "jetson-agx-thor-baseboard"
				(path ""
					(reference "R370")
					(unit 1)
				)
			)
		)
	)
	(symbol
		(lib_id "antmicroFixedInductors:L_1u8_6.8A_WE-MAPI-4020")
		(at 326.39 182.88 0)
		(unit 1)
		(exclude_from_sim no)
		(in_bom yes)
		(on_board yes)
		(dnp no)
		(fields_autoplaced yes)
		(property "Reference" "L5"
			(at 328.93 177.8 0)
			(effects
				(font
					(size 1.27 1.27)
					(thickness 0.15)
				)
			)
		)
		(property "Value" "L_1u8_6.8A_WE-MAPI-4020"
			(at 340.36 185.42 0)
			(effects
				(font
					(size 1.27 1.27)
					(thickness 0.15)
				)
				(justify left bottom)
				(hide yes)
			)
		)
		(property "Footprint" "antmicro-footprints:L_WE-MAPI-4020"
			(at 340.36 190.5 0)
			(effects
				(font
					(size 1.27 1.27)
					(thickness 0.15)
				)
				(justify left bottom)
				(hide yes)
			)
		)
		(property "Datasheet" "https://www.we-online.com/components/products/datasheet/74438356018.pdf"
			(at 340.36 193.04 0)
			(effects
				(font
					(size 1.27 1.27)
					(thickness 0.15)
				)
				(justify left bottom)
				(hide yes)
			)
		)
		(property "Description" "Power Inductors - SMD WE-MAPI 1.8uH 4.6A DCR=30mOhms AEC-Q200"
			(at 326.39 182.88 0)
			(effects
				(font
					(size 1.27 1.27)
				)
				(hide yes)
			)
		)
		(property "Val" "1u8/6.8A"
			(at 328.93 180.34 0)
			(effects
				(font
					(size 1.27 1.27)
					(thickness 0.15)
				)
			)
		)
		(property "Manufacturer" "Würth Elektronik"
			(at 340.36 195.58 0)
			(effects
				(font
					(size 1.27 1.27)
					(thickness 0.15)
				)
				(justify left bottom)
				(hide yes)
			)
		)
		(property "MPN" "74438356018"
			(at 340.36 198.12 0)
			(effects
				(font
					(size 1.27 1.27)
					(thickness 0.15)
				)
				(justify left bottom)
				(hide yes)
			)
		)
		(property "ISat" "6.5 A"
			(at 340.36 199.39 0)
			(effects
				(font
					(size 1.27 1.27)
				)
				(justify left)
				(hide yes)
			)
		)
		(property "IMax" "6.8 A"
			(at 340.36 203.2 0)
			(effects
				(font
					(size 1.27 1.27)
					(thickness 0.15)
				)
				(justify left bottom)
				(hide yes)
			)
		)
		(property "Size" "4.1x4.1mm"
			(at 340.36 205.74 0)
			(effects
				(font
					(size 1.27 1.27)
					(thickness 0.15)
				)
				(justify left bottom)
				(hide yes)
			)
		)
		(property "Author" "Antmicro"
			(at 340.36 208.28 0)
			(effects
				(font
					(size 1.27 1.27)
					(thickness 0.15)
				)
				(justify left bottom)
				(hide yes)
			)
		)
		(property "License" "Apache-2.0"
			(at 340.36 210.82 0)
			(effects
				(font
					(size 1.27 1.27)
					(thickness 0.15)
				)
				(justify left bottom)
				(hide yes)
			)
		)
		(pin "2"
		)
		(pin "1"
		)
		(instances
			(project "jetson-agx-thor-baseboard"
				(path ""
					(reference "L5")
					(unit 1)
				)
			)
		)
	)
	(symbol
		(lib_id "antmicroResistors0603:R_0R_22.4A_0603")
		(at 386.08 38.1 0)
		(unit 1)
		(exclude_from_sim no)
		(in_bom yes)
		(on_board yes)
		(dnp no)
		(fields_autoplaced yes)
		(property "Reference" "R22"
			(at 388.62 29.21 0)
			(effects
				(font
					(size 1.27 1.27)
				)
			)
		)
		(property "Value" "R_0R_22.4A_0603"
			(at 388.62 29.21 0)
			(effects
				(font
					(size 1.27 1.27)
					(thickness 0.15)
				)
				(hide yes)
			)
		)
		(property "Footprint" "antmicro-footprints:R_0603_1608Metric"
			(at 401.32 48.26 0)
			(effects
				(font
					(size 1.27 1.27)
					(thickness 0.15)
				)
				(justify left bottom)
				(hide yes)
			)
		)
		(property "Datasheet" "https://fscdn.rohm.com/en/products/databook/datasheet/passive/resistor/chip_resistor/pmr-jpw-e.pdf"
			(at 401.32 50.8 0)
			(effects
				(font
					(size 1.27 1.27)
					(thickness 0.15)
				)
				(justify left bottom)
				(hide yes)
			)
		)
		(property "Description" "SMD Chip Resistor"
			(at 386.08 38.1 0)
			(effects
				(font
					(size 1.27 1.27)
				)
				(hide yes)
			)
		)
		(property "Manufacturer" "ROHM Semiconductor"
			(at 401.32 55.88 0)
			(effects
				(font
					(size 1.27 1.27)
					(thickness 0.15)
				)
				(justify left bottom)
				(hide yes)
			)
		)
		(property "MPN" "PMR03EZPJ000"
			(at 401.32 53.34 0)
			(effects
				(font
					(size 1.27 1.27)
					(thickness 0.15)
				)
				(justify left bottom)
				(hide yes)
			)
		)
		(property "Val" "0R"
			(at 388.62 31.75 0)
			(effects
				(font
					(size 1.27 1.27)
					(thickness 0.15)
				)
			)
		)
		(property "Author" "Antmicro"
			(at 401.32 60.96 0)
			(effects
				(font
					(size 1.27 1.27)
					(thickness 0.15)
				)
				(justify left bottom)
				(hide yes)
			)
		)
		(property "License" "Apache-2.0"
			(at 401.32 63.5 0)
			(effects
				(font
					(size 1.27 1.27)
					(thickness 0.15)
				)
				(justify left bottom)
				(hide yes)
			)
		)
		(property "Max. Curr." "22.4A"
			(at 388.62 34.29 0)
			(effects
				(font
					(size 1.27 1.27)
					(thickness 0.15)
				)
			)
		)
		(property "Tolerance" "template_tolerance"
			(at 406.4 48.26 0)
			(effects
				(font
					(size 1.27 1.27)
				)
				(justify left bottom)
				(hide yes)
			)
		)
		(pin "1"
		)
		(pin "2"
		)
		(instances
			(project "jetson-agx-thor-baseboard"
				(path ""
					(reference "R22")
					(unit 1)
				)
			)
		)
	)
	(symbol
		(lib_id "antmicropower:PWR_FLAG")
		(at 237.49 101.6 270)
		(unit 1)
		(exclude_from_sim no)
		(in_bom yes)
		(on_board yes)
		(dnp no)
		(property "Reference" "#FLG023"
			(at 239.395 101.6 0)
			(effects
				(font
					(size 1.27 1.27)
				)
				(hide yes)
			)
		)
		(property "Value" "PWR_FLAG"
			(at 239.522 99.06 90)
			(effects
				(font
					(size 1.27 1.27)
				)
			)
		)
		(property "Footprint" ""
			(at 237.49 101.6 0)
			(effects
				(font
					(size 1.27 1.27)
				)
				(hide yes)
			)
		)
		(property "Datasheet" ""
			(at 237.49 101.6 0)
			(effects
				(font
					(size 1.27 1.27)
				)
				(hide yes)
			)
		)
		(property "Description" ""
			(at 237.49 101.6 0)
			(effects
				(font
					(size 1.27 1.27)
				)
				(hide yes)
			)
		)
		(pin "1"
		)
		(instances
			(project "jetson-agx-thor-baseboard"
				(path ""
					(reference "#FLG023")
					(unit 1)
				)
			)
		)
	)
	(symbol
		(lib_id "antmicropower:+24V")
		(at 233.68 100.33 0)
		(unit 1)
		(exclude_from_sim no)
		(in_bom yes)
		(on_board yes)
		(dnp no)
		(fields_autoplaced yes)
		(property "Reference" "#PWR0772"
			(at 233.68 104.14 0)
			(effects
				(font
					(size 1.27 1.27)
				)
				(hide yes)
			)
		)
		(property "Value" "+20V"
			(at 233.68 95.25 0)
			(effects
				(font
					(size 1.27 1.27)
				)
			)
		)
		(property "Footprint" ""
			(at 233.68 100.33 0)
			(effects
				(font
					(size 1.27 1.27)
				)
				(hide yes)
			)
		)
		(property "Datasheet" ""
			(at 233.68 100.33 0)
			(effects
				(font
					(size 1.27 1.27)
				)
				(hide yes)
			)
		)
		(property "Description" ""
			(at 233.68 106.68 0)
			(effects
				(font
					(size 1.27 1.27)
				)
				(justify left bottom)
				(hide yes)
			)
		)
		(pin "1"
		)
		(instances
			(project "jetson-agx-thor-baseboard"
				(path ""
					(reference "#PWR0772")
					(unit 1)
				)
			)
		)
	)
	(symbol
		(lib_id "antmicroResistors0402:R_10k_0402")
		(at 143.51 115.57 90)
		(unit 1)
		(exclude_from_sim no)
		(in_bom yes)
		(on_board yes)
		(dnp no)
		(property "Reference" "R125"
			(at 144.78 111.76 90)
			(effects
				(font
					(size 1.27 1.27)
					(thickness 0.15)
				)
				(justify right)
			)
		)
		(property "Value" "R_10k_0402"
			(at 156.21 95.25 0)
			(effects
				(font
					(size 1.27 1.27)
					(thickness 0.15)
				)
				(justify left bottom)
				(hide yes)
			)
		)
		(property "Footprint" "antmicro-footprints:R_0402_1005Metric"
			(at 158.75 95.25 0)
			(effects
				(font
					(size 1.27 1.27)
					(thickness 0.15)
				)
				(justify left bottom)
				(hide yes)
			)
		)
		(property "Datasheet" "https://www.bourns.com/docs/product-datasheets/cr.pdf"
			(at 161.29 95.25 0)
			(effects
				(font
					(size 1.27 1.27)
					(thickness 0.15)
				)
				(justify left bottom)
				(hide yes)
			)
		)
		(property "Description" "SMD Chip Resistor, 10 kohm, ± 1%, 62.5 mW, 0402 [1005 Metric], Thick Film, General Purpose"
			(at 143.51 115.57 0)
			(effects
				(font
					(size 1.27 1.27)
				)
				(hide yes)
			)
		)
		(property "MPN" "CR0402-FX-1002GLF"
			(at 163.83 95.25 0)
			(effects
				(font
					(size 1.27 1.27)
					(thickness 0.15)
				)
				(justify left bottom)
				(hide yes)
			)
		)
		(property "Manufacturer" "Bourns"
			(at 166.37 95.25 0)
			(effects
				(font
					(size 1.27 1.27)
					(thickness 0.15)
				)
				(justify left bottom)
				(hide yes)
			)
		)
		(property "License" "Apache-2.0"
			(at 168.91 95.25 0)
			(effects
				(font
					(size 1.27 1.27)
					(thickness 0.15)
				)
				(justify left bottom)
				(hide yes)
			)
		)
		(property "Author" "Antmicro"
			(at 171.45 95.25 0)
			(effects
				(font
					(size 1.27 1.27)
					(thickness 0.15)
				)
				(justify left bottom)
				(hide yes)
			)
		)
		(property "Val" "10k"
			(at 144.78 114.3 90)
			(effects
				(font
					(size 1.27 1.27)
					(thickness 0.15)
				)
				(justify right)
			)
		)
		(property "Tolerance" "1%"
			(at 153.67 95.25 0)
			(effects
				(font
					(size 1.27 1.27)
				)
				(justify left bottom)
				(hide yes)
			)
		)
		(pin "2"
		)
		(pin "1"
		)
		(instances
			(project "jetson-agx-thor-baseboard"
				(path ""
					(reference "R125")
					(unit 1)
				)
			)
		)
	)
	(symbol
		(lib_id "antmicropower:GND")
		(at 115.57 279.4 0)
		(unit 1)
		(exclude_from_sim no)
		(in_bom yes)
		(on_board yes)
		(dnp no)
		(property "Reference" "#PWR0121"
			(at 115.57 285.75 0)
			(effects
				(font
					(size 1.27 1.27)
				)
				(justify left bottom)
				(hide yes)
			)
		)
		(property "Value" "GND"
			(at 115.57 283.21 0)
			(effects
				(font
					(size 1.27 1.27)
					(thickness 0.15)
				)
			)
		)
		(property "Footprint" ""
			(at 124.46 287.02 0)
			(effects
				(font
					(size 1.27 1.27)
					(thickness 0.15)
				)
				(justify left bottom)
				(hide yes)
			)
		)
		(property "Datasheet" ""
			(at 124.46 292.1 0)
			(effects
				(font
					(size 1.27 1.27)
					(thickness 0.15)
				)
				(justify left bottom)
				(hide yes)
			)
		)
		(property "Description" ""
			(at 115.57 279.4 0)
			(effects
				(font
					(size 1.27 1.27)
				)
				(hide yes)
			)
		)
		(property "Author" "Antmicro"
			(at 124.46 287.02 0)
			(effects
				(font
					(size 1.27 1.27)
					(thickness 0.15)
				)
				(justify left bottom)
				(hide yes)
			)
		)
		(property "License" "Apache-2.0"
			(at 124.46 289.56 0)
			(effects
				(font
					(size 1.27 1.27)
					(thickness 0.15)
				)
				(justify left bottom)
				(hide yes)
			)
		)
		(pin "1"
		)
		(instances
			(project "jetson-agx-thor-baseboard"
				(path ""
					(reference "#PWR0121")
					(unit 1)
				)
			)
		)
	)
	(symbol
		(lib_id "antmicropower:GND")
		(at 220.98 66.04 0)
		(unit 1)
		(exclude_from_sim no)
		(in_bom yes)
		(on_board yes)
		(dnp no)
		(property "Reference" "#PWR0521"
			(at 229.87 68.58 0)
			(effects
				(font
					(size 1.27 1.27)
					(thickness 0.15)
				)
				(justify left bottom)
				(hide yes)
			)
		)
		(property "Value" "GND"
			(at 220.98 69.85 0)
			(effects
				(font
					(size 1.27 1.27)
					(thickness 0.15)
				)
			)
		)
		(property "Footprint" ""
			(at 229.87 73.66 0)
			(effects
				(font
					(size 1.27 1.27)
					(thickness 0.15)
				)
				(justify left bottom)
				(hide yes)
			)
		)
		(property "Datasheet" ""
			(at 229.87 78.74 0)
			(effects
				(font
					(size 1.27 1.27)
					(thickness 0.15)
				)
				(justify left bottom)
				(hide yes)
			)
		)
		(property "Description" ""
			(at 220.98 66.04 0)
			(effects
				(font
					(size 1.27 1.27)
				)
				(hide yes)
			)
		)
		(property "Author" "Antmicro"
			(at 229.87 73.66 0)
			(effects
				(font
					(size 1.27 1.27)
					(thickness 0.15)
				)
				(justify left bottom)
				(hide yes)
			)
		)
		(property "License" "Apache-2.0"
			(at 229.87 76.2 0)
			(effects
				(font
					(size 1.27 1.27)
					(thickness 0.15)
				)
				(justify left bottom)
				(hide yes)
			)
		)
		(pin "1"
		)
		(instances
			(project "jetson-agx-thor-baseboard"
				(path ""
					(reference "#PWR0521")
					(unit 1)
				)
			)
		)
	)
	(symbol
		(lib_id "antmicropower:GND")
		(at 34.29 107.95 0)
		(unit 1)
		(exclude_from_sim no)
		(in_bom yes)
		(on_board yes)
		(dnp no)
		(property "Reference" "#PWR0544"
			(at 34.29 114.3 0)
			(effects
				(font
					(size 1.27 1.27)
				)
				(justify left bottom)
				(hide yes)
			)
		)
		(property "Value" "GND"
			(at 34.29 111.76 0)
			(effects
				(font
					(size 1.27 1.27)
					(thickness 0.15)
				)
			)
		)
		(property "Footprint" ""
			(at 43.18 115.57 0)
			(effects
				(font
					(size 1.27 1.27)
					(thickness 0.15)
				)
				(justify left bottom)
				(hide yes)
			)
		)
		(property "Datasheet" ""
			(at 43.18 120.65 0)
			(effects
				(font
					(size 1.27 1.27)
					(thickness 0.15)
				)
				(justify left bottom)
				(hide yes)
			)
		)
		(property "Description" ""
			(at 34.29 107.95 0)
			(effects
				(font
					(size 1.27 1.27)
				)
				(hide yes)
			)
		)
		(property "Author" "Antmicro"
			(at 43.18 115.57 0)
			(effects
				(font
					(size 1.27 1.27)
					(thickness 0.15)
				)
				(justify left bottom)
				(hide yes)
			)
		)
		(property "License" "Apache-2.0"
			(at 43.18 118.11 0)
			(effects
				(font
					(size 1.27 1.27)
					(thickness 0.15)
				)
				(justify left bottom)
				(hide yes)
			)
		)
		(pin "1"
		)
		(instances
			(project "jetson-agx-thor-baseboard"
				(path ""
					(reference "#PWR0544")
					(unit 1)
				)
			)
		)
	)
	(symbol
		(lib_id "antmicropower:GND")
		(at 177.8 279.4 0)
		(unit 1)
		(exclude_from_sim no)
		(in_bom yes)
		(on_board yes)
		(dnp no)
		(property "Reference" "#PWR0149"
			(at 177.8 285.75 0)
			(effects
				(font
					(size 1.27 1.27)
				)
				(justify left bottom)
				(hide yes)
			)
		)
		(property "Value" "GND"
			(at 177.8 283.21 0)
			(effects
				(font
					(size 1.27 1.27)
					(thickness 0.15)
				)
			)
		)
		(property "Footprint" ""
			(at 186.69 287.02 0)
			(effects
				(font
					(size 1.27 1.27)
					(thickness 0.15)
				)
				(justify left bottom)
				(hide yes)
			)
		)
		(property "Datasheet" ""
			(at 186.69 292.1 0)
			(effects
				(font
					(size 1.27 1.27)
					(thickness 0.15)
				)
				(justify left bottom)
				(hide yes)
			)
		)
		(property "Description" ""
			(at 177.8 279.4 0)
			(effects
				(font
					(size 1.27 1.27)
				)
				(hide yes)
			)
		)
		(property "Author" "Antmicro"
			(at 186.69 287.02 0)
			(effects
				(font
					(size 1.27 1.27)
					(thickness 0.15)
				)
				(justify left bottom)
				(hide yes)
			)
		)
		(property "License" "Apache-2.0"
			(at 186.69 289.56 0)
			(effects
				(font
					(size 1.27 1.27)
					(thickness 0.15)
				)
				(justify left bottom)
				(hide yes)
			)
		)
		(pin "1"
		)
		(instances
			(project "jetson-agx-thor-baseboard"
				(path ""
					(reference "#PWR0149")
					(unit 1)
				)
			)
		)
	)
	(symbol
		(lib_id "antmicropower:GND")
		(at 233.68 48.26 0)
		(unit 1)
		(exclude_from_sim no)
		(in_bom yes)
		(on_board yes)
		(dnp no)
		(property "Reference" "#PWR087"
			(at 233.68 54.61 0)
			(effects
				(font
					(size 1.27 1.27)
				)
				(justify left bottom)
				(hide yes)
			)
		)
		(property "Value" "GND"
			(at 233.68 52.07 0)
			(effects
				(font
					(size 1.27 1.27)
					(thickness 0.15)
				)
			)
		)
		(property "Footprint" ""
			(at 242.57 55.88 0)
			(effects
				(font
					(size 1.27 1.27)
					(thickness 0.15)
				)
				(justify left bottom)
				(hide yes)
			)
		)
		(property "Datasheet" ""
			(at 242.57 60.96 0)
			(effects
				(font
					(size 1.27 1.27)
					(thickness 0.15)
				)
				(justify left bottom)
				(hide yes)
			)
		)
		(property "Description" ""
			(at 233.68 48.26 0)
			(effects
				(font
					(size 1.27 1.27)
				)
				(hide yes)
			)
		)
		(property "Author" "Antmicro"
			(at 242.57 55.88 0)
			(effects
				(font
					(size 1.27 1.27)
					(thickness 0.15)
				)
				(justify left bottom)
				(hide yes)
			)
		)
		(property "License" "Apache-2.0"
			(at 242.57 58.42 0)
			(effects
				(font
					(size 1.27 1.27)
					(thickness 0.15)
				)
				(justify left bottom)
				(hide yes)
			)
		)
		(pin "1"
		)
		(instances
			(project "jetson-agx-thor-baseboard"
				(path ""
					(reference "#PWR087")
					(unit 1)
				)
			)
		)
	)
	(symbol
		(lib_id "antmicroFixedInductors:L_3u3_15.1A_Coilcraft-XAL7070")
		(at 134.62 35.56 0)
		(unit 1)
		(exclude_from_sim no)
		(in_bom yes)
		(on_board yes)
		(dnp no)
		(fields_autoplaced yes)
		(property "Reference" "L3"
			(at 137.16 30.48 0)
			(effects
				(font
					(size 1.27 1.27)
					(thickness 0.15)
				)
			)
		)
		(property "Value" "L_3u3_15.1A_Coilcraft-XAL7070"
			(at 148.59 38.1 0)
			(effects
				(font
					(size 1.27 1.27)
					(thickness 0.15)
				)
				(justify left bottom)
				(hide yes)
			)
		)
		(property "Footprint" "antmicro-footprints:L_Coilcraft-XAL7070"
			(at 148.59 43.18 0)
			(effects
				(font
					(size 1.27 1.27)
					(thickness 0.15)
				)
				(justify left bottom)
				(hide yes)
			)
		)
		(property "Datasheet" "https://www.coilcraft.com/en-us/products/power/shielded-inductors/molded-inductor/xal/xal7070/xal7070-332/"
			(at 148.59 45.72 0)
			(effects
				(font
					(size 1.27 1.27)
					(thickness 0.15)
				)
				(justify left bottom)
				(hide yes)
			)
		)
		(property "Description" "Power Inductor (SMD), 3.3 µH, 15.1 A, Shielded, 19.4 A, XAL7070"
			(at 148.59 66.04 0)
			(effects
				(font
					(size 1.27 1.27)
				)
				(justify left bottom)
				(hide yes)
			)
		)
		(property "Val" "3u3/15.1A"
			(at 137.16 33.02 0)
			(effects
				(font
					(size 1.27 1.27)
					(thickness 0.15)
				)
			)
		)
		(property "Manufacturer" "Coilcraft"
			(at 148.59 48.26 0)
			(effects
				(font
					(size 1.27 1.27)
					(thickness 0.15)
				)
				(justify left bottom)
				(hide yes)
			)
		)
		(property "MPN" "XAL7070-332MEB"
			(at 148.59 50.8 0)
			(effects
				(font
					(size 1.27 1.27)
					(thickness 0.15)
				)
				(justify left bottom)
				(hide yes)
			)
		)
		(property "ISat" "19.4 A"
			(at 148.59 52.07 0)
			(effects
				(font
					(size 1.27 1.27)
				)
				(justify left)
				(hide yes)
			)
		)
		(property "IMax" "15.1 A"
			(at 148.59 55.88 0)
			(effects
				(font
					(size 1.27 1.27)
					(thickness 0.15)
				)
				(justify left bottom)
				(hide yes)
			)
		)
		(property "Size" "7.7x8"
			(at 148.59 58.42 0)
			(effects
				(font
					(size 1.27 1.27)
					(thickness 0.15)
				)
				(justify left bottom)
				(hide yes)
			)
		)
		(property "Author" "Antmicro"
			(at 148.59 60.96 0)
			(effects
				(font
					(size 1.27 1.27)
					(thickness 0.15)
				)
				(justify left bottom)
				(hide yes)
			)
		)
		(property "License" "Apache-2.0"
			(at 148.59 63.5 0)
			(effects
				(font
					(size 1.27 1.27)
					(thickness 0.15)
				)
				(justify left bottom)
				(hide yes)
			)
		)
		(pin "2"
		)
		(pin "1"
		)
		(instances
			(project "jetson-agx-thor-baseboard"
				(path ""
					(reference "L3")
					(unit 1)
				)
			)
		)
	)
	(symbol
		(lib_id "antmicroResistors0402:R_200k_0402")
		(at 58.42 186.69 90)
		(unit 1)
		(exclude_from_sim no)
		(in_bom yes)
		(on_board yes)
		(dnp no)
		(property "Reference" "R310"
			(at 59.69 182.88 90)
			(effects
				(font
					(size 1.27 1.27)
					(thickness 0.15)
				)
				(justify right)
			)
		)
		(property "Value" "R_200k_0402"
			(at 71.12 166.37 0)
			(effects
				(font
					(size 1.27 1.27)
					(thickness 0.15)
				)
				(justify left bottom)
				(hide yes)
			)
		)
		(property "Footprint" "antmicro-footprints:R_0402_1005Metric"
			(at 73.66 166.37 0)
			(effects
				(font
					(size 1.27 1.27)
					(thickness 0.15)
				)
				(justify left bottom)
				(hide yes)
			)
		)
		(property "Datasheet" "https://www.bourns.com/docs/product-datasheets/cr.pdf"
			(at 76.2 166.37 0)
			(effects
				(font
					(size 1.27 1.27)
					(thickness 0.15)
				)
				(justify left bottom)
				(hide yes)
			)
		)
		(property "Description" "SMD Chip Resistor, 200 kohm, ± 1%, 62.5 mW, 0402 [1005 Metric], Thick Film, General Purpose"
			(at 88.9 166.37 0)
			(effects
				(font
					(size 1.27 1.27)
				)
				(justify left bottom)
				(hide yes)
			)
		)
		(property "MPN" "CR0402-FX-2003GLF"
			(at 78.74 166.37 0)
			(effects
				(font
					(size 1.27 1.27)
					(thickness 0.15)
				)
				(justify left bottom)
				(hide yes)
			)
		)
		(property "Manufacturer" "Bourns"
			(at 81.28 166.37 0)
			(effects
				(font
					(size 1.27 1.27)
					(thickness 0.15)
				)
				(justify left bottom)
				(hide yes)
			)
		)
		(property "License" "Apache-2.0"
			(at 83.82 166.37 0)
			(effects
				(font
					(size 1.27 1.27)
					(thickness 0.15)
				)
				(justify left bottom)
				(hide yes)
			)
		)
		(property "Author" "Antmicro"
			(at 86.36 166.37 0)
			(effects
				(font
					(size 1.27 1.27)
					(thickness 0.15)
				)
				(justify left bottom)
				(hide yes)
			)
		)
		(property "Val" "200k"
			(at 59.69 185.42 90)
			(effects
				(font
					(size 1.27 1.27)
					(thickness 0.15)
				)
				(justify right)
			)
		)
		(property "Tolerance" "1%"
			(at 68.58 166.37 0)
			(effects
				(font
					(size 1.27 1.27)
				)
				(justify left bottom)
				(hide yes)
			)
		)
		(pin "2"
		)
		(pin "1"
		)
		(instances
			(project ""
				(path ""
					(reference "R310")
					(unit 1)
				)
			)
		)
	)
	(symbol
		(lib_id "antmicropower:GND")
		(at 232.41 187.96 0)
		(unit 1)
		(exclude_from_sim no)
		(in_bom yes)
		(on_board yes)
		(dnp no)
		(property "Reference" "#PWR0654"
			(at 232.41 194.31 0)
			(effects
				(font
					(size 1.27 1.27)
				)
				(justify left bottom)
				(hide yes)
			)
		)
		(property "Value" "GND"
			(at 232.41 191.77 0)
			(effects
				(font
					(size 1.27 1.27)
					(thickness 0.15)
				)
			)
		)
		(property "Footprint" ""
			(at 241.3 195.58 0)
			(effects
				(font
					(size 1.27 1.27)
					(thickness 0.15)
				)
				(justify left bottom)
				(hide yes)
			)
		)
		(property "Datasheet" ""
			(at 241.3 200.66 0)
			(effects
				(font
					(size 1.27 1.27)
					(thickness 0.15)
				)
				(justify left bottom)
				(hide yes)
			)
		)
		(property "Description" ""
			(at 232.41 187.96 0)
			(effects
				(font
					(size 1.27 1.27)
				)
				(hide yes)
			)
		)
		(property "Author" "Antmicro"
			(at 241.3 195.58 0)
			(effects
				(font
					(size 1.27 1.27)
					(thickness 0.15)
				)
				(justify left bottom)
				(hide yes)
			)
		)
		(property "License" "Apache-2.0"
			(at 241.3 198.12 0)
			(effects
				(font
					(size 1.27 1.27)
					(thickness 0.15)
				)
				(justify left bottom)
				(hide yes)
			)
		)
		(pin "1"
		)
		(instances
			(project "jetson-agx-thor-baseboard"
				(path ""
					(reference "#PWR0654")
					(unit 1)
				)
			)
		)
	)
	(symbol
		(lib_id "antmicroCapacitors0402:C_1u_0402")
		(at 72.39 278.13 90)
		(unit 1)
		(exclude_from_sim no)
		(in_bom yes)
		(on_board yes)
		(dnp no)
		(property "Reference" "C53"
			(at 73.025 273.685 90)
			(effects
				(font
					(size 1.27 1.27)
				)
				(justify right)
			)
		)
		(property "Value" "C_1u_0402"
			(at 82.55 257.81 0)
			(effects
				(font
					(size 1.27 1.27)
					(thickness 0.15)
				)
				(justify left bottom)
				(hide yes)
			)
		)
		(property "Footprint" "antmicro-footprints:C_0402_1005Metric"
			(at 85.09 257.81 0)
			(effects
				(font
					(size 1.27 1.27)
					(thickness 0.15)
				)
				(justify left bottom)
				(hide yes)
			)
		)
		(property "Datasheet" "https://product.tdk.com/en/search/capacitor/ceramic/mlcc/info?part_no=C1005X6S1A105K050BC"
			(at 87.63 257.81 0)
			(effects
				(font
					(size 1.27 1.27)
					(thickness 0.15)
				)
				(justify left bottom)
				(hide yes)
			)
		)
		(property "Description" "SMD Multilayer Ceramic Capacitor, 1 µF, 10 V, 0402 [1005 Metric], ± 10%, X6S, C"
			(at 72.39 278.13 0)
			(effects
				(font
					(size 1.27 1.27)
				)
				(hide yes)
			)
		)
		(property "Manufacturer" "TDK"
			(at 92.71 257.81 0)
			(effects
				(font
					(size 1.27 1.27)
					(thickness 0.15)
				)
				(justify left bottom)
				(hide yes)
			)
		)
		(property "MPN" "C1005X6S1A105K050BC"
			(at 90.17 257.81 0)
			(effects
				(font
					(size 1.27 1.27)
					(thickness 0.15)
				)
				(justify left bottom)
				(hide yes)
			)
		)
		(property "Val" "1u"
			(at 73.025 277.495 90)
			(effects
				(font
					(size 1.27 1.27)
					(thickness 0.15)
				)
				(justify right)
			)
		)
		(property "License" "Apache-2.0"
			(at 95.25 257.81 0)
			(effects
				(font
					(size 1.27 1.27)
					(thickness 0.15)
				)
				(justify left bottom)
				(hide yes)
			)
		)
		(property "Author" "Antmicro"
			(at 97.79 257.81 0)
			(effects
				(font
					(size 1.27 1.27)
					(thickness 0.15)
				)
				(justify left bottom)
				(hide yes)
			)
		)
		(property "Voltage" ""
			(at 100.33 257.81 0)
			(effects
				(font
					(size 1.27 1.27)
				)
				(justify left bottom)
				(hide yes)
			)
		)
		(property "Dielectric" ""
			(at 102.87 257.81 0)
			(effects
				(font
					(size 1.27 1.27)
				)
				(justify left bottom)
				(hide yes)
			)
		)
		(pin "1"
		)
		(pin "2"
		)
		(instances
			(project "jetson-agx-thor-baseboard"
				(path ""
					(reference "C53")
					(unit 1)
				)
			)
		)
	)
	(symbol
		(lib_id "antmicropower:GND")
		(at 143.51 279.4 0)
		(unit 1)
		(exclude_from_sim no)
		(in_bom yes)
		(on_board yes)
		(dnp no)
		(property "Reference" "#PWR0130"
			(at 143.51 285.75 0)
			(effects
				(font
					(size 1.27 1.27)
				)
				(justify left bottom)
				(hide yes)
			)
		)
		(property "Value" "GND"
			(at 143.51 283.21 0)
			(effects
				(font
					(size 1.27 1.27)
					(thickness 0.15)
				)
			)
		)
		(property "Footprint" ""
			(at 152.4 287.02 0)
			(effects
				(font
					(size 1.27 1.27)
					(thickness 0.15)
				)
				(justify left bottom)
				(hide yes)
			)
		)
		(property "Datasheet" ""
			(at 152.4 292.1 0)
			(effects
				(font
					(size 1.27 1.27)
					(thickness 0.15)
				)
				(justify left bottom)
				(hide yes)
			)
		)
		(property "Description" ""
			(at 143.51 279.4 0)
			(effects
				(font
					(size 1.27 1.27)
				)
				(hide yes)
			)
		)
		(property "Author" "Antmicro"
			(at 152.4 287.02 0)
			(effects
				(font
					(size 1.27 1.27)
					(thickness 0.15)
				)
				(justify left bottom)
				(hide yes)
			)
		)
		(property "License" "Apache-2.0"
			(at 152.4 289.56 0)
			(effects
				(font
					(size 1.27 1.27)
					(thickness 0.15)
				)
				(justify left bottom)
				(hide yes)
			)
		)
		(pin "1"
		)
		(instances
			(project "jetson-agx-thor-baseboard"
				(path ""
					(reference "#PWR0130")
					(unit 1)
				)
			)
		)
	)
	(symbol
		(lib_id "antmicropower:GND")
		(at 154.94 59.69 0)
		(unit 1)
		(exclude_from_sim no)
		(in_bom yes)
		(on_board yes)
		(dnp no)
		(property "Reference" "#PWR0540"
			(at 154.94 66.04 0)
			(effects
				(font
					(size 1.27 1.27)
				)
				(justify left bottom)
				(hide yes)
			)
		)
		(property "Value" "GND"
			(at 154.94 63.5 0)
			(effects
				(font
					(size 1.27 1.27)
					(thickness 0.15)
				)
			)
		)
		(property "Footprint" ""
			(at 163.83 67.31 0)
			(effects
				(font
					(size 1.27 1.27)
					(thickness 0.15)
				)
				(justify left bottom)
				(hide yes)
			)
		)
		(property "Datasheet" ""
			(at 163.83 72.39 0)
			(effects
				(font
					(size 1.27 1.27)
					(thickness 0.15)
				)
				(justify left bottom)
				(hide yes)
			)
		)
		(property "Description" ""
			(at 154.94 59.69 0)
			(effects
				(font
					(size 1.27 1.27)
				)
				(hide yes)
			)
		)
		(property "Author" "Antmicro"
			(at 163.83 67.31 0)
			(effects
				(font
					(size 1.27 1.27)
					(thickness 0.15)
				)
				(justify left bottom)
				(hide yes)
			)
		)
		(property "License" "Apache-2.0"
			(at 163.83 69.85 0)
			(effects
				(font
					(size 1.27 1.27)
					(thickness 0.15)
				)
				(justify left bottom)
				(hide yes)
			)
		)
		(pin "1"
		)
		(instances
			(project "jetson-agx-thor-baseboard"
				(path ""
					(reference "#PWR0540")
					(unit 1)
				)
			)
		)
	)
	(symbol
		(lib_id "antmicroCapacitors0402:C_100n_0402")
		(at 214.63 109.22 180)
		(unit 1)
		(exclude_from_sim no)
		(in_bom yes)
		(on_board yes)
		(dnp no)
		(property "Reference" "C386"
			(at 212.09 103.886 0)
			(effects
				(font
					(size 1.27 1.27)
				)
			)
		)
		(property "Value" "C_100n_0402"
			(at 194.31 99.06 0)
			(effects
				(font
					(size 1.27 1.27)
					(thickness 0.15)
				)
				(justify left bottom)
				(hide yes)
			)
		)
		(property "Footprint" "antmicro-footprints:C_0402_1005Metric"
			(at 194.31 96.52 0)
			(effects
				(font
					(size 1.27 1.27)
					(thickness 0.15)
				)
				(justify left bottom)
				(hide yes)
			)
		)
		(property "Datasheet" "https://www.murata.com/products/productdetail?partno=GRM155R61H104KE14%23"
			(at 194.31 93.98 0)
			(effects
				(font
					(size 1.27 1.27)
					(thickness 0.15)
				)
				(justify left bottom)
				(hide yes)
			)
		)
		(property "Description" "SMD Multilayer Ceramic Capacitor, 0.1 µF, 50 V, 0402 [1005 Metric], ± 10%, X5R, GRM Series"
			(at 214.63 109.22 0)
			(effects
				(font
					(size 1.27 1.27)
				)
				(hide yes)
			)
		)
		(property "Manufacturer" "Murata"
			(at 194.31 88.9 0)
			(effects
				(font
					(size 1.27 1.27)
					(thickness 0.15)
				)
				(justify left bottom)
				(hide yes)
			)
		)
		(property "MPN" "GRM155R61H104KE14D"
			(at 194.31 91.44 0)
			(effects
				(font
					(size 1.27 1.27)
					(thickness 0.15)
				)
				(justify left bottom)
				(hide yes)
			)
		)
		(property "Val" "100n"
			(at 212.09 106.426 0)
			(effects
				(font
					(size 1.27 1.27)
					(thickness 0.15)
				)
			)
		)
		(property "License" "Apache-2.0"
			(at 194.31 86.36 0)
			(effects
				(font
					(size 1.27 1.27)
					(thickness 0.15)
				)
				(justify left bottom)
				(hide yes)
			)
		)
		(property "Author" "Antmicro"
			(at 194.31 83.82 0)
			(effects
				(font
					(size 1.27 1.27)
					(thickness 0.15)
				)
				(justify left bottom)
				(hide yes)
			)
		)
		(property "Voltage" "50V"
			(at 194.31 81.28 0)
			(effects
				(font
					(size 1.27 1.27)
				)
				(justify left bottom)
				(hide yes)
			)
		)
		(property "Dielectric" "X5R"
			(at 194.31 78.74 0)
			(effects
				(font
					(size 1.27 1.27)
				)
				(justify left bottom)
				(hide yes)
			)
		)
		(pin "1"
		)
		(pin "2"
		)
		(instances
			(project "jetson-agx-thor-baseboard"
				(path ""
					(reference "C386")
					(unit 1)
				)
			)
		)
	)
	(symbol
		(lib_id "antmicroCapacitorsmisc:C_22u_25V_0805")
		(at 30.48 165.1 90)
		(unit 1)
		(exclude_from_sim no)
		(in_bom yes)
		(on_board yes)
		(dnp no)
		(property "Reference" "C371"
			(at 31.115 160.655 90)
			(effects
				(font
					(size 1.27 1.27)
					(thickness 0.15)
				)
				(justify right)
			)
		)
		(property "Value" "C_22u_25V_0805"
			(at 40.64 144.78 0)
			(effects
				(font
					(size 1.27 1.27)
					(thickness 0.15)
				)
				(justify left bottom)
				(hide yes)
			)
		)
		(property "Footprint" "antmicro-footprints:C_0805_2012Metric"
			(at 43.18 144.78 0)
			(effects
				(font
					(size 1.27 1.27)
					(thickness 0.15)
				)
				(justify left bottom)
				(hide yes)
			)
		)
		(property "Datasheet" "https://product.samsungsem.com/mlcc/CL21A226MAYNNN.do"
			(at 45.72 144.78 0)
			(effects
				(font
					(size 1.27 1.27)
					(thickness 0.15)
				)
				(justify left bottom)
				(hide yes)
			)
		)
		(property "Description" "SMT Multilayer Ceramic Capacitor, 22uF, +/-20%, 25V, X5R, 0805 [2012 Metric]"
			(at 30.48 165.1 0)
			(effects
				(font
					(size 1.27 1.27)
				)
				(hide yes)
			)
		)
		(property "MPN" "CL21A226MAYNNNE"
			(at 48.26 144.78 0)
			(effects
				(font
					(size 1.27 1.27)
					(thickness 0.15)
				)
				(justify left bottom)
				(hide yes)
			)
		)
		(property "Manufacturer" "Samsung Electro-Mechanics"
			(at 50.8 144.78 0)
			(effects
				(font
					(size 1.27 1.27)
					(thickness 0.15)
				)
				(justify left bottom)
				(hide yes)
			)
		)
		(property "License" "Apache-2.0"
			(at 53.34 144.78 0)
			(effects
				(font
					(size 1.27 1.27)
					(thickness 0.15)
				)
				(justify left bottom)
				(hide yes)
			)
		)
		(property "Author" "Antmicro"
			(at 55.88 144.78 0)
			(effects
				(font
					(size 1.27 1.27)
					(thickness 0.15)
				)
				(justify left bottom)
				(hide yes)
			)
		)
		(property "Val" "22u"
			(at 31.115 164.465 90)
			(effects
				(font
					(size 1.27 1.27)
					(thickness 0.15)
				)
				(justify right)
			)
		)
		(property "Voltage" "25V"
			(at 31.115 167.005 90)
			(effects
				(font
					(size 1.27 1.27)
				)
				(justify right)
			)
		)
		(property "Dielectric" "X5R"
			(at 60.96 144.78 0)
			(effects
				(font
					(size 1.27 1.27)
				)
				(justify left bottom)
				(hide yes)
			)
		)
		(property "Public" "False"
			(at 63.5 144.78 0)
			(effects
				(font
					(size 1.27 1.27)
				)
				(justify left bottom)
				(hide yes)
			)
		)
		(pin "1"
		)
		(pin "2"
		)
		(instances
			(project "jetson-agx-thor-baseboard"
				(path ""
					(reference "C371")
					(unit 1)
				)
			)
		)
	)
	(symbol
		(lib_id "antmicroCapacitors0402:C_1u_0402")
		(at 72.39 231.14 90)
		(unit 1)
		(exclude_from_sim no)
		(in_bom yes)
		(on_board yes)
		(dnp no)
		(property "Reference" "C52"
			(at 73.025 226.695 90)
			(effects
				(font
					(size 1.27 1.27)
				)
				(justify right)
			)
		)
		(property "Value" "C_1u_0402"
			(at 82.55 210.82 0)
			(effects
				(font
					(size 1.27 1.27)
					(thickness 0.15)
				)
				(justify left bottom)
				(hide yes)
			)
		)
		(property "Footprint" "antmicro-footprints:C_0402_1005Metric"
			(at 85.09 210.82 0)
			(effects
				(font
					(size 1.27 1.27)
					(thickness 0.15)
				)
				(justify left bottom)
				(hide yes)
			)
		)
		(property "Datasheet" "https://product.tdk.com/en/search/capacitor/ceramic/mlcc/info?part_no=C1005X6S1A105K050BC"
			(at 87.63 210.82 0)
			(effects
				(font
					(size 1.27 1.27)
					(thickness 0.15)
				)
				(justify left bottom)
				(hide yes)
			)
		)
		(property "Description" "SMD Multilayer Ceramic Capacitor, 1 µF, 10 V, 0402 [1005 Metric], ± 10%, X6S, C"
			(at 72.39 231.14 0)
			(effects
				(font
					(size 1.27 1.27)
				)
				(hide yes)
			)
		)
		(property "Manufacturer" "TDK"
			(at 92.71 210.82 0)
			(effects
				(font
					(size 1.27 1.27)
					(thickness 0.15)
				)
				(justify left bottom)
				(hide yes)
			)
		)
		(property "MPN" "C1005X6S1A105K050BC"
			(at 90.17 210.82 0)
			(effects
				(font
					(size 1.27 1.27)
					(thickness 0.15)
				)
				(justify left bottom)
				(hide yes)
			)
		)
		(property "Val" "1u"
			(at 73.025 230.505 90)
			(effects
				(font
					(size 1.27 1.27)
					(thickness 0.15)
				)
				(justify right)
			)
		)
		(property "License" "Apache-2.0"
			(at 95.25 210.82 0)
			(effects
				(font
					(size 1.27 1.27)
					(thickness 0.15)
				)
				(justify left bottom)
				(hide yes)
			)
		)
		(property "Author" "Antmicro"
			(at 97.79 210.82 0)
			(effects
				(font
					(size 1.27 1.27)
					(thickness 0.15)
				)
				(justify left bottom)
				(hide yes)
			)
		)
		(property "Voltage" ""
			(at 100.33 210.82 0)
			(effects
				(font
					(size 1.27 1.27)
				)
				(justify left bottom)
				(hide yes)
			)
		)
		(property "Dielectric" ""
			(at 102.87 210.82 0)
			(effects
				(font
					(size 1.27 1.27)
				)
				(justify left bottom)
				(hide yes)
			)
		)
		(pin "1"
		)
		(pin "2"
		)
		(instances
			(project "jetson-agx-thor-baseboard"
				(path ""
					(reference "C52")
					(unit 1)
				)
			)
		)
	)
	(symbol
		(lib_id "antmicroCapacitors0402:C_100n_0402")
		(at 346.71 193.04 90)
		(unit 1)
		(exclude_from_sim no)
		(in_bom yes)
		(on_board yes)
		(dnp no)
		(fields_autoplaced yes)
		(property "Reference" "C79"
			(at 349.25 189.2235 90)
			(effects
				(font
					(size 1.27 1.27)
					(thickness 0.15)
				)
				(justify right)
			)
		)
		(property "Value" "C_100n_0402"
			(at 356.87 172.72 0)
			(effects
				(font
					(size 1.27 1.27)
					(thickness 0.15)
				)
				(justify left bottom)
				(hide yes)
			)
		)
		(property "Footprint" "antmicro-footprints:C_0402_1005Metric"
			(at 359.41 172.72 0)
			(effects
				(font
					(size 1.27 1.27)
					(thickness 0.15)
				)
				(justify left bottom)
				(hide yes)
			)
		)
		(property "Datasheet" "https://www.murata.com/products/productdetail?partno=GRM155R61H104KE14%23"
			(at 361.95 172.72 0)
			(effects
				(font
					(size 1.27 1.27)
					(thickness 0.15)
				)
				(justify left bottom)
				(hide yes)
			)
		)
		(property "Description" "SMD Multilayer Ceramic Capacitor, 0.1 µF, 50 V, 0402 [1005 Metric], ± 10%, X5R, GRM Series"
			(at 346.71 193.04 0)
			(effects
				(font
					(size 1.27 1.27)
				)
				(hide yes)
			)
		)
		(property "MPN" "GRM155R61H104KE14D"
			(at 364.49 172.72 0)
			(effects
				(font
					(size 1.27 1.27)
					(thickness 0.15)
				)
				(justify left bottom)
				(hide yes)
			)
		)
		(property "Manufacturer" "Murata"
			(at 367.03 172.72 0)
			(effects
				(font
					(size 1.27 1.27)
					(thickness 0.15)
				)
				(justify left bottom)
				(hide yes)
			)
		)
		(property "License" "Apache-2.0"
			(at 369.57 172.72 0)
			(effects
				(font
					(size 1.27 1.27)
					(thickness 0.15)
				)
				(justify left bottom)
				(hide yes)
			)
		)
		(property "Author" "Antmicro"
			(at 372.11 172.72 0)
			(effects
				(font
					(size 1.27 1.27)
					(thickness 0.15)
				)
				(justify left bottom)
				(hide yes)
			)
		)
		(property "Val" "100n"
			(at 349.25 191.7635 90)
			(effects
				(font
					(size 1.27 1.27)
					(thickness 0.15)
				)
				(justify right)
			)
		)
		(property "Voltage" "50V"
			(at 374.65 172.72 0)
			(effects
				(font
					(size 1.27 1.27)
				)
				(justify left bottom)
				(hide yes)
			)
		)
		(property "Dielectric" "X5R"
			(at 377.19 172.72 0)
			(effects
				(font
					(size 1.27 1.27)
				)
				(justify left bottom)
				(hide yes)
			)
		)
		(pin "1"
		)
		(pin "2"
		)
		(instances
			(project "jetson-agx-thor-baseboard"
				(path ""
					(reference "C79")
					(unit 1)
				)
			)
		)
	)
	(symbol
		(lib_id "antmicropower:GND")
		(at 143.51 232.41 0)
		(unit 1)
		(exclude_from_sim no)
		(in_bom yes)
		(on_board yes)
		(dnp no)
		(property "Reference" "#PWR0129"
			(at 143.51 238.76 0)
			(effects
				(font
					(size 1.27 1.27)
				)
				(justify left bottom)
				(hide yes)
			)
		)
		(property "Value" "GND"
			(at 143.51 236.22 0)
			(effects
				(font
					(size 1.27 1.27)
					(thickness 0.15)
				)
			)
		)
		(property "Footprint" ""
			(at 152.4 240.03 0)
			(effects
				(font
					(size 1.27 1.27)
					(thickness 0.15)
				)
				(justify left bottom)
				(hide yes)
			)
		)
		(property "Datasheet" ""
			(at 152.4 245.11 0)
			(effects
				(font
					(size 1.27 1.27)
					(thickness 0.15)
				)
				(justify left bottom)
				(hide yes)
			)
		)
		(property "Description" ""
			(at 143.51 232.41 0)
			(effects
				(font
					(size 1.27 1.27)
				)
				(hide yes)
			)
		)
		(property "Author" "Antmicro"
			(at 152.4 240.03 0)
			(effects
				(font
					(size 1.27 1.27)
					(thickness 0.15)
				)
				(justify left bottom)
				(hide yes)
			)
		)
		(property "License" "Apache-2.0"
			(at 152.4 242.57 0)
			(effects
				(font
					(size 1.27 1.27)
					(thickness 0.15)
				)
				(justify left bottom)
				(hide yes)
			)
		)
		(pin "1"
		)
		(instances
			(project "jetson-agx-thor-baseboard"
				(path ""
					(reference "#PWR0129")
					(unit 1)
				)
			)
		)
	)
	(symbol
		(lib_id "antmicropower:GND")
		(at 27.94 232.41 0)
		(unit 1)
		(exclude_from_sim no)
		(in_bom yes)
		(on_board yes)
		(dnp no)
		(property "Reference" "#PWR0605"
			(at 27.94 238.76 0)
			(effects
				(font
					(size 1.27 1.27)
				)
				(justify left bottom)
				(hide yes)
			)
		)
		(property "Value" "GND"
			(at 27.94 236.22 0)
			(effects
				(font
					(size 1.27 1.27)
					(thickness 0.15)
				)
			)
		)
		(property "Footprint" ""
			(at 36.83 240.03 0)
			(effects
				(font
					(size 1.27 1.27)
					(thickness 0.15)
				)
				(justify left bottom)
				(hide yes)
			)
		)
		(property "Datasheet" ""
			(at 36.83 245.11 0)
			(effects
				(font
					(size 1.27 1.27)
					(thickness 0.15)
				)
				(justify left bottom)
				(hide yes)
			)
		)
		(property "Description" ""
			(at 27.94 232.41 0)
			(effects
				(font
					(size 1.27 1.27)
				)
				(hide yes)
			)
		)
		(property "Author" "Antmicro"
			(at 36.83 240.03 0)
			(effects
				(font
					(size 1.27 1.27)
					(thickness 0.15)
				)
				(justify left bottom)
				(hide yes)
			)
		)
		(property "License" "Apache-2.0"
			(at 36.83 242.57 0)
			(effects
				(font
					(size 1.27 1.27)
					(thickness 0.15)
				)
				(justify left bottom)
				(hide yes)
			)
		)
		(pin "1"
		)
		(instances
			(project "jetson-agx-thor-baseboard"
				(path ""
					(reference "#PWR0605")
					(unit 1)
				)
			)
		)
	)
	(symbol
		(lib_id "antmicroCapacitors0603:C_22u_16V_0603")
		(at 275.59 124.46 90)
		(unit 1)
		(exclude_from_sim no)
		(in_bom yes)
		(on_board yes)
		(dnp no)
		(fields_autoplaced yes)
		(property "Reference" "C32"
			(at 278.13 119.3735 90)
			(effects
				(font
					(size 1.27 1.27)
					(thickness 0.15)
				)
				(justify right)
			)
		)
		(property "Value" "C_22u_16V_0603"
			(at 285.75 104.14 0)
			(effects
				(font
					(size 1.27 1.27)
					(thickness 0.15)
				)
				(justify left bottom)
				(hide yes)
			)
		)
		(property "Footprint" "antmicro-footprints:C_0603_1608Metric_EIA"
			(at 288.29 104.14 0)
			(effects
				(font
					(size 1.27 1.27)
					(thickness 0.15)
				)
				(justify left bottom)
				(hide yes)
			)
		)
		(property "Datasheet" "https://product.samsungsem.com/mlcc/CL10A226MO7JZN.do"
			(at 290.83 104.14 0)
			(effects
				(font
					(size 1.27 1.27)
					(thickness 0.15)
				)
				(justify left bottom)
				(hide yes)
			)
		)
		(property "Description" "SMD Multilayer Ceramic Capacitor"
			(at 275.59 124.46 0)
			(effects
				(font
					(size 1.27 1.27)
				)
				(hide yes)
			)
		)
		(property "MPN" "CL10A226MO7JZNC"
			(at 293.37 104.14 0)
			(effects
				(font
					(size 1.27 1.27)
					(thickness 0.15)
				)
				(justify left bottom)
				(hide yes)
			)
		)
		(property "Manufacturer" "Samsung Electro-Mechanics"
			(at 295.91 104.14 0)
			(effects
				(font
					(size 1.27 1.27)
					(thickness 0.15)
				)
				(justify left bottom)
				(hide yes)
			)
		)
		(property "License" "Apache-2.0"
			(at 298.45 104.14 0)
			(effects
				(font
					(size 1.27 1.27)
					(thickness 0.15)
				)
				(justify left bottom)
				(hide yes)
			)
		)
		(property "Author" "Antmicro"
			(at 300.99 104.14 0)
			(effects
				(font
					(size 1.27 1.27)
					(thickness 0.15)
				)
				(justify left bottom)
				(hide yes)
			)
		)
		(property "Val" "22u"
			(at 278.13 121.9135 90)
			(effects
				(font
					(size 1.27 1.27)
					(thickness 0.15)
				)
				(justify right)
			)
		)
		(property "Voltage" "16V"
			(at 278.13 124.4535 90)
			(effects
				(font
					(size 1.27 1.27)
				)
				(justify right)
				(hide yes)
			)
		)
		(property "Dielectric" ""
			(at 306.07 104.14 0)
			(effects
				(font
					(size 1.27 1.27)
				)
				(justify left bottom)
				(hide yes)
			)
		)
		(property "Public" "False"
			(at 308.61 104.14 0)
			(effects
				(font
					(size 1.27 1.27)
				)
				(justify left bottom)
				(hide yes)
			)
		)
		(pin "2"
		)
		(pin "1"
		)
		(instances
			(project "jetson-agx-thor-baseboard"
				(path ""
					(reference "C32")
					(unit 1)
				)
			)
		)
	)
	(symbol
		(lib_id "antmicropower:GND")
		(at 215.9 280.67 0)
		(unit 1)
		(exclude_from_sim no)
		(in_bom yes)
		(on_board yes)
		(dnp no)
		(property "Reference" "#PWR0528"
			(at 215.9 287.02 0)
			(effects
				(font
					(size 1.27 1.27)
				)
				(justify left bottom)
				(hide yes)
			)
		)
		(property "Value" "GND"
			(at 219.456 282.448 0)
			(effects
				(font
					(size 1.27 1.27)
					(thickness 0.15)
				)
			)
		)
		(property "Footprint" ""
			(at 224.79 288.29 0)
			(effects
				(font
					(size 1.27 1.27)
					(thickness 0.15)
				)
				(justify left bottom)
				(hide yes)
			)
		)
		(property "Datasheet" ""
			(at 224.79 293.37 0)
			(effects
				(font
					(size 1.27 1.27)
					(thickness 0.15)
				)
				(justify left bottom)
				(hide yes)
			)
		)
		(property "Description" ""
			(at 215.9 280.67 0)
			(effects
				(font
					(size 1.27 1.27)
				)
				(hide yes)
			)
		)
		(property "Author" "Antmicro"
			(at 224.79 288.29 0)
			(effects
				(font
					(size 1.27 1.27)
					(thickness 0.15)
				)
				(justify left bottom)
				(hide yes)
			)
		)
		(property "License" "Apache-2.0"
			(at 224.79 290.83 0)
			(effects
				(font
					(size 1.27 1.27)
					(thickness 0.15)
				)
				(justify left bottom)
				(hide yes)
			)
		)
		(pin "1"
		)
		(instances
			(project "jetson-agx-thor-baseboard"
				(path ""
					(reference "#PWR0528")
					(unit 1)
				)
			)
		)
	)
	(symbol
		(lib_id "antmicroCapacitorsmisc:C_22u_25V_0805")
		(at 21.59 224.79 90)
		(unit 1)
		(exclude_from_sim no)
		(in_bom yes)
		(on_board yes)
		(dnp no)
		(property "Reference" "C267"
			(at 22.225 220.345 90)
			(effects
				(font
					(size 1.27 1.27)
					(thickness 0.15)
				)
				(justify right)
			)
		)
		(property "Value" "C_22u_25V_0805"
			(at 31.75 204.47 0)
			(effects
				(font
					(size 1.27 1.27)
					(thickness 0.15)
				)
				(justify left bottom)
				(hide yes)
			)
		)
		(property "Footprint" "antmicro-footprints:C_0805_2012Metric"
			(at 34.29 204.47 0)
			(effects
				(font
					(size 1.27 1.27)
					(thickness 0.15)
				)
				(justify left bottom)
				(hide yes)
			)
		)
		(property "Datasheet" "https://product.samsungsem.com/mlcc/CL21A226MAYNNN.do"
			(at 36.83 204.47 0)
			(effects
				(font
					(size 1.27 1.27)
					(thickness 0.15)
				)
				(justify left bottom)
				(hide yes)
			)
		)
		(property "Description" "SMT Multilayer Ceramic Capacitor, 22uF, +/-20%, 25V, X5R, 0805 [2012 Metric]"
			(at 21.59 224.79 0)
			(effects
				(font
					(size 1.27 1.27)
				)
				(hide yes)
			)
		)
		(property "MPN" "CL21A226MAYNNNE"
			(at 39.37 204.47 0)
			(effects
				(font
					(size 1.27 1.27)
					(thickness 0.15)
				)
				(justify left bottom)
				(hide yes)
			)
		)
		(property "Manufacturer" "Samsung Electro-Mechanics"
			(at 41.91 204.47 0)
			(effects
				(font
					(size 1.27 1.27)
					(thickness 0.15)
				)
				(justify left bottom)
				(hide yes)
			)
		)
		(property "License" "Apache-2.0"
			(at 44.45 204.47 0)
			(effects
				(font
					(size 1.27 1.27)
					(thickness 0.15)
				)
				(justify left bottom)
				(hide yes)
			)
		)
		(property "Author" "Antmicro"
			(at 46.99 204.47 0)
			(effects
				(font
					(size 1.27 1.27)
					(thickness 0.15)
				)
				(justify left bottom)
				(hide yes)
			)
		)
		(property "Val" "22u"
			(at 22.225 224.155 90)
			(effects
				(font
					(size 1.27 1.27)
					(thickness 0.15)
				)
				(justify right)
			)
		)
		(property "Voltage" "25V"
			(at 22.225 226.695 90)
			(effects
				(font
					(size 1.27 1.27)
				)
				(justify right)
			)
		)
		(property "Dielectric" "X5R"
			(at 52.07 204.47 0)
			(effects
				(font
					(size 1.27 1.27)
				)
				(justify left bottom)
				(hide yes)
			)
		)
		(property "Public" "False"
			(at 54.61 204.47 0)
			(effects
				(font
					(size 1.27 1.27)
				)
				(justify left bottom)
				(hide yes)
			)
		)
		(pin "2"
		)
		(pin "1"
		)
		(instances
			(project "jetson-agx-thor-baseboard"
				(path ""
					(reference "C267")
					(unit 1)
				)
			)
		)
	)
	(symbol
		(lib_id "antmicroCapacitorsmisc:C_22u_25V_0805")
		(at 262.89 57.15 90)
		(unit 1)
		(exclude_from_sim no)
		(in_bom yes)
		(on_board yes)
		(dnp no)
		(property "Reference" "C309"
			(at 264.922 52.07 90)
			(effects
				(font
					(size 1.27 1.27)
				)
				(justify right)
			)
		)
		(property "Value" "C_22u_25V_0805"
			(at 273.05 36.83 0)
			(effects
				(font
					(size 1.27 1.27)
					(thickness 0.15)
				)
				(justify left bottom)
				(hide yes)
			)
		)
		(property "Footprint" "antmicro-footprints:C_0805_2012Metric"
			(at 275.59 36.83 0)
			(effects
				(font
					(size 1.27 1.27)
					(thickness 0.15)
				)
				(justify left bottom)
				(hide yes)
			)
		)
		(property "Datasheet" "https://product.samsungsem.com/mlcc/CL21A226MAYNNN.do"
			(at 278.13 36.83 0)
			(effects
				(font
					(size 1.27 1.27)
					(thickness 0.15)
				)
				(justify left bottom)
				(hide yes)
			)
		)
		(property "Description" "SMT Multilayer Ceramic Capacitor, 22uF, +/-20%, 25V, X5R, 0805 [2012 Metric]"
			(at 262.89 57.15 0)
			(effects
				(font
					(size 1.27 1.27)
				)
				(hide yes)
			)
		)
		(property "Manufacturer" "Samsung Electro-Mechanics"
			(at 283.21 36.83 0)
			(effects
				(font
					(size 1.27 1.27)
					(thickness 0.15)
				)
				(justify left bottom)
				(hide yes)
			)
		)
		(property "MPN" "CL21A226MAYNNNE"
			(at 280.67 36.83 0)
			(effects
				(font
					(size 1.27 1.27)
					(thickness 0.15)
				)
				(justify left bottom)
				(hide yes)
			)
		)
		(property "Val" "22u"
			(at 264.922 54.6101 90)
			(effects
				(font
					(size 1.27 1.27)
					(thickness 0.15)
				)
				(justify right)
			)
		)
		(property "License" "Apache-2.0"
			(at 285.75 36.83 0)
			(effects
				(font
					(size 1.27 1.27)
					(thickness 0.15)
				)
				(justify left bottom)
				(hide yes)
			)
		)
		(property "Author" "Antmicro"
			(at 288.29 36.83 0)
			(effects
				(font
					(size 1.27 1.27)
					(thickness 0.15)
				)
				(justify left bottom)
				(hide yes)
			)
		)
		(property "Voltage" "25V"
			(at 264.922 57.15 90)
			(effects
				(font
					(size 1.27 1.27)
				)
				(justify right)
			)
		)
		(property "Dielectric" "X5R"
			(at 293.37 36.83 0)
			(effects
				(font
					(size 1.27 1.27)
				)
				(justify left bottom)
				(hide yes)
			)
		)
		(property "Public" "False"
			(at 295.91 36.83 0)
			(effects
				(font
					(size 1.27 1.27)
				)
				(justify left bottom)
				(hide yes)
			)
		)
		(pin "1"
		)
		(pin "2"
		)
		(instances
			(project "jetson-agx-thor-baseboard"
				(path ""
					(reference "C309")
					(unit 1)
				)
			)
		)
	)
	(symbol
		(lib_id "antmicroCapacitors0402:C_100n_0402")
		(at 129.54 96.52 180)
		(unit 1)
		(exclude_from_sim no)
		(in_bom yes)
		(on_board yes)
		(dnp no)
		(fields_autoplaced yes)
		(property "Reference" "C281"
			(at 126.9936 90.17 0)
			(effects
				(font
					(size 1.27 1.27)
				)
			)
		)
		(property "Value" "C_100n_0402"
			(at 109.22 86.36 0)
			(effects
				(font
					(size 1.27 1.27)
					(thickness 0.15)
				)
				(justify left bottom)
				(hide yes)
			)
		)
		(property "Footprint" "antmicro-footprints:C_0402_1005Metric"
			(at 109.22 83.82 0)
			(effects
				(font
					(size 1.27 1.27)
					(thickness 0.15)
				)
				(justify left bottom)
				(hide yes)
			)
		)
		(property "Datasheet" "https://www.murata.com/products/productdetail?partno=GRM155R61H104KE14%23"
			(at 109.22 81.28 0)
			(effects
				(font
					(size 1.27 1.27)
					(thickness 0.15)
				)
				(justify left bottom)
				(hide yes)
			)
		)
		(property "Description" "SMD Multilayer Ceramic Capacitor, 0.1 µF, 50 V, 0402 [1005 Metric], ± 10%, X5R, GRM Series"
			(at 129.54 96.52 0)
			(effects
				(font
					(size 1.27 1.27)
				)
				(hide yes)
			)
		)
		(property "Manufacturer" "Murata"
			(at 109.22 76.2 0)
			(effects
				(font
					(size 1.27 1.27)
					(thickness 0.15)
				)
				(justify left bottom)
				(hide yes)
			)
		)
		(property "MPN" "GRM155R61H104KE14D"
			(at 109.22 78.74 0)
			(effects
				(font
					(size 1.27 1.27)
					(thickness 0.15)
				)
				(justify left bottom)
				(hide yes)
			)
		)
		(property "Val" "100n"
			(at 126.9936 92.71 0)
			(effects
				(font
					(size 1.27 1.27)
					(thickness 0.15)
				)
			)
		)
		(property "License" "Apache-2.0"
			(at 109.22 73.66 0)
			(effects
				(font
					(size 1.27 1.27)
					(thickness 0.15)
				)
				(justify left bottom)
				(hide yes)
			)
		)
		(property "Author" "Antmicro"
			(at 109.22 71.12 0)
			(effects
				(font
					(size 1.27 1.27)
					(thickness 0.15)
				)
				(justify left bottom)
				(hide yes)
			)
		)
		(property "Voltage" "50V"
			(at 109.22 68.58 0)
			(effects
				(font
					(size 1.27 1.27)
				)
				(justify left bottom)
				(hide yes)
			)
		)
		(property "Dielectric" "X5R"
			(at 109.22 66.04 0)
			(effects
				(font
					(size 1.27 1.27)
				)
				(justify left bottom)
				(hide yes)
			)
		)
		(pin "1"
		)
		(pin "2"
		)
		(instances
			(project "jetson-agx-thor-baseboard"
				(path ""
					(reference "C281")
					(unit 1)
				)
			)
		)
	)
	(symbol
		(lib_id "antmicropower:VCC")
		(at 21.59 252.73 0)
		(unit 1)
		(exclude_from_sim no)
		(in_bom yes)
		(on_board yes)
		(dnp no)
		(property "Reference" "#PWR0101"
			(at 21.59 256.54 0)
			(effects
				(font
					(size 1.27 1.27)
				)
				(justify left bottom)
				(hide yes)
			)
		)
		(property "Value" "VCC"
			(at 19.685 248.92 0)
			(effects
				(font
					(size 1.27 1.27)
				)
				(justify left)
			)
		)
		(property "Footprint" ""
			(at 21.59 252.73 0)
			(effects
				(font
					(size 1.27 1.27)
				)
				(hide yes)
			)
		)
		(property "Datasheet" ""
			(at 21.59 252.73 0)
			(effects
				(font
					(size 1.27 1.27)
				)
				(hide yes)
			)
		)
		(property "Description" ""
			(at 21.59 252.73 0)
			(effects
				(font
					(size 1.27 1.27)
				)
				(hide yes)
			)
		)
		(pin "1"
		)
		(instances
			(project "jetson-agx-thor-baseboard"
				(path ""
					(reference "#PWR0101")
					(unit 1)
				)
			)
		)
	)
	(symbol
		(lib_id "antmicroCapacitors0402:C_1u_0402")
		(at 72.39 54.61 90)
		(unit 1)
		(exclude_from_sim no)
		(in_bom yes)
		(on_board yes)
		(dnp no)
		(property "Reference" "C244"
			(at 73.025 50.165 90)
			(effects
				(font
					(size 1.27 1.27)
				)
				(justify right)
			)
		)
		(property "Value" "C_1u_0402"
			(at 82.55 34.29 0)
			(effects
				(font
					(size 1.27 1.27)
					(thickness 0.15)
				)
				(justify left bottom)
				(hide yes)
			)
		)
		(property "Footprint" "antmicro-footprints:C_0402_1005Metric"
			(at 85.09 34.29 0)
			(effects
				(font
					(size 1.27 1.27)
					(thickness 0.15)
				)
				(justify left bottom)
				(hide yes)
			)
		)
		(property "Datasheet" "https://product.tdk.com/en/search/capacitor/ceramic/mlcc/info?part_no=C1005X6S1A105K050BC"
			(at 87.63 34.29 0)
			(effects
				(font
					(size 1.27 1.27)
					(thickness 0.15)
				)
				(justify left bottom)
				(hide yes)
			)
		)
		(property "Description" "SMD Multilayer Ceramic Capacitor, 1 µF, 10 V, 0402 [1005 Metric], ± 10%, X6S, C"
			(at 72.39 54.61 0)
			(effects
				(font
					(size 1.27 1.27)
				)
				(hide yes)
			)
		)
		(property "Manufacturer" "TDK"
			(at 92.71 34.29 0)
			(effects
				(font
					(size 1.27 1.27)
					(thickness 0.15)
				)
				(justify left bottom)
				(hide yes)
			)
		)
		(property "MPN" "C1005X6S1A105K050BC"
			(at 90.17 34.29 0)
			(effects
				(font
					(size 1.27 1.27)
					(thickness 0.15)
				)
				(justify left bottom)
				(hide yes)
			)
		)
		(property "Val" "1u"
			(at 73.025 53.975 90)
			(effects
				(font
					(size 1.27 1.27)
					(thickness 0.15)
				)
				(justify right)
			)
		)
		(property "License" "Apache-2.0"
			(at 95.25 34.29 0)
			(effects
				(font
					(size 1.27 1.27)
					(thickness 0.15)
				)
				(justify left bottom)
				(hide yes)
			)
		)
		(property "Author" "Antmicro"
			(at 97.79 34.29 0)
			(effects
				(font
					(size 1.27 1.27)
					(thickness 0.15)
				)
				(justify left bottom)
				(hide yes)
			)
		)
		(property "Voltage" ""
			(at 100.33 34.29 0)
			(effects
				(font
					(size 1.27 1.27)
				)
				(justify left bottom)
				(hide yes)
			)
		)
		(property "Dielectric" ""
			(at 102.87 34.29 0)
			(effects
				(font
					(size 1.27 1.27)
				)
				(justify left bottom)
				(hide yes)
			)
		)
		(pin "1"
		)
		(pin "2"
		)
		(instances
			(project "jetson-agx-thor-baseboard"
				(path ""
					(reference "C244")
					(unit 1)
				)
			)
		)
	)
	(symbol
		(lib_id "antmicropower:GND")
		(at 275.59 128.27 0)
		(unit 1)
		(exclude_from_sim no)
		(in_bom yes)
		(on_board yes)
		(dnp no)
		(property "Reference" "#PWR0621"
			(at 284.48 130.81 0)
			(effects
				(font
					(size 1.27 1.27)
					(thickness 0.15)
				)
				(justify left bottom)
				(hide yes)
			)
		)
		(property "Value" "GND"
			(at 275.59 132.08 0)
			(effects
				(font
					(size 1.27 1.27)
					(thickness 0.15)
				)
			)
		)
		(property "Footprint" ""
			(at 284.48 135.89 0)
			(effects
				(font
					(size 1.27 1.27)
					(thickness 0.15)
				)
				(justify left bottom)
				(hide yes)
			)
		)
		(property "Datasheet" ""
			(at 284.48 140.97 0)
			(effects
				(font
					(size 1.27 1.27)
					(thickness 0.15)
				)
				(justify left bottom)
				(hide yes)
			)
		)
		(property "Description" ""
			(at 275.59 128.27 0)
			(effects
				(font
					(size 1.27 1.27)
				)
				(hide yes)
			)
		)
		(property "Author" "Antmicro"
			(at 284.48 135.89 0)
			(effects
				(font
					(size 1.27 1.27)
					(thickness 0.15)
				)
				(justify left bottom)
				(hide yes)
			)
		)
		(property "License" "Apache-2.0"
			(at 284.48 138.43 0)
			(effects
				(font
					(size 1.27 1.27)
					(thickness 0.15)
				)
				(justify left bottom)
				(hide yes)
			)
		)
		(pin "1"
		)
		(instances
			(project "jetson-agx-thor-baseboard"
				(path ""
					(reference "#PWR0621")
					(unit 1)
				)
			)
		)
	)
	(symbol
		(lib_id "antmicroCapacitorsmisc:C_22u_25V_0805")
		(at 170.18 73.66 90)
		(unit 1)
		(exclude_from_sim no)
		(in_bom yes)
		(on_board yes)
		(dnp no)
		(property "Reference" "C290"
			(at 171.704 68.5801 90)
			(effects
				(font
					(size 1.27 1.27)
					(thickness 0.15)
				)
				(justify right)
			)
		)
		(property "Value" "C_22u_25V_0805"
			(at 180.34 53.34 0)
			(effects
				(font
					(size 1.27 1.27)
					(thickness 0.15)
				)
				(justify left bottom)
				(hide yes)
			)
		)
		(property "Footprint" "antmicro-footprints:C_0805_2012Metric"
			(at 182.88 53.34 0)
			(effects
				(font
					(size 1.27 1.27)
					(thickness 0.15)
				)
				(justify left bottom)
				(hide yes)
			)
		)
		(property "Datasheet" "https://product.samsungsem.com/mlcc/CL21A226MAYNNN.do"
			(at 185.42 53.34 0)
			(effects
				(font
					(size 1.27 1.27)
					(thickness 0.15)
				)
				(justify left bottom)
				(hide yes)
			)
		)
		(property "Description" "SMT Multilayer Ceramic Capacitor, 22uF, +/-20%, 25V, X5R, 0805 [2012 Metric]"
			(at 203.2 53.34 0)
			(effects
				(font
					(size 1.27 1.27)
				)
				(justify left bottom)
				(hide yes)
			)
		)
		(property "MPN" "CL21A226MAYNNNE"
			(at 187.96 53.34 0)
			(effects
				(font
					(size 1.27 1.27)
					(thickness 0.15)
				)
				(justify left bottom)
				(hide yes)
			)
		)
		(property "Manufacturer" "Samsung Electro-Mechanics"
			(at 190.5 53.34 0)
			(effects
				(font
					(size 1.27 1.27)
					(thickness 0.15)
				)
				(justify left bottom)
				(hide yes)
			)
		)
		(property "License" "Apache-2.0"
			(at 193.04 53.34 0)
			(effects
				(font
					(size 1.27 1.27)
					(thickness 0.15)
				)
				(justify left bottom)
				(hide yes)
			)
		)
		(property "Author" "Antmicro"
			(at 195.58 53.34 0)
			(effects
				(font
					(size 1.27 1.27)
					(thickness 0.15)
				)
				(justify left bottom)
				(hide yes)
			)
		)
		(property "Val" "22u"
			(at 171.704 71.1201 90)
			(effects
				(font
					(size 1.27 1.27)
					(thickness 0.15)
				)
				(justify right)
			)
		)
		(property "Voltage" "25V"
			(at 171.704 73.66 90)
			(effects
				(font
					(size 1.27 1.27)
				)
				(justify right)
			)
		)
		(property "Dielectric" "X5R"
			(at 200.66 53.34 0)
			(effects
				(font
					(size 1.27 1.27)
				)
				(justify left bottom)
				(hide yes)
			)
		)
		(property "Public" "False"
			(at 203.2 53.34 0)
			(effects
				(font
					(size 1.27 1.27)
				)
				(justify left bottom)
				(hide yes)
			)
		)
		(pin "2"
		)
		(pin "1"
		)
		(instances
			(project "jetson-agx-thor-baseboard"
				(path ""
					(reference "C290")
					(unit 1)
				)
			)
		)
	)
	(symbol
		(lib_id "antmicroResistorsmisc:R_0R001_0805")
		(at 209.55 101.6 0)
		(unit 1)
		(exclude_from_sim no)
		(in_bom yes)
		(on_board yes)
		(dnp no)
		(property "Reference" "R284"
			(at 212.09 96.52 0)
			(effects
				(font
					(size 1.27 1.27)
					(thickness 0.15)
				)
			)
		)
		(property "Value" "R_0R001_0805"
			(at 229.87 114.3 0)
			(effects
				(font
					(size 1.27 1.27)
					(thickness 0.15)
				)
				(justify left bottom)
				(hide yes)
			)
		)
		(property "Footprint" "antmicro-footprints:R_0805_2012Metric"
			(at 229.87 116.84 0)
			(effects
				(font
					(size 1.27 1.27)
					(thickness 0.15)
				)
				(justify left bottom)
				(hide yes)
			)
		)
		(property "Datasheet" "https://www.eaton.com/content/dam/eaton/products/electronic-components/resources/data-sheet/eaton-msma-automotive-smd-current-sense-resistor-metal-strip-data-sheet-elx1179.pdf"
			(at 229.87 119.38 0)
			(effects
				(font
					(size 1.27 1.27)
					(thickness 0.15)
				)
				(justify left bottom)
				(hide yes)
			)
		)
		(property "Description" "Current Sense Resistors - SMD MSMA, 0805 SIZE, 1/2 Watt, 1 mohm, 50 TCR MnCu Metal AEC-Q"
			(at 209.55 101.6 0)
			(effects
				(font
					(size 1.27 1.27)
				)
				(hide yes)
			)
		)
		(property "MPN" "MSMA0805R0010FSM"
			(at 229.87 121.92 0)
			(effects
				(font
					(size 1.27 1.27)
					(thickness 0.15)
				)
				(justify left bottom)
				(hide yes)
			)
		)
		(property "Manufacturer" "Eaton"
			(at 229.87 124.46 0)
			(effects
				(font
					(size 1.27 1.27)
					(thickness 0.15)
				)
				(justify left bottom)
				(hide yes)
			)
		)
		(property "License" "Apache-2.0"
			(at 229.87 127 0)
			(effects
				(font
					(size 1.27 1.27)
					(thickness 0.15)
				)
				(justify left bottom)
				(hide yes)
			)
		)
		(property "Author" "Antmicro"
			(at 229.87 129.54 0)
			(effects
				(font
					(size 1.27 1.27)
					(thickness 0.15)
				)
				(justify left bottom)
				(hide yes)
			)
		)
		(property "Val" "0R001"
			(at 212.09 99.06 0)
			(effects
				(font
					(size 1.27 1.27)
					(thickness 0.15)
				)
			)
		)
		(property "Tolerance" "1%"
			(at 229.87 111.76 0)
			(effects
				(font
					(size 1.27 1.27)
				)
				(justify left bottom)
				(hide yes)
			)
		)
		(property "Public" "False"
			(at 229.87 132.08 0)
			(effects
				(font
					(size 1.27 1.27)
				)
				(justify left bottom)
				(hide yes)
			)
		)
		(pin "2"
		)
		(pin "1"
		)
		(instances
			(project "jetson-agx-thor-baseboard"
				(path ""
					(reference "R284")
					(unit 1)
				)
			)
		)
	)
	(symbol
		(lib_id "antmicropower:GND")
		(at 365.76 130.81 0)
		(unit 1)
		(exclude_from_sim no)
		(in_bom yes)
		(on_board yes)
		(dnp no)
		(property "Reference" "#PWR0626"
			(at 374.65 133.35 0)
			(effects
				(font
					(size 1.27 1.27)
					(thickness 0.15)
				)
				(justify left bottom)
				(hide yes)
			)
		)
		(property "Value" "GND"
			(at 365.76 134.62 0)
			(effects
				(font
					(size 1.27 1.27)
					(thickness 0.15)
				)
			)
		)
		(property "Footprint" ""
			(at 374.65 138.43 0)
			(effects
				(font
					(size 1.27 1.27)
					(thickness 0.15)
				)
				(justify left bottom)
				(hide yes)
			)
		)
		(property "Datasheet" ""
			(at 374.65 143.51 0)
			(effects
				(font
					(size 1.27 1.27)
					(thickness 0.15)
				)
				(justify left bottom)
				(hide yes)
			)
		)
		(property "Description" ""
			(at 365.76 130.81 0)
			(effects
				(font
					(size 1.27 1.27)
				)
				(hide yes)
			)
		)
		(property "Author" "Antmicro"
			(at 374.65 138.43 0)
			(effects
				(font
					(size 1.27 1.27)
					(thickness 0.15)
				)
				(justify left bottom)
				(hide yes)
			)
		)
		(property "License" "Apache-2.0"
			(at 374.65 140.97 0)
			(effects
				(font
					(size 1.27 1.27)
					(thickness 0.15)
				)
				(justify left bottom)
				(hide yes)
			)
		)
		(pin "1"
		)
		(instances
			(project "jetson-agx-thor-baseboard"
				(path ""
					(reference "#PWR0626")
					(unit 1)
				)
			)
		)
	)
	(symbol
		(lib_id "antmicroCapacitors0603:C_22u_16V_0603")
		(at 177.8 273.05 90)
		(unit 1)
		(exclude_from_sim no)
		(in_bom yes)
		(on_board yes)
		(dnp no)
		(property "Reference" "C73"
			(at 178.435 268.605 90)
			(effects
				(font
					(size 1.27 1.27)
				)
				(justify right)
			)
		)
		(property "Value" "C_22u_16V_0603"
			(at 187.96 252.73 0)
			(effects
				(font
					(size 1.27 1.27)
					(thickness 0.15)
				)
				(justify left bottom)
				(hide yes)
			)
		)
		(property "Footprint" "antmicro-footprints:C_0603_1608Metric_EIA"
			(at 190.5 252.73 0)
			(effects
				(font
					(size 1.27 1.27)
					(thickness 0.15)
				)
				(justify left bottom)
				(hide yes)
			)
		)
		(property "Datasheet" "https://product.samsungsem.com/mlcc/CL10A226MO7JZN.do"
			(at 193.04 252.73 0)
			(effects
				(font
					(size 1.27 1.27)
					(thickness 0.15)
				)
				(justify left bottom)
				(hide yes)
			)
		)
		(property "Description" "SMD Multilayer Ceramic Capacitor"
			(at 177.8 273.05 0)
			(effects
				(font
					(size 1.27 1.27)
				)
				(hide yes)
			)
		)
		(property "Manufacturer" "Samsung Electro-Mechanics"
			(at 198.12 252.73 0)
			(effects
				(font
					(size 1.27 1.27)
					(thickness 0.15)
				)
				(justify left bottom)
				(hide yes)
			)
		)
		(property "MPN" "CL10A226MO7JZNC"
			(at 195.58 252.73 0)
			(effects
				(font
					(size 1.27 1.27)
					(thickness 0.15)
				)
				(justify left bottom)
				(hide yes)
			)
		)
		(property "Val" "22u"
			(at 178.435 272.415 90)
			(effects
				(font
					(size 1.27 1.27)
					(thickness 0.15)
				)
				(justify right)
			)
		)
		(property "License" "Apache-2.0"
			(at 200.66 252.73 0)
			(effects
				(font
					(size 1.27 1.27)
					(thickness 0.15)
				)
				(justify left bottom)
				(hide yes)
			)
		)
		(property "Author" "Antmicro"
			(at 203.2 252.73 0)
			(effects
				(font
					(size 1.27 1.27)
					(thickness 0.15)
				)
				(justify left bottom)
				(hide yes)
			)
		)
		(property "Voltage" "16V"
			(at 205.74 252.73 0)
			(effects
				(font
					(size 1.27 1.27)
				)
				(justify left bottom)
				(hide yes)
			)
		)
		(property "Dielectric" ""
			(at 208.28 252.73 0)
			(effects
				(font
					(size 1.27 1.27)
				)
				(justify left bottom)
				(hide yes)
			)
		)
		(pin "1"
		)
		(pin "2"
		)
		(instances
			(project "jetson-agx-thor-baseboard"
				(path ""
					(reference "C73")
					(unit 1)
				)
			)
		)
	)
	(symbol
		(lib_id "antmicroCapacitorsmisc:C_22u_25V_0805")
		(at 170.18 58.42 90)
		(unit 1)
		(exclude_from_sim no)
		(in_bom yes)
		(on_board yes)
		(dnp no)
		(property "Reference" "C259"
			(at 171.704 53.3401 90)
			(effects
				(font
					(size 1.27 1.27)
					(thickness 0.15)
				)
				(justify right)
			)
		)
		(property "Value" "C_22u_25V_0805"
			(at 180.34 38.1 0)
			(effects
				(font
					(size 1.27 1.27)
					(thickness 0.15)
				)
				(justify left bottom)
				(hide yes)
			)
		)
		(property "Footprint" "antmicro-footprints:C_0805_2012Metric"
			(at 182.88 38.1 0)
			(effects
				(font
					(size 1.27 1.27)
					(thickness 0.15)
				)
				(justify left bottom)
				(hide yes)
			)
		)
		(property "Datasheet" "https://product.samsungsem.com/mlcc/CL21A226MAYNNN.do"
			(at 185.42 38.1 0)
			(effects
				(font
					(size 1.27 1.27)
					(thickness 0.15)
				)
				(justify left bottom)
				(hide yes)
			)
		)
		(property "Description" "SMT Multilayer Ceramic Capacitor, 22uF, +/-20%, 25V, X5R, 0805 [2012 Metric]"
			(at 203.2 38.1 0)
			(effects
				(font
					(size 1.27 1.27)
				)
				(justify left bottom)
				(hide yes)
			)
		)
		(property "MPN" "CL21A226MAYNNNE"
			(at 187.96 38.1 0)
			(effects
				(font
					(size 1.27 1.27)
					(thickness 0.15)
				)
				(justify left bottom)
				(hide yes)
			)
		)
		(property "Manufacturer" "Samsung Electro-Mechanics"
			(at 190.5 38.1 0)
			(effects
				(font
					(size 1.27 1.27)
					(thickness 0.15)
				)
				(justify left bottom)
				(hide yes)
			)
		)
		(property "License" "Apache-2.0"
			(at 193.04 38.1 0)
			(effects
				(font
					(size 1.27 1.27)
					(thickness 0.15)
				)
				(justify left bottom)
				(hide yes)
			)
		)
		(property "Author" "Antmicro"
			(at 195.58 38.1 0)
			(effects
				(font
					(size 1.27 1.27)
					(thickness 0.15)
				)
				(justify left bottom)
				(hide yes)
			)
		)
		(property "Val" "22u"
			(at 171.704 55.8801 90)
			(effects
				(font
					(size 1.27 1.27)
					(thickness 0.15)
				)
				(justify right)
			)
		)
		(property "Voltage" "25V"
			(at 171.704 58.42 90)
			(effects
				(font
					(size 1.27 1.27)
				)
				(justify right)
			)
		)
		(property "Dielectric" "X5R"
			(at 200.66 38.1 0)
			(effects
				(font
					(size 1.27 1.27)
				)
				(justify left bottom)
				(hide yes)
			)
		)
		(property "Public" "False"
			(at 203.2 38.1 0)
			(effects
				(font
					(size 1.27 1.27)
				)
				(justify left bottom)
				(hide yes)
			)
		)
		(pin "2"
		)
		(pin "1"
		)
		(instances
			(project "jetson-agx-thor-baseboard"
				(path ""
					(reference "C259")
					(unit 1)
				)
			)
		)
	)
	(symbol
		(lib_id "antmicroCapacitors0603:C_22u_16V_0603")
		(at 355.6 121.92 270)
		(unit 1)
		(exclude_from_sim no)
		(in_bom yes)
		(on_board yes)
		(dnp no)
		(fields_autoplaced yes)
		(property "Reference" "C305"
			(at 358.14 123.1963 90)
			(effects
				(font
					(size 1.27 1.27)
					(thickness 0.15)
				)
				(justify left)
			)
		)
		(property "Value" "C_22u_16V_0603"
			(at 353.06 135.89 0)
			(effects
				(font
					(size 1.27 1.27)
					(thickness 0.15)
				)
				(justify left bottom)
				(hide yes)
			)
		)
		(property "Footprint" "antmicro-footprints:C_0603_1608Metric_EIA"
			(at 347.98 135.89 0)
			(effects
				(font
					(size 1.27 1.27)
					(thickness 0.15)
				)
				(justify left bottom)
				(hide yes)
			)
		)
		(property "Datasheet" "https://product.samsungsem.com/mlcc/CL10A226MO7JZN.do"
			(at 345.44 135.89 0)
			(effects
				(font
					(size 1.27 1.27)
					(thickness 0.15)
				)
				(justify left bottom)
				(hide yes)
			)
		)
		(property "Description" "SMD Multilayer Ceramic Capacitor"
			(at 355.6 121.92 0)
			(effects
				(font
					(size 1.27 1.27)
				)
				(hide yes)
			)
		)
		(property "Val" "22u"
			(at 358.14 125.7363 90)
			(effects
				(font
					(size 1.27 1.27)
					(thickness 0.15)
				)
				(justify left)
			)
		)
		(property "MPN" "CL10A226MO7JZNC"
			(at 342.9 135.89 0)
			(effects
				(font
					(size 1.27 1.27)
					(thickness 0.15)
				)
				(justify left bottom)
				(hide yes)
			)
		)
		(property "Manufacturer" "Samsung Electro-Mechanics"
			(at 340.36 135.89 0)
			(effects
				(font
					(size 1.27 1.27)
					(thickness 0.15)
				)
				(justify left bottom)
				(hide yes)
			)
		)
		(property "License" "Apache-2.0"
			(at 337.82 135.89 0)
			(effects
				(font
					(size 1.27 1.27)
					(thickness 0.15)
				)
				(justify left bottom)
				(hide yes)
			)
		)
		(property "Author" "Antmicro"
			(at 335.28 135.89 0)
			(effects
				(font
					(size 1.27 1.27)
					(thickness 0.15)
				)
				(justify left bottom)
				(hide yes)
			)
		)
		(property "Voltage" "16V"
			(at 358.14 126.4665 90)
			(effects
				(font
					(size 1.27 1.27)
				)
				(justify left)
				(hide yes)
			)
		)
		(property "Dielectric" ""
			(at 330.2 135.89 0)
			(effects
				(font
					(size 1.27 1.27)
				)
				(justify left bottom)
				(hide yes)
			)
		)
		(pin "2"
		)
		(pin "1"
		)
		(instances
			(project "jetson-agx-thor-baseboard"
				(path ""
					(reference "C305")
					(unit 1)
				)
			)
		)
	)
	(symbol
		(lib_id "antmicropower:GND")
		(at 275.59 194.31 0)
		(unit 1)
		(exclude_from_sim no)
		(in_bom yes)
		(on_board yes)
		(dnp no)
		(property "Reference" "#PWR052"
			(at 284.48 196.85 0)
			(effects
				(font
					(size 1.27 1.27)
					(thickness 0.15)
				)
				(justify left bottom)
				(hide yes)
			)
		)
		(property "Value" "GND"
			(at 275.59 198.12 0)
			(effects
				(font
					(size 1.27 1.27)
					(thickness 0.15)
				)
			)
		)
		(property "Footprint" ""
			(at 284.48 201.93 0)
			(effects
				(font
					(size 1.27 1.27)
					(thickness 0.15)
				)
				(justify left bottom)
				(hide yes)
			)
		)
		(property "Datasheet" ""
			(at 284.48 207.01 0)
			(effects
				(font
					(size 1.27 1.27)
					(thickness 0.15)
				)
				(justify left bottom)
				(hide yes)
			)
		)
		(property "Description" ""
			(at 275.59 194.31 0)
			(effects
				(font
					(size 1.27 1.27)
				)
				(hide yes)
			)
		)
		(property "Author" "Antmicro"
			(at 284.48 201.93 0)
			(effects
				(font
					(size 1.27 1.27)
					(thickness 0.15)
				)
				(justify left bottom)
				(hide yes)
			)
		)
		(property "License" "Apache-2.0"
			(at 284.48 204.47 0)
			(effects
				(font
					(size 1.27 1.27)
					(thickness 0.15)
				)
				(justify left bottom)
				(hide yes)
			)
		)
		(pin "1"
		)
		(instances
			(project "jetson-agx-thor-baseboard"
				(path ""
					(reference "#PWR052")
					(unit 1)
				)
			)
		)
	)
	(symbol
		(lib_id "antmicroResistors0402:R_330k_0402")
		(at 143.51 107.95 90)
		(unit 1)
		(exclude_from_sim no)
		(in_bom yes)
		(on_board yes)
		(dnp no)
		(property "Reference" "R94"
			(at 145.034 104.14 90)
			(effects
				(font
					(size 1.27 1.27)
					(thickness 0.15)
				)
				(justify right)
			)
		)
		(property "Value" "R_330k_0402"
			(at 156.21 87.63 0)
			(effects
				(font
					(size 1.27 1.27)
					(thickness 0.15)
				)
				(justify left bottom)
				(hide yes)
			)
		)
		(property "Footprint" "antmicro-footprints:R_0402_1005Metric"
			(at 158.75 87.63 0)
			(effects
				(font
					(size 1.27 1.27)
					(thickness 0.15)
				)
				(justify left bottom)
				(hide yes)
			)
		)
		(property "Datasheet" "https://www.bourns.com/docs/product-datasheets/cr.pdf"
			(at 161.29 87.63 0)
			(effects
				(font
					(size 1.27 1.27)
					(thickness 0.15)
				)
				(justify left bottom)
				(hide yes)
			)
		)
		(property "Description" "SMD Chip Resistor"
			(at 173.99 87.63 0)
			(effects
				(font
					(size 1.27 1.27)
				)
				(justify left bottom)
				(hide yes)
			)
		)
		(property "MPN" "CR0402-FX-3303GLF"
			(at 163.83 87.63 0)
			(effects
				(font
					(size 1.27 1.27)
					(thickness 0.15)
				)
				(justify left bottom)
				(hide yes)
			)
		)
		(property "Manufacturer" "Bourns"
			(at 166.37 87.63 0)
			(effects
				(font
					(size 1.27 1.27)
					(thickness 0.15)
				)
				(justify left bottom)
				(hide yes)
			)
		)
		(property "License" "Apache-2.0"
			(at 168.91 87.63 0)
			(effects
				(font
					(size 1.27 1.27)
					(thickness 0.15)
				)
				(justify left bottom)
				(hide yes)
			)
		)
		(property "Author" "Antmicro"
			(at 171.45 87.63 0)
			(effects
				(font
					(size 1.27 1.27)
					(thickness 0.15)
				)
				(justify left bottom)
				(hide yes)
			)
		)
		(property "Val" "330k"
			(at 145.034 106.68 90)
			(effects
				(font
					(size 1.27 1.27)
					(thickness 0.15)
				)
				(justify right)
			)
		)
		(property "Tolerance" "1%"
			(at 153.67 87.63 0)
			(effects
				(font
					(size 1.27 1.27)
				)
				(justify left bottom)
				(hide yes)
			)
		)
		(pin "2"
		)
		(pin "1"
		)
		(instances
			(project "jetson-agx-thor-baseboard"
				(path ""
					(reference "R94")
					(unit 1)
				)
			)
		)
	)
	(symbol
		(lib_id "antmicropower:GND")
		(at 162.56 44.45 0)
		(unit 1)
		(exclude_from_sim no)
		(in_bom yes)
		(on_board yes)
		(dnp no)
		(property "Reference" "#PWR0535"
			(at 162.56 50.8 0)
			(effects
				(font
					(size 1.27 1.27)
				)
				(justify left bottom)
				(hide yes)
			)
		)
		(property "Value" "GND"
			(at 162.56 48.26 0)
			(effects
				(font
					(size 1.27 1.27)
					(thickness 0.15)
				)
			)
		)
		(property "Footprint" ""
			(at 171.45 52.07 0)
			(effects
				(font
					(size 1.27 1.27)
					(thickness 0.15)
				)
				(justify left bottom)
				(hide yes)
			)
		)
		(property "Datasheet" ""
			(at 171.45 57.15 0)
			(effects
				(font
					(size 1.27 1.27)
					(thickness 0.15)
				)
				(justify left bottom)
				(hide yes)
			)
		)
		(property "Description" ""
			(at 162.56 44.45 0)
			(effects
				(font
					(size 1.27 1.27)
				)
				(hide yes)
			)
		)
		(property "Author" "Antmicro"
			(at 171.45 52.07 0)
			(effects
				(font
					(size 1.27 1.27)
					(thickness 0.15)
				)
				(justify left bottom)
				(hide yes)
			)
		)
		(property "License" "Apache-2.0"
			(at 171.45 54.61 0)
			(effects
				(font
					(size 1.27 1.27)
					(thickness 0.15)
				)
				(justify left bottom)
				(hide yes)
			)
		)
		(pin "1"
		)
		(instances
			(project "jetson-agx-thor-baseboard"
				(path ""
					(reference "#PWR0535")
					(unit 1)
				)
			)
		)
	)
	(symbol
		(lib_id "antmicroCapacitorsmisc:C_22u_25V_0805")
		(at 40.64 105.41 90)
		(unit 1)
		(exclude_from_sim no)
		(in_bom yes)
		(on_board yes)
		(dnp no)
		(property "Reference" "C277"
			(at 41.275 100.965 90)
			(effects
				(font
					(size 1.27 1.27)
					(thickness 0.15)
				)
				(justify right)
			)
		)
		(property "Value" "C_22u_25V_0805"
			(at 50.8 85.09 0)
			(effects
				(font
					(size 1.27 1.27)
					(thickness 0.15)
				)
				(justify left bottom)
				(hide yes)
			)
		)
		(property "Footprint" "antmicro-footprints:C_0805_2012Metric"
			(at 53.34 85.09 0)
			(effects
				(font
					(size 1.27 1.27)
					(thickness 0.15)
				)
				(justify left bottom)
				(hide yes)
			)
		)
		(property "Datasheet" "https://product.samsungsem.com/mlcc/CL21A226MAYNNN.do"
			(at 55.88 85.09 0)
			(effects
				(font
					(size 1.27 1.27)
					(thickness 0.15)
				)
				(justify left bottom)
				(hide yes)
			)
		)
		(property "Description" "SMT Multilayer Ceramic Capacitor, 22uF, +/-20%, 25V, X5R, 0805 [2012 Metric]"
			(at 40.64 105.41 0)
			(effects
				(font
					(size 1.27 1.27)
				)
				(hide yes)
			)
		)
		(property "MPN" "CL21A226MAYNNNE"
			(at 58.42 85.09 0)
			(effects
				(font
					(size 1.27 1.27)
					(thickness 0.15)
				)
				(justify left bottom)
				(hide yes)
			)
		)
		(property "Manufacturer" "Samsung Electro-Mechanics"
			(at 60.96 85.09 0)
			(effects
				(font
					(size 1.27 1.27)
					(thickness 0.15)
				)
				(justify left bottom)
				(hide yes)
			)
		)
		(property "License" "Apache-2.0"
			(at 63.5 85.09 0)
			(effects
				(font
					(size 1.27 1.27)
					(thickness 0.15)
				)
				(justify left bottom)
				(hide yes)
			)
		)
		(property "Author" "Antmicro"
			(at 66.04 85.09 0)
			(effects
				(font
					(size 1.27 1.27)
					(thickness 0.15)
				)
				(justify left bottom)
				(hide yes)
			)
		)
		(property "Val" "22u"
			(at 41.275 104.775 90)
			(effects
				(font
					(size 1.27 1.27)
					(thickness 0.15)
				)
				(justify right)
			)
		)
		(property "Voltage" "25V"
			(at 41.275 107.315 90)
			(effects
				(font
					(size 1.27 1.27)
				)
				(justify right)
			)
		)
		(property "Dielectric" "X5R"
			(at 71.12 85.09 0)
			(effects
				(font
					(size 1.27 1.27)
				)
				(justify left bottom)
				(hide yes)
			)
		)
		(property "Public" "False"
			(at 73.66 85.09 0)
			(effects
				(font
					(size 1.27 1.27)
				)
				(justify left bottom)
				(hide yes)
			)
		)
		(pin "1"
		)
		(pin "2"
		)
		(instances
			(project "jetson-agx-thor-baseboard"
				(path ""
					(reference "C277")
					(unit 1)
				)
			)
		)
	)
	(symbol
		(lib_id "antmicropower:GND")
		(at 185.42 110.49 0)
		(unit 1)
		(exclude_from_sim no)
		(in_bom yes)
		(on_board yes)
		(dnp no)
		(property "Reference" "#PWR0586"
			(at 185.42 116.84 0)
			(effects
				(font
					(size 1.27 1.27)
				)
				(justify left bottom)
				(hide yes)
			)
		)
		(property "Value" "GND"
			(at 185.42 114.3 0)
			(effects
				(font
					(size 1.27 1.27)
					(thickness 0.15)
				)
			)
		)
		(property "Footprint" ""
			(at 194.31 118.11 0)
			(effects
				(font
					(size 1.27 1.27)
					(thickness 0.15)
				)
				(justify left bottom)
				(hide yes)
			)
		)
		(property "Datasheet" ""
			(at 194.31 123.19 0)
			(effects
				(font
					(size 1.27 1.27)
					(thickness 0.15)
				)
				(justify left bottom)
				(hide yes)
			)
		)
		(property "Description" ""
			(at 185.42 110.49 0)
			(effects
				(font
					(size 1.27 1.27)
				)
				(hide yes)
			)
		)
		(property "Author" "Antmicro"
			(at 194.31 118.11 0)
			(effects
				(font
					(size 1.27 1.27)
					(thickness 0.15)
				)
				(justify left bottom)
				(hide yes)
			)
		)
		(property "License" "Apache-2.0"
			(at 194.31 120.65 0)
			(effects
				(font
					(size 1.27 1.27)
					(thickness 0.15)
				)
				(justify left bottom)
				(hide yes)
			)
		)
		(pin "1"
		)
		(instances
			(project "jetson-agx-thor-baseboard"
				(path ""
					(reference "#PWR0586")
					(unit 1)
				)
			)
		)
	)
	(symbol
		(lib_id "antmicropower:GND")
		(at 374.65 63.5 0)
		(mirror y)
		(unit 1)
		(exclude_from_sim no)
		(in_bom yes)
		(on_board yes)
		(dnp no)
		(property "Reference" "#PWR0617"
			(at 374.65 69.85 0)
			(effects
				(font
					(size 1.27 1.27)
				)
				(justify left bottom)
				(hide yes)
			)
		)
		(property "Value" "GND"
			(at 374.65 67.31 0)
			(effects
				(font
					(size 1.27 1.27)
					(thickness 0.15)
				)
			)
		)
		(property "Footprint" ""
			(at 365.76 71.12 0)
			(effects
				(font
					(size 1.27 1.27)
					(thickness 0.15)
				)
				(justify left bottom)
				(hide yes)
			)
		)
		(property "Datasheet" ""
			(at 365.76 76.2 0)
			(effects
				(font
					(size 1.27 1.27)
					(thickness 0.15)
				)
				(justify left bottom)
				(hide yes)
			)
		)
		(property "Description" ""
			(at 374.65 63.5 0)
			(effects
				(font
					(size 1.27 1.27)
				)
				(hide yes)
			)
		)
		(property "Author" "Antmicro"
			(at 365.76 71.12 0)
			(effects
				(font
					(size 1.27 1.27)
					(thickness 0.15)
				)
				(justify left bottom)
				(hide yes)
			)
		)
		(property "License" "Apache-2.0"
			(at 365.76 73.66 0)
			(effects
				(font
					(size 1.27 1.27)
					(thickness 0.15)
				)
				(justify left bottom)
				(hide yes)
			)
		)
		(pin "1"
		)
		(instances
			(project "jetson-agx-thor-baseboard"
				(path ""
					(reference "#PWR0617")
					(unit 1)
				)
			)
		)
	)
	(symbol
		(lib_id "antmicropower:GND")
		(at 154.94 125.73 0)
		(unit 1)
		(exclude_from_sim no)
		(in_bom yes)
		(on_board yes)
		(dnp no)
		(property "Reference" "#PWR0555"
			(at 154.94 132.08 0)
			(effects
				(font
					(size 1.27 1.27)
				)
				(justify left bottom)
				(hide yes)
			)
		)
		(property "Value" "GND"
			(at 154.94 129.54 0)
			(effects
				(font
					(size 1.27 1.27)
					(thickness 0.15)
				)
			)
		)
		(property "Footprint" ""
			(at 163.83 133.35 0)
			(effects
				(font
					(size 1.27 1.27)
					(thickness 0.15)
				)
				(justify left bottom)
				(hide yes)
			)
		)
		(property "Datasheet" ""
			(at 163.83 138.43 0)
			(effects
				(font
					(size 1.27 1.27)
					(thickness 0.15)
				)
				(justify left bottom)
				(hide yes)
			)
		)
		(property "Description" ""
			(at 154.94 125.73 0)
			(effects
				(font
					(size 1.27 1.27)
				)
				(hide yes)
			)
		)
		(property "Author" "Antmicro"
			(at 163.83 133.35 0)
			(effects
				(font
					(size 1.27 1.27)
					(thickness 0.15)
				)
				(justify left bottom)
				(hide yes)
			)
		)
		(property "License" "Apache-2.0"
			(at 163.83 135.89 0)
			(effects
				(font
					(size 1.27 1.27)
					(thickness 0.15)
				)
				(justify left bottom)
				(hide yes)
			)
		)
		(pin "1"
		)
		(instances
			(project "jetson-agx-thor-baseboard"
				(path ""
					(reference "#PWR0555")
					(unit 1)
				)
			)
		)
	)
	(symbol
		(lib_id "antmicropower:GND")
		(at 170.18 232.41 0)
		(unit 1)
		(exclude_from_sim no)
		(in_bom yes)
		(on_board yes)
		(dnp no)
		(property "Reference" "#PWR0145"
			(at 170.18 238.76 0)
			(effects
				(font
					(size 1.27 1.27)
				)
				(justify left bottom)
				(hide yes)
			)
		)
		(property "Value" "GND"
			(at 170.18 236.22 0)
			(effects
				(font
					(size 1.27 1.27)
					(thickness 0.15)
				)
			)
		)
		(property "Footprint" ""
			(at 179.07 240.03 0)
			(effects
				(font
					(size 1.27 1.27)
					(thickness 0.15)
				)
				(justify left bottom)
				(hide yes)
			)
		)
		(property "Datasheet" ""
			(at 179.07 245.11 0)
			(effects
				(font
					(size 1.27 1.27)
					(thickness 0.15)
				)
				(justify left bottom)
				(hide yes)
			)
		)
		(property "Description" ""
			(at 170.18 232.41 0)
			(effects
				(font
					(size 1.27 1.27)
				)
				(hide yes)
			)
		)
		(property "Author" "Antmicro"
			(at 179.07 240.03 0)
			(effects
				(font
					(size 1.27 1.27)
					(thickness 0.15)
				)
				(justify left bottom)
				(hide yes)
			)
		)
		(property "License" "Apache-2.0"
			(at 179.07 242.57 0)
			(effects
				(font
					(size 1.27 1.27)
					(thickness 0.15)
				)
				(justify left bottom)
				(hide yes)
			)
		)
		(pin "1"
		)
		(instances
			(project "jetson-agx-thor-baseboard"
				(path ""
					(reference "#PWR0145")
					(unit 1)
				)
			)
		)
	)
	(symbol
		(lib_id "antmicroCapacitorsmisc:C_22u_25V_0805")
		(at 40.64 224.79 90)
		(unit 1)
		(exclude_from_sim no)
		(in_bom yes)
		(on_board yes)
		(dnp no)
		(property "Reference" "C45"
			(at 41.275 220.345 90)
			(effects
				(font
					(size 1.27 1.27)
					(thickness 0.15)
				)
				(justify right)
			)
		)
		(property "Value" "C_22u_25V_0805"
			(at 50.8 204.47 0)
			(effects
				(font
					(size 1.27 1.27)
					(thickness 0.15)
				)
				(justify left bottom)
				(hide yes)
			)
		)
		(property "Footprint" "antmicro-footprints:C_0805_2012Metric"
			(at 53.34 204.47 0)
			(effects
				(font
					(size 1.27 1.27)
					(thickness 0.15)
				)
				(justify left bottom)
				(hide yes)
			)
		)
		(property "Datasheet" "https://product.samsungsem.com/mlcc/CL21A226MAYNNN.do"
			(at 55.88 204.47 0)
			(effects
				(font
					(size 1.27 1.27)
					(thickness 0.15)
				)
				(justify left bottom)
				(hide yes)
			)
		)
		(property "Description" "SMT Multilayer Ceramic Capacitor, 22uF, +/-20%, 25V, X5R, 0805 [2012 Metric]"
			(at 40.64 224.79 0)
			(effects
				(font
					(size 1.27 1.27)
				)
				(hide yes)
			)
		)
		(property "MPN" "CL21A226MAYNNNE"
			(at 58.42 204.47 0)
			(effects
				(font
					(size 1.27 1.27)
					(thickness 0.15)
				)
				(justify left bottom)
				(hide yes)
			)
		)
		(property "Manufacturer" "Samsung Electro-Mechanics"
			(at 60.96 204.47 0)
			(effects
				(font
					(size 1.27 1.27)
					(thickness 0.15)
				)
				(justify left bottom)
				(hide yes)
			)
		)
		(property "License" "Apache-2.0"
			(at 63.5 204.47 0)
			(effects
				(font
					(size 1.27 1.27)
					(thickness 0.15)
				)
				(justify left bottom)
				(hide yes)
			)
		)
		(property "Author" "Antmicro"
			(at 66.04 204.47 0)
			(effects
				(font
					(size 1.27 1.27)
					(thickness 0.15)
				)
				(justify left bottom)
				(hide yes)
			)
		)
		(property "Val" "22u"
			(at 41.275 224.155 90)
			(effects
				(font
					(size 1.27 1.27)
					(thickness 0.15)
				)
				(justify right)
			)
		)
		(property "Voltage" "25V"
			(at 41.275 226.695 90)
			(effects
				(font
					(size 1.27 1.27)
				)
				(justify right)
			)
		)
		(property "Dielectric" "X5R"
			(at 71.12 204.47 0)
			(effects
				(font
					(size 1.27 1.27)
				)
				(justify left bottom)
				(hide yes)
			)
		)
		(property "Public" "False"
			(at 73.66 204.47 0)
			(effects
				(font
					(size 1.27 1.27)
				)
				(justify left bottom)
				(hide yes)
			)
		)
		(pin "1"
		)
		(pin "2"
		)
		(instances
			(project "jetson-agx-thor-baseboard"
				(path ""
					(reference "C45")
					(unit 1)
				)
			)
		)
	)
	(symbol
		(lib_id "antmicropower:GND")
		(at 170.18 59.69 0)
		(unit 1)
		(exclude_from_sim no)
		(in_bom yes)
		(on_board yes)
		(dnp no)
		(property "Reference" "#PWR0542"
			(at 170.18 66.04 0)
			(effects
				(font
					(size 1.27 1.27)
				)
				(justify left bottom)
				(hide yes)
			)
		)
		(property "Value" "GND"
			(at 170.18 63.5 0)
			(effects
				(font
					(size 1.27 1.27)
					(thickness 0.15)
				)
			)
		)
		(property "Footprint" ""
			(at 179.07 67.31 0)
			(effects
				(font
					(size 1.27 1.27)
					(thickness 0.15)
				)
				(justify left bottom)
				(hide yes)
			)
		)
		(property "Datasheet" ""
			(at 179.07 72.39 0)
			(effects
				(font
					(size 1.27 1.27)
					(thickness 0.15)
				)
				(justify left bottom)
				(hide yes)
			)
		)
		(property "Description" ""
			(at 170.18 59.69 0)
			(effects
				(font
					(size 1.27 1.27)
				)
				(hide yes)
			)
		)
		(property "Author" "Antmicro"
			(at 179.07 67.31 0)
			(effects
				(font
					(size 1.27 1.27)
					(thickness 0.15)
				)
				(justify left bottom)
				(hide yes)
			)
		)
		(property "License" "Apache-2.0"
			(at 179.07 69.85 0)
			(effects
				(font
					(size 1.27 1.27)
					(thickness 0.15)
				)
				(justify left bottom)
				(hide yes)
			)
		)
		(pin "1"
		)
		(instances
			(project "jetson-agx-thor-baseboard"
				(path ""
					(reference "#PWR0542")
					(unit 1)
				)
			)
		)
	)
	(symbol
		(lib_id "antmicropower:+3V3_AON")
		(at 227.33 53.34 0)
		(unit 1)
		(exclude_from_sim no)
		(in_bom yes)
		(on_board yes)
		(dnp no)
		(property "Reference" "#PWR0523"
			(at 227.33 57.15 0)
			(effects
				(font
					(size 1.27 1.27)
				)
				(hide yes)
			)
		)
		(property "Value" "+3V3_AON"
			(at 227.33 48.26 0)
			(effects
				(font
					(size 1.27 1.27)
				)
			)
		)
		(property "Footprint" ""
			(at 227.33 53.34 0)
			(effects
				(font
					(size 1.27 1.27)
				)
				(hide yes)
			)
		)
		(property "Datasheet" ""
			(at 227.33 53.34 0)
			(effects
				(font
					(size 1.27 1.27)
				)
				(hide yes)
			)
		)
		(property "Description" ""
			(at 227.33 53.34 0)
			(effects
				(font
					(size 1.27 1.27)
				)
				(hide yes)
			)
		)
		(pin "1"
		)
		(instances
			(project "jetson-agx-thor-baseboard"
				(path ""
					(reference "#PWR0523")
					(unit 1)
				)
			)
		)
	)
	(symbol
		(lib_id "antmicroCapacitorsmisc:C_22u_25V_0805")
		(at 161.29 175.26 90)
		(unit 1)
		(exclude_from_sim no)
		(in_bom yes)
		(on_board yes)
		(dnp no)
		(property "Reference" "C379"
			(at 163.068 170.1801 90)
			(effects
				(font
					(size 1.27 1.27)
					(thickness 0.15)
				)
				(justify right)
			)
		)
		(property "Value" "C_22u_25V_0805"
			(at 171.45 154.94 0)
			(effects
				(font
					(size 1.27 1.27)
					(thickness 0.15)
				)
				(justify left bottom)
				(hide yes)
			)
		)
		(property "Footprint" "antmicro-footprints:C_0805_2012Metric"
			(at 173.99 154.94 0)
			(effects
				(font
					(size 1.27 1.27)
					(thickness 0.15)
				)
				(justify left bottom)
				(hide yes)
			)
		)
		(property "Datasheet" "https://product.samsungsem.com/mlcc/CL21A226MAYNNN.do"
			(at 176.53 154.94 0)
			(effects
				(font
					(size 1.27 1.27)
					(thickness 0.15)
				)
				(justify left bottom)
				(hide yes)
			)
		)
		(property "Description" "SMT Multilayer Ceramic Capacitor, 22uF, +/-20%, 25V, X5R, 0805 [2012 Metric]"
			(at 194.31 154.94 0)
			(effects
				(font
					(size 1.27 1.27)
				)
				(justify left bottom)
				(hide yes)
			)
		)
		(property "MPN" "CL21A226MAYNNNE"
			(at 179.07 154.94 0)
			(effects
				(font
					(size 1.27 1.27)
					(thickness 0.15)
				)
				(justify left bottom)
				(hide yes)
			)
		)
		(property "Manufacturer" "Samsung Electro-Mechanics"
			(at 181.61 154.94 0)
			(effects
				(font
					(size 1.27 1.27)
					(thickness 0.15)
				)
				(justify left bottom)
				(hide yes)
			)
		)
		(property "License" "Apache-2.0"
			(at 184.15 154.94 0)
			(effects
				(font
					(size 1.27 1.27)
					(thickness 0.15)
				)
				(justify left bottom)
				(hide yes)
			)
		)
		(property "Author" "Antmicro"
			(at 186.69 154.94 0)
			(effects
				(font
					(size 1.27 1.27)
					(thickness 0.15)
				)
				(justify left bottom)
				(hide yes)
			)
		)
		(property "Val" "22u"
			(at 163.068 172.7201 90)
			(effects
				(font
					(size 1.27 1.27)
					(thickness 0.15)
				)
				(justify right)
			)
		)
		(property "Voltage" "25V"
			(at 163.068 175.26 90)
			(effects
				(font
					(size 1.27 1.27)
				)
				(justify right)
			)
		)
		(property "Dielectric" "X5R"
			(at 191.77 154.94 0)
			(effects
				(font
					(size 1.27 1.27)
				)
				(justify left bottom)
				(hide yes)
			)
		)
		(property "Public" "False"
			(at 194.31 154.94 0)
			(effects
				(font
					(size 1.27 1.27)
				)
				(justify left bottom)
				(hide yes)
			)
		)
		(pin "2"
		)
		(pin "1"
		)
		(instances
			(project "jetson-agx-thor-baseboard"
				(path ""
					(reference "C379")
					(unit 1)
				)
			)
		)
	)
	(symbol
		(lib_id "antmicroCapacitors0402:C_4u7_25V_0402")
		(at 83.82 120.65 90)
		(unit 1)
		(exclude_from_sim no)
		(in_bom yes)
		(on_board yes)
		(dnp no)
		(property "Reference" "C280"
			(at 84.455 116.205 90)
			(effects
				(font
					(size 1.27 1.27)
					(thickness 0.15)
				)
				(justify right)
			)
		)
		(property "Value" "C_4u7_25V_0402"
			(at 93.98 100.33 0)
			(effects
				(font
					(size 1.27 1.27)
					(thickness 0.15)
				)
				(justify left bottom)
				(hide yes)
			)
		)
		(property "Footprint" "antmicro-footprints:C_0402_1005Metric"
			(at 96.52 100.33 0)
			(effects
				(font
					(size 1.27 1.27)
					(thickness 0.15)
				)
				(justify left bottom)
				(hide yes)
			)
		)
		(property "Datasheet" "https://www.murata.com/products/productdetail?partno=GRM155C61E475ME15%23"
			(at 99.06 100.33 0)
			(effects
				(font
					(size 1.27 1.27)
					(thickness 0.15)
				)
				(justify left bottom)
				(hide yes)
			)
		)
		(property "Description" "SMD Multilayer Ceramic Capacitor"
			(at 83.82 120.65 0)
			(effects
				(font
					(size 1.27 1.27)
				)
				(hide yes)
			)
		)
		(property "MPN" "GRM155C61E475ME15J"
			(at 101.6 100.33 0)
			(effects
				(font
					(size 1.27 1.27)
					(thickness 0.15)
				)
				(justify left bottom)
				(hide yes)
			)
		)
		(property "Manufacturer" "Murata"
			(at 104.14 100.33 0)
			(effects
				(font
					(size 1.27 1.27)
					(thickness 0.15)
				)
				(justify left bottom)
				(hide yes)
			)
		)
		(property "License" "Apache-2.0"
			(at 106.68 100.33 0)
			(effects
				(font
					(size 1.27 1.27)
					(thickness 0.15)
				)
				(justify left bottom)
				(hide yes)
			)
		)
		(property "Author" "Antmicro"
			(at 109.22 100.33 0)
			(effects
				(font
					(size 1.27 1.27)
					(thickness 0.15)
				)
				(justify left bottom)
				(hide yes)
			)
		)
		(property "Val" "4u7"
			(at 84.455 120.015 90)
			(effects
				(font
					(size 1.27 1.27)
					(thickness 0.15)
				)
				(justify right)
			)
		)
		(property "Voltage" "25V"
			(at 111.76 100.33 0)
			(effects
				(font
					(size 1.27 1.27)
				)
				(justify left bottom)
				(hide yes)
			)
		)
		(property "Dielectric" "X5S"
			(at 114.3 100.33 0)
			(effects
				(font
					(size 1.27 1.27)
				)
				(justify left bottom)
				(hide yes)
			)
		)
		(pin "2"
		)
		(pin "1"
		)
		(instances
			(project "jetson-agx-thor-baseboard"
				(path ""
					(reference "C280")
					(unit 1)
				)
			)
		)
	)
	(symbol
		(lib_id "antmicroCapacitors0603:C_22u_16V_0603")
		(at 170.18 273.05 90)
		(unit 1)
		(exclude_from_sim no)
		(in_bom yes)
		(on_board yes)
		(dnp no)
		(property "Reference" "C70"
			(at 170.815 268.605 90)
			(effects
				(font
					(size 1.27 1.27)
				)
				(justify right)
			)
		)
		(property "Value" "C_22u_16V_0603"
			(at 180.34 252.73 0)
			(effects
				(font
					(size 1.27 1.27)
					(thickness 0.15)
				)
				(justify left bottom)
				(hide yes)
			)
		)
		(property "Footprint" "antmicro-footprints:C_0603_1608Metric_EIA"
			(at 182.88 252.73 0)
			(effects
				(font
					(size 1.27 1.27)
					(thickness 0.15)
				)
				(justify left bottom)
				(hide yes)
			)
		)
		(property "Datasheet" "https://product.samsungsem.com/mlcc/CL10A226MO7JZN.do"
			(at 185.42 252.73 0)
			(effects
				(font
					(size 1.27 1.27)
					(thickness 0.15)
				)
				(justify left bottom)
				(hide yes)
			)
		)
		(property "Description" "SMD Multilayer Ceramic Capacitor"
			(at 170.18 273.05 0)
			(effects
				(font
					(size 1.27 1.27)
				)
				(hide yes)
			)
		)
		(property "Manufacturer" "Samsung Electro-Mechanics"
			(at 190.5 252.73 0)
			(effects
				(font
					(size 1.27 1.27)
					(thickness 0.15)
				)
				(justify left bottom)
				(hide yes)
			)
		)
		(property "MPN" "CL10A226MO7JZNC"
			(at 187.96 252.73 0)
			(effects
				(font
					(size 1.27 1.27)
					(thickness 0.15)
				)
				(justify left bottom)
				(hide yes)
			)
		)
		(property "Val" "22u"
			(at 170.815 272.415 90)
			(effects
				(font
					(size 1.27 1.27)
					(thickness 0.15)
				)
				(justify right)
			)
		)
		(property "License" "Apache-2.0"
			(at 193.04 252.73 0)
			(effects
				(font
					(size 1.27 1.27)
					(thickness 0.15)
				)
				(justify left bottom)
				(hide yes)
			)
		)
		(property "Author" "Antmicro"
			(at 195.58 252.73 0)
			(effects
				(font
					(size 1.27 1.27)
					(thickness 0.15)
				)
				(justify left bottom)
				(hide yes)
			)
		)
		(property "Voltage" "16V"
			(at 198.12 252.73 0)
			(effects
				(font
					(size 1.27 1.27)
				)
				(justify left bottom)
				(hide yes)
			)
		)
		(property "Dielectric" ""
			(at 200.66 252.73 0)
			(effects
				(font
					(size 1.27 1.27)
				)
				(justify left bottom)
				(hide yes)
			)
		)
		(pin "1"
		)
		(pin "2"
		)
		(instances
			(project "jetson-agx-thor-baseboard"
				(path ""
					(reference "C70")
					(unit 1)
				)
			)
		)
	)
	(symbol
		(lib_id "antmicropower:GND")
		(at 66.04 187.96 0)
		(unit 1)
		(exclude_from_sim no)
		(in_bom yes)
		(on_board yes)
		(dnp no)
		(property "Reference" "#PWR0751"
			(at 66.04 194.31 0)
			(effects
				(font
					(size 1.27 1.27)
				)
				(justify left bottom)
				(hide yes)
			)
		)
		(property "Value" "GND"
			(at 66.04 191.77 0)
			(effects
				(font
					(size 1.27 1.27)
					(thickness 0.15)
				)
			)
		)
		(property "Footprint" ""
			(at 74.93 195.58 0)
			(effects
				(font
					(size 1.27 1.27)
					(thickness 0.15)
				)
				(justify left bottom)
				(hide yes)
			)
		)
		(property "Datasheet" ""
			(at 74.93 200.66 0)
			(effects
				(font
					(size 1.27 1.27)
					(thickness 0.15)
				)
				(justify left bottom)
				(hide yes)
			)
		)
		(property "Description" ""
			(at 66.04 187.96 0)
			(effects
				(font
					(size 1.27 1.27)
				)
				(hide yes)
			)
		)
		(property "Author" "Antmicro"
			(at 74.93 195.58 0)
			(effects
				(font
					(size 1.27 1.27)
					(thickness 0.15)
				)
				(justify left bottom)
				(hide yes)
			)
		)
		(property "License" "Apache-2.0"
			(at 74.93 198.12 0)
			(effects
				(font
					(size 1.27 1.27)
					(thickness 0.15)
				)
				(justify left bottom)
				(hide yes)
			)
		)
		(pin "1"
		)
		(instances
			(project "jetson-agx-thor-baseboard"
				(path ""
					(reference "#PWR0751")
					(unit 1)
				)
			)
		)
	)
	(symbol
		(lib_id "antmicroCapacitors0603:C_22u_16V_0603")
		(at 177.8 226.06 90)
		(unit 1)
		(exclude_from_sim no)
		(in_bom yes)
		(on_board yes)
		(dnp no)
		(property "Reference" "C72"
			(at 178.435 221.615 90)
			(effects
				(font
					(size 1.27 1.27)
				)
				(justify right)
			)
		)
		(property "Value" "C_22u_16V_0603"
			(at 187.96 205.74 0)
			(effects
				(font
					(size 1.27 1.27)
					(thickness 0.15)
				)
				(justify left bottom)
				(hide yes)
			)
		)
		(property "Footprint" "antmicro-footprints:C_0603_1608Metric_EIA"
			(at 190.5 205.74 0)
			(effects
				(font
					(size 1.27 1.27)
					(thickness 0.15)
				)
				(justify left bottom)
				(hide yes)
			)
		)
		(property "Datasheet" "https://product.samsungsem.com/mlcc/CL10A226MO7JZN.do"
			(at 193.04 205.74 0)
			(effects
				(font
					(size 1.27 1.27)
					(thickness 0.15)
				)
				(justify left bottom)
				(hide yes)
			)
		)
		(property "Description" "SMD Multilayer Ceramic Capacitor"
			(at 177.8 226.06 0)
			(effects
				(font
					(size 1.27 1.27)
				)
				(hide yes)
			)
		)
		(property "Manufacturer" "Samsung Electro-Mechanics"
			(at 198.12 205.74 0)
			(effects
				(font
					(size 1.27 1.27)
					(thickness 0.15)
				)
				(justify left bottom)
				(hide yes)
			)
		)
		(property "MPN" "CL10A226MO7JZNC"
			(at 195.58 205.74 0)
			(effects
				(font
					(size 1.27 1.27)
					(thickness 0.15)
				)
				(justify left bottom)
				(hide yes)
			)
		)
		(property "Val" "22u"
			(at 178.435 225.425 90)
			(effects
				(font
					(size 1.27 1.27)
					(thickness 0.15)
				)
				(justify right)
			)
		)
		(property "License" "Apache-2.0"
			(at 200.66 205.74 0)
			(effects
				(font
					(size 1.27 1.27)
					(thickness 0.15)
				)
				(justify left bottom)
				(hide yes)
			)
		)
		(property "Author" "Antmicro"
			(at 203.2 205.74 0)
			(effects
				(font
					(size 1.27 1.27)
					(thickness 0.15)
				)
				(justify left bottom)
				(hide yes)
			)
		)
		(property "Voltage" "16V"
			(at 205.74 205.74 0)
			(effects
				(font
					(size 1.27 1.27)
				)
				(justify left bottom)
				(hide yes)
			)
		)
		(property "Dielectric" ""
			(at 208.28 205.74 0)
			(effects
				(font
					(size 1.27 1.27)
				)
				(justify left bottom)
				(hide yes)
			)
		)
		(pin "1"
		)
		(pin "2"
		)
		(instances
			(project "jetson-agx-thor-baseboard"
				(path ""
					(reference "C72")
					(unit 1)
				)
			)
		)
	)
	(symbol
		(lib_id "antmicroDCDCConverters:TPS564247DRLR")
		(at 300.99 182.88 0)
		(unit 1)
		(exclude_from_sim no)
		(in_bom yes)
		(on_board yes)
		(dnp no)
		(fields_autoplaced yes)
		(property "Reference" "U69"
			(at 308.61 176.53 0)
			(effects
				(font
					(size 1.27 1.27)
				)
			)
		)
		(property "Value" "TPS564247DRLR"
			(at 300.99 182.88 0)
			(effects
				(font
					(size 1.27 1.27)
				)
				(hide yes)
			)
		)
		(property "Footprint" "antmicro-footprints:SOT-563"
			(at 300.99 182.88 0)
			(effects
				(font
					(size 1.27 1.27)
				)
				(hide yes)
			)
		)
		(property "Datasheet" "https://www.ti.com/lit/ds/symlink/tps564247.pdf?ts=1713526387938&ref_url=https%253A%252F%252Fwww.mouser.pl%252F"
			(at 300.99 182.88 0)
			(effects
				(font
					(size 1.27 1.27)
				)
				(hide yes)
			)
		)
		(property "Description" "Switching Voltage Regulators 3-V to 16-V input voltage, 4-A FCCM mode, synchronous buck converter in SOT-563 package 6-SOT-5X3 -40 to 125"
			(at 300.99 182.88 0)
			(effects
				(font
					(size 1.27 1.27)
				)
				(hide yes)
			)
		)
		(property "MPN" "TPS564247DRLR"
			(at 308.61 179.07 0)
			(effects
				(font
					(size 1.27 1.27)
				)
			)
		)
		(property "Author" "Antmicro"
			(at 331.47 203.2 0)
			(effects
				(font
					(size 1.27 1.27)
					(thickness 0.15)
				)
				(justify left bottom)
				(hide yes)
			)
		)
		(property "License" "Apache-2.0"
			(at 331.47 205.74 0)
			(effects
				(font
					(size 1.27 1.27)
					(thickness 0.15)
				)
				(justify left bottom)
				(hide yes)
			)
		)
		(property "Manufacturer" "Texas Instruments"
			(at 331.47 200.66 0)
			(effects
				(font
					(size 1.27 1.27)
					(thickness 0.15)
				)
				(justify left bottom)
				(hide yes)
			)
		)
		(pin "1"
		)
		(pin "6"
		)
		(pin "2"
		)
		(pin "3"
		)
		(pin "5"
		)
		(pin "4"
		)
		(instances
			(project "jetson-agx-thor-baseboard"
				(path ""
					(reference "U69")
					(unit 1)
				)
			)
		)
	)
	(symbol
		(lib_id "antmicropower:VCC")
		(at 16.51 157.48 0)
		(unit 1)
		(exclude_from_sim no)
		(in_bom yes)
		(on_board yes)
		(dnp no)
		(property "Reference" "#PWR0491"
			(at 16.51 161.29 0)
			(effects
				(font
					(size 1.27 1.27)
				)
				(justify left bottom)
				(hide yes)
			)
		)
		(property "Value" "VCC"
			(at 16.51 153.67 0)
			(effects
				(font
					(size 1.27 1.27)
				)
			)
		)
		(property "Footprint" ""
			(at 16.51 157.48 0)
			(effects
				(font
					(size 1.27 1.27)
				)
				(hide yes)
			)
		)
		(property "Datasheet" ""
			(at 16.51 157.48 0)
			(effects
				(font
					(size 1.27 1.27)
				)
				(hide yes)
			)
		)
		(property "Description" ""
			(at 16.51 157.48 0)
			(effects
				(font
					(size 1.27 1.27)
				)
				(hide yes)
			)
		)
		(pin "1"
		)
		(instances
			(project "jetson-agx-thor-baseboard"
				(path ""
					(reference "#PWR0491")
					(unit 1)
				)
			)
		)
	)
	(symbol
		(lib_id "antmicroCapacitors0402:C_100n_0402")
		(at 215.9 278.13 90)
		(unit 1)
		(exclude_from_sim no)
		(in_bom yes)
		(on_board yes)
		(dnp no)
		(property "Reference" "C217"
			(at 218.44 274.3135 90)
			(effects
				(font
					(size 1.27 1.27)
					(thickness 0.15)
				)
				(justify right)
			)
		)
		(property "Value" "C_100n_0402"
			(at 226.06 257.81 0)
			(effects
				(font
					(size 1.27 1.27)
					(thickness 0.15)
				)
				(justify left bottom)
				(hide yes)
			)
		)
		(property "Footprint" "antmicro-footprints:C_0402_1005Metric"
			(at 228.6 257.81 0)
			(effects
				(font
					(size 1.27 1.27)
					(thickness 0.15)
				)
				(justify left bottom)
				(hide yes)
			)
		)
		(property "Datasheet" "https://www.murata.com/products/productdetail?partno=GRM155R61H104KE14%23"
			(at 231.14 257.81 0)
			(effects
				(font
					(size 1.27 1.27)
					(thickness 0.15)
				)
				(justify left bottom)
				(hide yes)
			)
		)
		(property "Description" "SMD Multilayer Ceramic Capacitor, 0.1 µF, 50 V, 0402 [1005 Metric], ± 10%, X5R, GRM Series"
			(at 215.9 278.13 0)
			(effects
				(font
					(size 1.27 1.27)
				)
				(hide yes)
			)
		)
		(property "MPN" "GRM155R61H104KE14D"
			(at 233.68 257.81 0)
			(effects
				(font
					(size 1.27 1.27)
					(thickness 0.15)
				)
				(justify left bottom)
				(hide yes)
			)
		)
		(property "Manufacturer" "Murata"
			(at 236.22 257.81 0)
			(effects
				(font
					(size 1.27 1.27)
					(thickness 0.15)
				)
				(justify left bottom)
				(hide yes)
			)
		)
		(property "License" "Apache-2.0"
			(at 238.76 257.81 0)
			(effects
				(font
					(size 1.27 1.27)
					(thickness 0.15)
				)
				(justify left bottom)
				(hide yes)
			)
		)
		(property "Author" "Antmicro"
			(at 241.3 257.81 0)
			(effects
				(font
					(size 1.27 1.27)
					(thickness 0.15)
				)
				(justify left bottom)
				(hide yes)
			)
		)
		(property "Val" "100n"
			(at 218.44 276.8535 90)
			(effects
				(font
					(size 1.27 1.27)
					(thickness 0.15)
				)
				(justify right)
			)
		)
		(property "Voltage" "50V"
			(at 243.84 257.81 0)
			(effects
				(font
					(size 1.27 1.27)
				)
				(justify left bottom)
				(hide yes)
			)
		)
		(property "Dielectric" "X5R"
			(at 246.38 257.81 0)
			(effects
				(font
					(size 1.27 1.27)
				)
				(justify left bottom)
				(hide yes)
			)
		)
		(property "Public" "False"
			(at 248.92 257.81 0)
			(effects
				(font
					(size 1.27 1.27)
				)
				(justify left bottom)
				(hide yes)
			)
		)
		(pin "1"
		)
		(pin "2"
		)
		(instances
			(project "jetson-agx-thor-baseboard"
				(path ""
					(reference "C217")
					(unit 1)
				)
			)
		)
	)
	(symbol
		(lib_id "antmicroCapacitors0402:C_100n_0402")
		(at 209.55 166.37 180)
		(unit 1)
		(exclude_from_sim no)
		(in_bom yes)
		(on_board yes)
		(dnp no)
		(property "Reference" "C382"
			(at 207.01 161.036 0)
			(effects
				(font
					(size 1.27 1.27)
				)
			)
		)
		(property "Value" "C_100n_0402"
			(at 189.23 156.21 0)
			(effects
				(font
					(size 1.27 1.27)
					(thickness 0.15)
				)
				(justify left bottom)
				(hide yes)
			)
		)
		(property "Footprint" "antmicro-footprints:C_0402_1005Metric"
			(at 189.23 153.67 0)
			(effects
				(font
					(size 1.27 1.27)
					(thickness 0.15)
				)
				(justify left bottom)
				(hide yes)
			)
		)
		(property "Datasheet" "https://www.murata.com/products/productdetail?partno=GRM155R61H104KE14%23"
			(at 189.23 151.13 0)
			(effects
				(font
					(size 1.27 1.27)
					(thickness 0.15)
				)
				(justify left bottom)
				(hide yes)
			)
		)
		(property "Description" "SMD Multilayer Ceramic Capacitor, 0.1 µF, 50 V, 0402 [1005 Metric], ± 10%, X5R, GRM Series"
			(at 209.55 166.37 0)
			(effects
				(font
					(size 1.27 1.27)
				)
				(hide yes)
			)
		)
		(property "Manufacturer" "Murata"
			(at 189.23 146.05 0)
			(effects
				(font
					(size 1.27 1.27)
					(thickness 0.15)
				)
				(justify left bottom)
				(hide yes)
			)
		)
		(property "MPN" "GRM155R61H104KE14D"
			(at 189.23 148.59 0)
			(effects
				(font
					(size 1.27 1.27)
					(thickness 0.15)
				)
				(justify left bottom)
				(hide yes)
			)
		)
		(property "Val" "100n"
			(at 207.01 163.576 0)
			(effects
				(font
					(size 1.27 1.27)
					(thickness 0.15)
				)
			)
		)
		(property "License" "Apache-2.0"
			(at 189.23 143.51 0)
			(effects
				(font
					(size 1.27 1.27)
					(thickness 0.15)
				)
				(justify left bottom)
				(hide yes)
			)
		)
		(property "Author" "Antmicro"
			(at 189.23 140.97 0)
			(effects
				(font
					(size 1.27 1.27)
					(thickness 0.15)
				)
				(justify left bottom)
				(hide yes)
			)
		)
		(property "Voltage" "50V"
			(at 189.23 138.43 0)
			(effects
				(font
					(size 1.27 1.27)
				)
				(justify left bottom)
				(hide yes)
			)
		)
		(property "Dielectric" "X5R"
			(at 189.23 135.89 0)
			(effects
				(font
					(size 1.27 1.27)
				)
				(justify left bottom)
				(hide yes)
			)
		)
		(pin "1"
		)
		(pin "2"
		)
		(instances
			(project "jetson-agx-thor-baseboard"
				(path ""
					(reference "C382")
					(unit 1)
				)
			)
		)
	)
	(symbol
		(lib_id "antmicropower:+3V3_AON")
		(at 222.25 223.52 0)
		(unit 1)
		(exclude_from_sim no)
		(in_bom yes)
		(on_board yes)
		(dnp no)
		(fields_autoplaced yes)
		(property "Reference" "#PWR0527"
			(at 222.25 227.33 0)
			(effects
				(font
					(size 1.27 1.27)
				)
				(hide yes)
			)
		)
		(property "Value" "+3V3_AON"
			(at 222.25 218.44 0)
			(effects
				(font
					(size 1.27 1.27)
				)
			)
		)
		(property "Footprint" ""
			(at 222.25 223.52 0)
			(effects
				(font
					(size 1.27 1.27)
				)
				(hide yes)
			)
		)
		(property "Datasheet" ""
			(at 222.25 223.52 0)
			(effects
				(font
					(size 1.27 1.27)
				)
				(hide yes)
			)
		)
		(property "Description" ""
			(at 222.25 223.52 0)
			(effects
				(font
					(size 1.27 1.27)
				)
				(hide yes)
			)
		)
		(pin "1"
		)
		(instances
			(project "jetson-agx-thor-baseboard"
				(path ""
					(reference "#PWR0527")
					(unit 1)
				)
			)
		)
	)
	(symbol
		(lib_id "antmicroDCDCConverters:SIC437AED-T1-GE3")
		(at 92.71 207.01 0)
		(unit 1)
		(exclude_from_sim no)
		(in_bom yes)
		(on_board yes)
		(dnp no)
		(property "Reference" "U12"
			(at 102.87 200.66 0)
			(effects
				(font
					(size 1.27 1.27)
					(thickness 0.15)
				)
			)
		)
		(property "Value" "SIC437AED-T1-GE3"
			(at 125.73 214.63 0)
			(effects
				(font
					(size 1.27 1.27)
					(thickness 0.15)
				)
				(justify left bottom)
				(hide yes)
			)
		)
		(property "Footprint" "antmicro-footprints:MLP44-24L_4x4x0.75mm"
			(at 125.73 217.17 0)
			(effects
				(font
					(size 1.27 1.27)
					(thickness 0.15)
				)
				(justify left bottom)
				(hide yes)
			)
		)
		(property "Datasheet" "https://www.vishay.com/docs/75921/sic437.pdf"
			(at 125.73 219.71 0)
			(effects
				(font
					(size 1.27 1.27)
					(thickness 0.15)
				)
				(justify left bottom)
				(hide yes)
			)
		)
		(property "Description" "DC/DC Buck Step Down Regulator Adjustable, 4.5-28V In, 0.6V to 20V/12A Out, 1MHz, PowerPAK MLP44-24"
			(at 125.73 229.87 0)
			(effects
				(font
					(size 1.27 1.27)
				)
				(justify left bottom)
				(hide yes)
			)
		)
		(property "Manufacturer" "Vishay"
			(at 125.73 222.25 0)
			(effects
				(font
					(size 1.27 1.27)
					(thickness 0.15)
				)
				(justify left bottom)
				(hide yes)
			)
		)
		(property "MPN" "SIC437AED-T1-GE3"
			(at 102.87 203.2 0)
			(effects
				(font
					(size 1.27 1.27)
					(thickness 0.15)
				)
			)
		)
		(property "Author" "Antmicro"
			(at 125.73 224.79 0)
			(effects
				(font
					(size 1.27 1.27)
					(thickness 0.15)
				)
				(justify left bottom)
				(hide yes)
			)
		)
		(property "License" "Apache-2.0"
			(at 125.73 227.33 0)
			(effects
				(font
					(size 1.27 1.27)
					(thickness 0.15)
				)
				(justify left bottom)
				(hide yes)
			)
		)
		(pin "7"
		)
		(pin "16"
		)
		(pin "18"
		)
		(pin "8"
		)
		(pin "15"
		)
		(pin "14"
		)
		(pin "20"
		)
		(pin "2"
		)
		(pin "12"
		)
		(pin "22"
		)
		(pin "11"
		)
		(pin "26"
		)
		(pin "10"
		)
		(pin "19"
		)
		(pin "5"
		)
		(pin "4"
		)
		(pin "17"
		)
		(pin "6"
		)
		(pin "3"
		)
		(pin "1"
		)
		(pin "13"
		)
		(pin "23"
		)
		(pin "25"
		)
		(pin "21"
		)
		(pin "24"
		)
		(pin "9"
		)
		(pin "27"
		)
		(pin "28"
		)
		(instances
			(project "jetson-agx-thor-baseboard"
				(path ""
					(reference "U12")
					(unit 1)
				)
			)
		)
	)
	(symbol
		(lib_id "antmicroPowerMeasurement:INA219AIDCNR")
		(at 199.39 175.26 0)
		(unit 1)
		(exclude_from_sim no)
		(in_bom yes)
		(on_board yes)
		(dnp no)
		(property "Reference" "U76"
			(at 207.01 170.18 0)
			(effects
				(font
					(size 1.27 1.27)
				)
			)
		)
		(property "Value" "INA219AIDCNR"
			(at 199.39 175.26 0)
			(effects
				(font
					(size 1.27 1.27)
				)
				(hide yes)
			)
		)
		(property "Footprint" "antmicro-footprints:SOT-23-8"
			(at 199.39 175.26 0)
			(effects
				(font
					(size 1.27 1.27)
				)
				(hide yes)
			)
		)
		(property "Datasheet" "https://www.ti.com/lit/ds/symlink/ina219.pdf?ts=1713856455637&ref_url=https%253A%252F%252Fwww.mouser.es%252F"
			(at 199.39 175.26 0)
			(effects
				(font
					(size 1.27 1.27)
				)
				(hide yes)
			)
		)
		(property "Description" "Zerø-Drift, Bidirectional Current/Power Monitor With I2C Interface"
			(at 199.39 175.26 0)
			(effects
				(font
					(size 1.27 1.27)
				)
				(hide yes)
			)
		)
		(property "Manufacturer" "Texas Instruments"
			(at 199.39 175.26 0)
			(effects
				(font
					(size 1.27 1.27)
				)
				(hide yes)
			)
		)
		(property "MPN" "INA219AIDCNR"
			(at 207.01 172.72 0)
			(effects
				(font
					(size 1.27 1.27)
				)
			)
		)
		(property "Author" "Antmicro"
			(at 224.79 195.58 0)
			(effects
				(font
					(size 1.27 1.27)
					(thickness 0.15)
				)
				(justify left bottom)
				(hide yes)
			)
		)
		(property "License" "Apache-2.0"
			(at 224.79 198.12 0)
			(effects
				(font
					(size 1.27 1.27)
					(thickness 0.15)
				)
				(justify left bottom)
				(hide yes)
			)
		)
		(pin "1"
		)
		(pin "2"
		)
		(pin "5"
		)
		(pin "6"
		)
		(pin "8"
		)
		(pin "3"
		)
		(pin "7"
		)
		(pin "4"
		)
		(instances
			(project "jetson-agx-thor-baseboard"
				(path ""
					(reference "U76")
					(unit 1)
				)
			)
		)
	)
	(symbol
		(lib_id "antmicropower:GND")
		(at 154.94 279.4 0)
		(unit 1)
		(exclude_from_sim no)
		(in_bom yes)
		(on_board yes)
		(dnp no)
		(property "Reference" "#PWR0137"
			(at 154.94 285.75 0)
			(effects
				(font
					(size 1.27 1.27)
				)
				(justify left bottom)
				(hide yes)
			)
		)
		(property "Value" "GND"
			(at 154.94 283.21 0)
			(effects
				(font
					(size 1.27 1.27)
					(thickness 0.15)
				)
			)
		)
		(property "Footprint" ""
			(at 163.83 287.02 0)
			(effects
				(font
					(size 1.27 1.27)
					(thickness 0.15)
				)
				(justify left bottom)
				(hide yes)
			)
		)
		(property "Datasheet" ""
			(at 163.83 292.1 0)
			(effects
				(font
					(size 1.27 1.27)
					(thickness 0.15)
				)
				(justify left bottom)
				(hide yes)
			)
		)
		(property "Description" ""
			(at 154.94 279.4 0)
			(effects
				(font
					(size 1.27 1.27)
				)
				(hide yes)
			)
		)
		(property "Author" "Antmicro"
			(at 163.83 287.02 0)
			(effects
				(font
					(size 1.27 1.27)
					(thickness 0.15)
				)
				(justify left bottom)
				(hide yes)
			)
		)
		(property "License" "Apache-2.0"
			(at 163.83 289.56 0)
			(effects
				(font
					(size 1.27 1.27)
					(thickness 0.15)
				)
				(justify left bottom)
				(hide yes)
			)
		)
		(pin "1"
		)
		(instances
			(project "jetson-agx-thor-baseboard"
				(path ""
					(reference "#PWR0137")
					(unit 1)
				)
			)
		)
	)
	(symbol
		(lib_id "antmicropower:GND")
		(at 168.91 176.53 0)
		(unit 1)
		(exclude_from_sim no)
		(in_bom yes)
		(on_board yes)
		(dnp no)
		(property "Reference" "#PWR0758"
			(at 168.91 182.88 0)
			(effects
				(font
					(size 1.27 1.27)
				)
				(justify left bottom)
				(hide yes)
			)
		)
		(property "Value" "GND"
			(at 168.91 180.34 0)
			(effects
				(font
					(size 1.27 1.27)
					(thickness 0.15)
				)
			)
		)
		(property "Footprint" ""
			(at 177.8 184.15 0)
			(effects
				(font
					(size 1.27 1.27)
					(thickness 0.15)
				)
				(justify left bottom)
				(hide yes)
			)
		)
		(property "Datasheet" ""
			(at 177.8 189.23 0)
			(effects
				(font
					(size 1.27 1.27)
					(thickness 0.15)
				)
				(justify left bottom)
				(hide yes)
			)
		)
		(property "Description" ""
			(at 168.91 176.53 0)
			(effects
				(font
					(size 1.27 1.27)
				)
				(hide yes)
			)
		)
		(property "Author" "Antmicro"
			(at 177.8 184.15 0)
			(effects
				(font
					(size 1.27 1.27)
					(thickness 0.15)
				)
				(justify left bottom)
				(hide yes)
			)
		)
		(property "License" "Apache-2.0"
			(at 177.8 186.69 0)
			(effects
				(font
					(size 1.27 1.27)
					(thickness 0.15)
				)
				(justify left bottom)
				(hide yes)
			)
		)
		(pin "1"
		)
		(instances
			(project "jetson-agx-thor-baseboard"
				(path ""
					(reference "#PWR0758")
					(unit 1)
				)
			)
		)
	)
	(symbol
		(lib_id "antmicropower:GND")
		(at 36.83 167.64 0)
		(unit 1)
		(exclude_from_sim no)
		(in_bom yes)
		(on_board yes)
		(dnp no)
		(property "Reference" "#PWR0747"
			(at 36.83 173.99 0)
			(effects
				(font
					(size 1.27 1.27)
				)
				(justify left bottom)
				(hide yes)
			)
		)
		(property "Value" "GND"
			(at 36.83 171.45 0)
			(effects
				(font
					(size 1.27 1.27)
					(thickness 0.15)
				)
			)
		)
		(property "Footprint" ""
			(at 45.72 175.26 0)
			(effects
				(font
					(size 1.27 1.27)
					(thickness 0.15)
				)
				(justify left bottom)
				(hide yes)
			)
		)
		(property "Datasheet" ""
			(at 45.72 180.34 0)
			(effects
				(font
					(size 1.27 1.27)
					(thickness 0.15)
				)
				(justify left bottom)
				(hide yes)
			)
		)
		(property "Description" ""
			(at 36.83 167.64 0)
			(effects
				(font
					(size 1.27 1.27)
				)
				(hide yes)
			)
		)
		(property "Author" "Antmicro"
			(at 45.72 175.26 0)
			(effects
				(font
					(size 1.27 1.27)
					(thickness 0.15)
				)
				(justify left bottom)
				(hide yes)
			)
		)
		(property "License" "Apache-2.0"
			(at 45.72 177.8 0)
			(effects
				(font
					(size 1.27 1.27)
					(thickness 0.15)
				)
				(justify left bottom)
				(hide yes)
			)
		)
		(pin "1"
		)
		(instances
			(project "jetson-agx-thor-baseboard"
				(path ""
					(reference "#PWR0747")
					(unit 1)
				)
			)
		)
	)
	(symbol
		(lib_id "antmicropower:GND")
		(at 170.18 140.97 0)
		(unit 1)
		(exclude_from_sim no)
		(in_bom yes)
		(on_board yes)
		(dnp no)
		(property "Reference" "#PWR0590"
			(at 170.18 147.32 0)
			(effects
				(font
					(size 1.27 1.27)
				)
				(justify left bottom)
				(hide yes)
			)
		)
		(property "Value" "GND"
			(at 170.18 144.78 0)
			(effects
				(font
					(size 1.27 1.27)
					(thickness 0.15)
				)
			)
		)
		(property "Footprint" ""
			(at 179.07 148.59 0)
			(effects
				(font
					(size 1.27 1.27)
					(thickness 0.15)
				)
				(justify left bottom)
				(hide yes)
			)
		)
		(property "Datasheet" ""
			(at 179.07 153.67 0)
			(effects
				(font
					(size 1.27 1.27)
					(thickness 0.15)
				)
				(justify left bottom)
				(hide yes)
			)
		)
		(property "Description" ""
			(at 170.18 140.97 0)
			(effects
				(font
					(size 1.27 1.27)
				)
				(hide yes)
			)
		)
		(property "Author" "Antmicro"
			(at 179.07 148.59 0)
			(effects
				(font
					(size 1.27 1.27)
					(thickness 0.15)
				)
				(justify left bottom)
				(hide yes)
			)
		)
		(property "License" "Apache-2.0"
			(at 179.07 151.13 0)
			(effects
				(font
					(size 1.27 1.27)
					(thickness 0.15)
				)
				(justify left bottom)
				(hide yes)
			)
		)
		(pin "1"
		)
		(instances
			(project "jetson-agx-thor-baseboard"
				(path ""
					(reference "#PWR0590")
					(unit 1)
				)
			)
		)
	)
	(symbol
		(lib_id "antmicroCapacitors0603:C_22u_16V_0603")
		(at 170.18 226.06 90)
		(unit 1)
		(exclude_from_sim no)
		(in_bom yes)
		(on_board yes)
		(dnp no)
		(property "Reference" "C69"
			(at 170.815 221.615 90)
			(effects
				(font
					(size 1.27 1.27)
				)
				(justify right)
			)
		)
		(property "Value" "C_22u_16V_0603"
			(at 180.34 205.74 0)
			(effects
				(font
					(size 1.27 1.27)
					(thickness 0.15)
				)
				(justify left bottom)
				(hide yes)
			)
		)
		(property "Footprint" "antmicro-footprints:C_0603_1608Metric_EIA"
			(at 182.88 205.74 0)
			(effects
				(font
					(size 1.27 1.27)
					(thickness 0.15)
				)
				(justify left bottom)
				(hide yes)
			)
		)
		(property "Datasheet" "https://product.samsungsem.com/mlcc/CL10A226MO7JZN.do"
			(at 185.42 205.74 0)
			(effects
				(font
					(size 1.27 1.27)
					(thickness 0.15)
				)
				(justify left bottom)
				(hide yes)
			)
		)
		(property "Description" "SMD Multilayer Ceramic Capacitor"
			(at 170.18 226.06 0)
			(effects
				(font
					(size 1.27 1.27)
				)
				(hide yes)
			)
		)
		(property "Manufacturer" "Samsung Electro-Mechanics"
			(at 190.5 205.74 0)
			(effects
				(font
					(size 1.27 1.27)
					(thickness 0.15)
				)
				(justify left bottom)
				(hide yes)
			)
		)
		(property "MPN" "CL10A226MO7JZNC"
			(at 187.96 205.74 0)
			(effects
				(font
					(size 1.27 1.27)
					(thickness 0.15)
				)
				(justify left bottom)
				(hide yes)
			)
		)
		(property "Val" "22u"
			(at 170.815 225.425 90)
			(effects
				(font
					(size 1.27 1.27)
					(thickness 0.15)
				)
				(justify right)
			)
		)
		(property "License" "Apache-2.0"
			(at 193.04 205.74 0)
			(effects
				(font
					(size 1.27 1.27)
					(thickness 0.15)
				)
				(justify left bottom)
				(hide yes)
			)
		)
		(property "Author" "Antmicro"
			(at 195.58 205.74 0)
			(effects
				(font
					(size 1.27 1.27)
					(thickness 0.15)
				)
				(justify left bottom)
				(hide yes)
			)
		)
		(property "Voltage" "16V"
			(at 198.12 205.74 0)
			(effects
				(font
					(size 1.27 1.27)
				)
				(justify left bottom)
				(hide yes)
			)
		)
		(property "Dielectric" ""
			(at 200.66 205.74 0)
			(effects
				(font
					(size 1.27 1.27)
				)
				(justify left bottom)
				(hide yes)
			)
		)
		(pin "1"
		)
		(pin "2"
		)
		(instances
			(project "jetson-agx-thor-baseboard"
				(path ""
					(reference "C69")
					(unit 1)
				)
			)
		)
	)
	(symbol
		(lib_id "antmicropower:GND")
		(at 34.29 279.4 0)
		(unit 1)
		(exclude_from_sim no)
		(in_bom yes)
		(on_board yes)
		(dnp no)
		(property "Reference" "#PWR094"
			(at 34.29 285.75 0)
			(effects
				(font
					(size 1.27 1.27)
				)
				(justify left bottom)
				(hide yes)
			)
		)
		(property "Value" "GND"
			(at 34.29 283.21 0)
			(effects
				(font
					(size 1.27 1.27)
					(thickness 0.15)
				)
			)
		)
		(property "Footprint" ""
			(at 43.18 287.02 0)
			(effects
				(font
					(size 1.27 1.27)
					(thickness 0.15)
				)
				(justify left bottom)
				(hide yes)
			)
		)
		(property "Datasheet" ""
			(at 43.18 292.1 0)
			(effects
				(font
					(size 1.27 1.27)
					(thickness 0.15)
				)
				(justify left bottom)
				(hide yes)
			)
		)
		(property "Description" ""
			(at 34.29 279.4 0)
			(effects
				(font
					(size 1.27 1.27)
				)
				(hide yes)
			)
		)
		(property "Author" "Antmicro"
			(at 43.18 287.02 0)
			(effects
				(font
					(size 1.27 1.27)
					(thickness 0.15)
				)
				(justify left bottom)
				(hide yes)
			)
		)
		(property "License" "Apache-2.0"
			(at 43.18 289.56 0)
			(effects
				(font
					(size 1.27 1.27)
					(thickness 0.15)
				)
				(justify left bottom)
				(hide yes)
			)
		)
		(pin "1"
		)
		(instances
			(project "jetson-agx-thor-baseboard"
				(path ""
					(reference "#PWR094")
					(unit 1)
				)
			)
		)
	)
	(symbol
		(lib_id "antmicropower:GND")
		(at 162.56 110.49 0)
		(unit 1)
		(exclude_from_sim no)
		(in_bom yes)
		(on_board yes)
		(dnp no)
		(property "Reference" "#PWR0556"
			(at 162.56 116.84 0)
			(effects
				(font
					(size 1.27 1.27)
				)
				(justify left bottom)
				(hide yes)
			)
		)
		(property "Value" "GND"
			(at 162.56 114.3 0)
			(effects
				(font
					(size 1.27 1.27)
					(thickness 0.15)
				)
			)
		)
		(property "Footprint" ""
			(at 171.45 118.11 0)
			(effects
				(font
					(size 1.27 1.27)
					(thickness 0.15)
				)
				(justify left bottom)
				(hide yes)
			)
		)
		(property "Datasheet" ""
			(at 171.45 123.19 0)
			(effects
				(font
					(size 1.27 1.27)
					(thickness 0.15)
				)
				(justify left bottom)
				(hide yes)
			)
		)
		(property "Description" ""
			(at 162.56 110.49 0)
			(effects
				(font
					(size 1.27 1.27)
				)
				(hide yes)
			)
		)
		(property "Author" "Antmicro"
			(at 171.45 118.11 0)
			(effects
				(font
					(size 1.27 1.27)
					(thickness 0.15)
				)
				(justify left bottom)
				(hide yes)
			)
		)
		(property "License" "Apache-2.0"
			(at 171.45 120.65 0)
			(effects
				(font
					(size 1.27 1.27)
					(thickness 0.15)
				)
				(justify left bottom)
				(hide yes)
			)
		)
		(pin "1"
		)
		(instances
			(project "jetson-agx-thor-baseboard"
				(path ""
					(reference "#PWR0556")
					(unit 1)
				)
			)
		)
	)
	(symbol
		(lib_id "antmicropower:GND")
		(at 40.64 232.41 0)
		(unit 1)
		(exclude_from_sim no)
		(in_bom yes)
		(on_board yes)
		(dnp no)
		(property "Reference" "#PWR096"
			(at 40.64 238.76 0)
			(effects
				(font
					(size 1.27 1.27)
				)
				(justify left bottom)
				(hide yes)
			)
		)
		(property "Value" "GND"
			(at 40.64 236.22 0)
			(effects
				(font
					(size 1.27 1.27)
					(thickness 0.15)
				)
			)
		)
		(property "Footprint" ""
			(at 49.53 240.03 0)
			(effects
				(font
					(size 1.27 1.27)
					(thickness 0.15)
				)
				(justify left bottom)
				(hide yes)
			)
		)
		(property "Datasheet" ""
			(at 49.53 245.11 0)
			(effects
				(font
					(size 1.27 1.27)
					(thickness 0.15)
				)
				(justify left bottom)
				(hide yes)
			)
		)
		(property "Description" ""
			(at 40.64 232.41 0)
			(effects
				(font
					(size 1.27 1.27)
				)
				(hide yes)
			)
		)
		(property "Author" "Antmicro"
			(at 49.53 240.03 0)
			(effects
				(font
					(size 1.27 1.27)
					(thickness 0.15)
				)
				(justify left bottom)
				(hide yes)
			)
		)
		(property "License" "Apache-2.0"
			(at 49.53 242.57 0)
			(effects
				(font
					(size 1.27 1.27)
					(thickness 0.15)
				)
				(justify left bottom)
				(hide yes)
			)
		)
		(pin "1"
		)
		(instances
			(project "jetson-agx-thor-baseboard"
				(path ""
					(reference "#PWR096")
					(unit 1)
				)
			)
		)
	)
	(symbol
		(lib_id "antmicroCapacitors0402:C_1u_0402")
		(at 74.93 120.65 90)
		(unit 1)
		(exclude_from_sim no)
		(in_bom yes)
		(on_board yes)
		(dnp no)
		(property "Reference" "C279"
			(at 75.565 116.205 90)
			(effects
				(font
					(size 1.27 1.27)
				)
				(justify right)
			)
		)
		(property "Value" "C_1u_0402"
			(at 85.09 100.33 0)
			(effects
				(font
					(size 1.27 1.27)
					(thickness 0.15)
				)
				(justify left bottom)
				(hide yes)
			)
		)
		(property "Footprint" "antmicro-footprints:C_0402_1005Metric"
			(at 87.63 100.33 0)
			(effects
				(font
					(size 1.27 1.27)
					(thickness 0.15)
				)
				(justify left bottom)
				(hide yes)
			)
		)
		(property "Datasheet" "https://product.tdk.com/en/search/capacitor/ceramic/mlcc/info?part_no=C1005X6S1A105K050BC"
			(at 90.17 100.33 0)
			(effects
				(font
					(size 1.27 1.27)
					(thickness 0.15)
				)
				(justify left bottom)
				(hide yes)
			)
		)
		(property "Description" "SMD Multilayer Ceramic Capacitor, 1 µF, 10 V, 0402 [1005 Metric], ± 10%, X6S, C"
			(at 74.93 120.65 0)
			(effects
				(font
					(size 1.27 1.27)
				)
				(hide yes)
			)
		)
		(property "Manufacturer" "TDK"
			(at 95.25 100.33 0)
			(effects
				(font
					(size 1.27 1.27)
					(thickness 0.15)
				)
				(justify left bottom)
				(hide yes)
			)
		)
		(property "MPN" "C1005X6S1A105K050BC"
			(at 92.71 100.33 0)
			(effects
				(font
					(size 1.27 1.27)
					(thickness 0.15)
				)
				(justify left bottom)
				(hide yes)
			)
		)
		(property "Val" "1u"
			(at 75.565 120.015 90)
			(effects
				(font
					(size 1.27 1.27)
					(thickness 0.15)
				)
				(justify right)
			)
		)
		(property "License" "Apache-2.0"
			(at 97.79 100.33 0)
			(effects
				(font
					(size 1.27 1.27)
					(thickness 0.15)
				)
				(justify left bottom)
				(hide yes)
			)
		)
		(property "Author" "Antmicro"
			(at 100.33 100.33 0)
			(effects
				(font
					(size 1.27 1.27)
					(thickness 0.15)
				)
				(justify left bottom)
				(hide yes)
			)
		)
		(property "Voltage" ""
			(at 102.87 100.33 0)
			(effects
				(font
					(size 1.27 1.27)
				)
				(justify left bottom)
				(hide yes)
			)
		)
		(property "Dielectric" ""
			(at 105.41 100.33 0)
			(effects
				(font
					(size 1.27 1.27)
				)
				(justify left bottom)
				(hide yes)
			)
		)
		(pin "1"
		)
		(pin "2"
		)
		(instances
			(project "jetson-agx-thor-baseboard"
				(path ""
					(reference "C279")
					(unit 1)
				)
			)
		)
	)
	(symbol
		(lib_id "antmicropower:GND")
		(at 154.94 44.45 0)
		(unit 1)
		(exclude_from_sim no)
		(in_bom yes)
		(on_board yes)
		(dnp no)
		(property "Reference" "#PWR0534"
			(at 154.94 50.8 0)
			(effects
				(font
					(size 1.27 1.27)
				)
				(justify left bottom)
				(hide yes)
			)
		)
		(property "Value" "GND"
			(at 154.94 48.26 0)
			(effects
				(font
					(size 1.27 1.27)
					(thickness 0.15)
				)
			)
		)
		(property "Footprint" ""
			(at 163.83 52.07 0)
			(effects
				(font
					(size 1.27 1.27)
					(thickness 0.15)
				)
				(justify left bottom)
				(hide yes)
			)
		)
		(property "Datasheet" ""
			(at 163.83 57.15 0)
			(effects
				(font
					(size 1.27 1.27)
					(thickness 0.15)
				)
				(justify left bottom)
				(hide yes)
			)
		)
		(property "Description" ""
			(at 154.94 44.45 0)
			(effects
				(font
					(size 1.27 1.27)
				)
				(hide yes)
			)
		)
		(property "Author" "Antmicro"
			(at 163.83 52.07 0)
			(effects
				(font
					(size 1.27 1.27)
					(thickness 0.15)
				)
				(justify left bottom)
				(hide yes)
			)
		)
		(property "License" "Apache-2.0"
			(at 163.83 54.61 0)
			(effects
				(font
					(size 1.27 1.27)
					(thickness 0.15)
				)
				(justify left bottom)
				(hide yes)
			)
		)
		(pin "1"
		)
		(instances
			(project "jetson-agx-thor-baseboard"
				(path ""
					(reference "#PWR0534")
					(unit 1)
				)
			)
		)
	)
	(symbol
		(lib_id "antmicropower:GND")
		(at 162.56 125.73 0)
		(unit 1)
		(exclude_from_sim no)
		(in_bom yes)
		(on_board yes)
		(dnp no)
		(property "Reference" "#PWR0557"
			(at 162.56 132.08 0)
			(effects
				(font
					(size 1.27 1.27)
				)
				(justify left bottom)
				(hide yes)
			)
		)
		(property "Value" "GND"
			(at 162.56 129.54 0)
			(effects
				(font
					(size 1.27 1.27)
					(thickness 0.15)
				)
			)
		)
		(property "Footprint" ""
			(at 171.45 133.35 0)
			(effects
				(font
					(size 1.27 1.27)
					(thickness 0.15)
				)
				(justify left bottom)
				(hide yes)
			)
		)
		(property "Datasheet" ""
			(at 171.45 138.43 0)
			(effects
				(font
					(size 1.27 1.27)
					(thickness 0.15)
				)
				(justify left bottom)
				(hide yes)
			)
		)
		(property "Description" ""
			(at 162.56 125.73 0)
			(effects
				(font
					(size 1.27 1.27)
				)
				(hide yes)
			)
		)
		(property "Author" "Antmicro"
			(at 171.45 133.35 0)
			(effects
				(font
					(size 1.27 1.27)
					(thickness 0.15)
				)
				(justify left bottom)
				(hide yes)
			)
		)
		(property "License" "Apache-2.0"
			(at 171.45 135.89 0)
			(effects
				(font
					(size 1.27 1.27)
					(thickness 0.15)
				)
				(justify left bottom)
				(hide yes)
			)
		)
		(pin "1"
		)
		(instances
			(project "jetson-agx-thor-baseboard"
				(path ""
					(reference "#PWR0557")
					(unit 1)
				)
			)
		)
	)
	(symbol
		(lib_id "antmicropower:GND")
		(at 355.6 196.85 0)
		(unit 1)
		(exclude_from_sim no)
		(in_bom yes)
		(on_board yes)
		(dnp no)
		(property "Reference" "#PWR057"
			(at 364.49 199.39 0)
			(effects
				(font
					(size 1.27 1.27)
					(thickness 0.15)
				)
				(justify left bottom)
				(hide yes)
			)
		)
		(property "Value" "GND"
			(at 355.6 200.66 0)
			(effects
				(font
					(size 1.27 1.27)
					(thickness 0.15)
				)
			)
		)
		(property "Footprint" ""
			(at 364.49 204.47 0)
			(effects
				(font
					(size 1.27 1.27)
					(thickness 0.15)
				)
				(justify left bottom)
				(hide yes)
			)
		)
		(property "Datasheet" ""
			(at 364.49 209.55 0)
			(effects
				(font
					(size 1.27 1.27)
					(thickness 0.15)
				)
				(justify left bottom)
				(hide yes)
			)
		)
		(property "Description" ""
			(at 355.6 196.85 0)
			(effects
				(font
					(size 1.27 1.27)
				)
				(hide yes)
			)
		)
		(property "Author" "Antmicro"
			(at 364.49 204.47 0)
			(effects
				(font
					(size 1.27 1.27)
					(thickness 0.15)
				)
				(justify left bottom)
				(hide yes)
			)
		)
		(property "License" "Apache-2.0"
			(at 364.49 207.01 0)
			(effects
				(font
					(size 1.27 1.27)
					(thickness 0.15)
				)
				(justify left bottom)
				(hide yes)
			)
		)
		(pin "1"
		)
		(instances
			(project "jetson-agx-thor-baseboard"
				(path ""
					(reference "#PWR057")
					(unit 1)
				)
			)
		)
	)
	(symbol
		(lib_id "antmicroCapacitorsmisc:C_22u_25V_0805")
		(at 170.18 139.7 90)
		(unit 1)
		(exclude_from_sim no)
		(in_bom yes)
		(on_board yes)
		(dnp no)
		(property "Reference" "C293"
			(at 171.958 134.6201 90)
			(effects
				(font
					(size 1.27 1.27)
					(thickness 0.15)
				)
				(justify right)
			)
		)
		(property "Value" "C_22u_25V_0805"
			(at 180.34 119.38 0)
			(effects
				(font
					(size 1.27 1.27)
					(thickness 0.15)
				)
				(justify left bottom)
				(hide yes)
			)
		)
		(property "Footprint" "antmicro-footprints:C_0805_2012Metric"
			(at 182.88 119.38 0)
			(effects
				(font
					(size 1.27 1.27)
					(thickness 0.15)
				)
				(justify left bottom)
				(hide yes)
			)
		)
		(property "Datasheet" "https://product.samsungsem.com/mlcc/CL21A226MAYNNN.do"
			(at 185.42 119.38 0)
			(effects
				(font
					(size 1.27 1.27)
					(thickness 0.15)
				)
				(justify left bottom)
				(hide yes)
			)
		)
		(property "Description" "SMT Multilayer Ceramic Capacitor, 22uF, +/-20%, 25V, X5R, 0805 [2012 Metric]"
			(at 203.2 119.38 0)
			(effects
				(font
					(size 1.27 1.27)
				)
				(justify left bottom)
				(hide yes)
			)
		)
		(property "MPN" "CL21A226MAYNNNE"
			(at 187.96 119.38 0)
			(effects
				(font
					(size 1.27 1.27)
					(thickness 0.15)
				)
				(justify left bottom)
				(hide yes)
			)
		)
		(property "Manufacturer" "Samsung Electro-Mechanics"
			(at 190.5 119.38 0)
			(effects
				(font
					(size 1.27 1.27)
					(thickness 0.15)
				)
				(justify left bottom)
				(hide yes)
			)
		)
		(property "License" "Apache-2.0"
			(at 193.04 119.38 0)
			(effects
				(font
					(size 1.27 1.27)
					(thickness 0.15)
				)
				(justify left bottom)
				(hide yes)
			)
		)
		(property "Author" "Antmicro"
			(at 195.58 119.38 0)
			(effects
				(font
					(size 1.27 1.27)
					(thickness 0.15)
				)
				(justify left bottom)
				(hide yes)
			)
		)
		(property "Val" "22u"
			(at 171.958 137.1601 90)
			(effects
				(font
					(size 1.27 1.27)
					(thickness 0.15)
				)
				(justify right)
			)
		)
		(property "Voltage" "25V"
			(at 171.958 139.7 90)
			(effects
				(font
					(size 1.27 1.27)
				)
				(justify right)
			)
		)
		(property "Dielectric" "X5R"
			(at 200.66 119.38 0)
			(effects
				(font
					(size 1.27 1.27)
				)
				(justify left bottom)
				(hide yes)
			)
		)
		(property "Public" "False"
			(at 203.2 119.38 0)
			(effects
				(font
					(size 1.27 1.27)
				)
				(justify left bottom)
				(hide yes)
			)
		)
		(pin "2"
		)
		(pin "1"
		)
		(instances
			(project "jetson-agx-thor-baseboard"
				(path ""
					(reference "C293")
					(unit 1)
				)
			)
		)
	)
	(symbol
		(lib_id "antmicropower:VCC")
		(at 21.59 205.74 0)
		(unit 1)
		(exclude_from_sim no)
		(in_bom yes)
		(on_board yes)
		(dnp no)
		(property "Reference" "#PWR098"
			(at 21.59 209.55 0)
			(effects
				(font
					(size 1.27 1.27)
				)
				(justify left bottom)
				(hide yes)
			)
		)
		(property "Value" "VCC"
			(at 19.685 201.93 0)
			(effects
				(font
					(size 1.27 1.27)
				)
				(justify left)
			)
		)
		(property "Footprint" ""
			(at 21.59 205.74 0)
			(effects
				(font
					(size 1.27 1.27)
				)
				(hide yes)
			)
		)
		(property "Datasheet" ""
			(at 21.59 205.74 0)
			(effects
				(font
					(size 1.27 1.27)
				)
				(hide yes)
			)
		)
		(property "Description" ""
			(at 21.59 205.74 0)
			(effects
				(font
					(size 1.27 1.27)
				)
				(hide yes)
			)
		)
		(pin "1"
		)
		(instances
			(project "jetson-agx-thor-baseboard"
				(path ""
					(reference "#PWR098")
					(unit 1)
				)
			)
		)
	)
	(symbol
		(lib_id "antmicroResistorsmisc:R_0R001_0805")
		(at 204.47 250.19 0)
		(unit 1)
		(exclude_from_sim no)
		(in_bom yes)
		(on_board yes)
		(dnp no)
		(property "Reference" "R258"
			(at 207.01 245.11 0)
			(effects
				(font
					(size 1.27 1.27)
					(thickness 0.15)
				)
			)
		)
		(property "Value" "R_0R001_0805"
			(at 224.79 262.89 0)
			(effects
				(font
					(size 1.27 1.27)
					(thickness 0.15)
				)
				(justify left bottom)
				(hide yes)
			)
		)
		(property "Footprint" "antmicro-footprints:R_0805_2012Metric"
			(at 224.79 265.43 0)
			(effects
				(font
					(size 1.27 1.27)
					(thickness 0.15)
				)
				(justify left bottom)
				(hide yes)
			)
		)
		(property "Datasheet" "https://www.eaton.com/content/dam/eaton/products/electronic-components/resources/data-sheet/eaton-msma-automotive-smd-current-sense-resistor-metal-strip-data-sheet-elx1179.pdf"
			(at 224.79 267.97 0)
			(effects
				(font
					(size 1.27 1.27)
					(thickness 0.15)
				)
				(justify left bottom)
				(hide yes)
			)
		)
		(property "Description" "Current Sense Resistors - SMD MSMA, 0805 SIZE, 1/2 Watt, 1 mohm, 50 TCR MnCu Metal AEC-Q"
			(at 204.47 250.19 0)
			(effects
				(font
					(size 1.27 1.27)
				)
				(hide yes)
			)
		)
		(property "MPN" "MSMA0805R0010FSM"
			(at 224.79 270.51 0)
			(effects
				(font
					(size 1.27 1.27)
					(thickness 0.15)
				)
				(justify left bottom)
				(hide yes)
			)
		)
		(property "Manufacturer" "Eaton"
			(at 224.79 273.05 0)
			(effects
				(font
					(size 1.27 1.27)
					(thickness 0.15)
				)
				(justify left bottom)
				(hide yes)
			)
		)
		(property "License" "Apache-2.0"
			(at 224.79 275.59 0)
			(effects
				(font
					(size 1.27 1.27)
					(thickness 0.15)
				)
				(justify left bottom)
				(hide yes)
			)
		)
		(property "Author" "Antmicro"
			(at 224.79 278.13 0)
			(effects
				(font
					(size 1.27 1.27)
					(thickness 0.15)
				)
				(justify left bottom)
				(hide yes)
			)
		)
		(property "Val" "0R001"
			(at 207.01 247.65 0)
			(effects
				(font
					(size 1.27 1.27)
					(thickness 0.15)
				)
			)
		)
		(property "Tolerance" "1%"
			(at 224.79 260.35 0)
			(effects
				(font
					(size 1.27 1.27)
				)
				(justify left bottom)
				(hide yes)
			)
		)
		(property "Public" "False"
			(at 224.79 280.67 0)
			(effects
				(font
					(size 1.27 1.27)
				)
				(justify left bottom)
				(hide yes)
			)
		)
		(pin "2"
		)
		(pin "1"
		)
		(instances
			(project "jetson-agx-thor-baseboard"
				(path ""
					(reference "R258")
					(unit 1)
				)
			)
		)
	)
	(symbol
		(lib_id "antmicropower:GND")
		(at 336.55 130.81 0)
		(unit 1)
		(exclude_from_sim no)
		(in_bom yes)
		(on_board yes)
		(dnp no)
		(property "Reference" "#PWR0623"
			(at 345.44 133.35 0)
			(effects
				(font
					(size 1.27 1.27)
					(thickness 0.15)
				)
				(justify left bottom)
				(hide yes)
			)
		)
		(property "Value" "GND"
			(at 336.55 134.62 0)
			(effects
				(font
					(size 1.27 1.27)
					(thickness 0.15)
				)
			)
		)
		(property "Footprint" ""
			(at 345.44 138.43 0)
			(effects
				(font
					(size 1.27 1.27)
					(thickness 0.15)
				)
				(justify left bottom)
				(hide yes)
			)
		)
		(property "Datasheet" ""
			(at 345.44 143.51 0)
			(effects
				(font
					(size 1.27 1.27)
					(thickness 0.15)
				)
				(justify left bottom)
				(hide yes)
			)
		)
		(property "Description" ""
			(at 336.55 130.81 0)
			(effects
				(font
					(size 1.27 1.27)
				)
				(hide yes)
			)
		)
		(property "Author" "Antmicro"
			(at 345.44 138.43 0)
			(effects
				(font
					(size 1.27 1.27)
					(thickness 0.15)
				)
				(justify left bottom)
				(hide yes)
			)
		)
		(property "License" "Apache-2.0"
			(at 345.44 140.97 0)
			(effects
				(font
					(size 1.27 1.27)
					(thickness 0.15)
				)
				(justify left bottom)
				(hide yes)
			)
		)
		(pin "1"
		)
		(instances
			(project "jetson-agx-thor-baseboard"
				(path ""
					(reference "#PWR0623")
					(unit 1)
				)
			)
		)
	)
	(symbol
		(lib_id "antmicropower:GND")
		(at 115.57 232.41 0)
		(unit 1)
		(exclude_from_sim no)
		(in_bom yes)
		(on_board yes)
		(dnp no)
		(property "Reference" "#PWR0120"
			(at 115.57 238.76 0)
			(effects
				(font
					(size 1.27 1.27)
				)
				(justify left bottom)
				(hide yes)
			)
		)
		(property "Value" "GND"
			(at 115.57 236.22 0)
			(effects
				(font
					(size 1.27 1.27)
					(thickness 0.15)
				)
			)
		)
		(property "Footprint" ""
			(at 124.46 240.03 0)
			(effects
				(font
					(size 1.27 1.27)
					(thickness 0.15)
				)
				(justify left bottom)
				(hide yes)
			)
		)
		(property "Datasheet" ""
			(at 124.46 245.11 0)
			(effects
				(font
					(size 1.27 1.27)
					(thickness 0.15)
				)
				(justify left bottom)
				(hide yes)
			)
		)
		(property "Description" ""
			(at 115.57 232.41 0)
			(effects
				(font
					(size 1.27 1.27)
				)
				(hide yes)
			)
		)
		(property "Author" "Antmicro"
			(at 124.46 240.03 0)
			(effects
				(font
					(size 1.27 1.27)
					(thickness 0.15)
				)
				(justify left bottom)
				(hide yes)
			)
		)
		(property "License" "Apache-2.0"
			(at 124.46 242.57 0)
			(effects
				(font
					(size 1.27 1.27)
					(thickness 0.15)
				)
				(justify left bottom)
				(hide yes)
			)
		)
		(pin "1"
		)
		(instances
			(project "jetson-agx-thor-baseboard"
				(path ""
					(reference "#PWR0120")
					(unit 1)
				)
			)
		)
	)
	(symbol
		(lib_id "antmicroResistors0402:R_200k_0402")
		(at 64.77 278.13 90)
		(unit 1)
		(exclude_from_sim no)
		(in_bom yes)
		(on_board yes)
		(dnp no)
		(property "Reference" "R43"
			(at 66.04 274.32 90)
			(effects
				(font
					(size 1.27 1.27)
					(thickness 0.15)
				)
				(justify right)
			)
		)
		(property "Value" "R_200k_0402"
			(at 77.47 257.81 0)
			(effects
				(font
					(size 1.27 1.27)
					(thickness 0.15)
				)
				(justify left bottom)
				(hide yes)
			)
		)
		(property "Footprint" "antmicro-footprints:R_0402_1005Metric"
			(at 80.01 257.81 0)
			(effects
				(font
					(size 1.27 1.27)
					(thickness 0.15)
				)
				(justify left bottom)
				(hide yes)
			)
		)
		(property "Datasheet" "https://www.bourns.com/docs/product-datasheets/cr.pdf"
			(at 82.55 257.81 0)
			(effects
				(font
					(size 1.27 1.27)
					(thickness 0.15)
				)
				(justify left bottom)
				(hide yes)
			)
		)
		(property "Description" "SMD Chip Resistor, 200 kohm, ± 1%, 62.5 mW, 0402 [1005 Metric], Thick Film, General Purpose"
			(at 64.77 278.13 0)
			(effects
				(font
					(size 1.27 1.27)
				)
				(hide yes)
			)
		)
		(property "MPN" "CR0402-FX-2003GLF"
			(at 85.09 257.81 0)
			(effects
				(font
					(size 1.27 1.27)
					(thickness 0.15)
				)
				(justify left bottom)
				(hide yes)
			)
		)
		(property "Manufacturer" "Bourns"
			(at 87.63 257.81 0)
			(effects
				(font
					(size 1.27 1.27)
					(thickness 0.15)
				)
				(justify left bottom)
				(hide yes)
			)
		)
		(property "License" "Apache-2.0"
			(at 90.17 257.81 0)
			(effects
				(font
					(size 1.27 1.27)
					(thickness 0.15)
				)
				(justify left bottom)
				(hide yes)
			)
		)
		(property "Author" "Antmicro"
			(at 92.71 257.81 0)
			(effects
				(font
					(size 1.27 1.27)
					(thickness 0.15)
				)
				(justify left bottom)
				(hide yes)
			)
		)
		(property "Val" "200k"
			(at 66.04 276.86 90)
			(effects
				(font
					(size 1.27 1.27)
					(thickness 0.15)
				)
				(justify right)
			)
		)
		(property "Tolerance" "1%"
			(at 74.93 257.81 0)
			(effects
				(font
					(size 1.27 1.27)
				)
				(justify left bottom)
				(hide yes)
			)
		)
		(pin "2"
		)
		(pin "1"
		)
		(instances
			(project "jetson-agx-thor-baseboard"
				(path ""
					(reference "R43")
					(unit 1)
				)
			)
		)
	)
	(symbol
		(lib_id "antmicropower:PWR_FLAG")
		(at 398.78 38.1 270)
		(unit 1)
		(exclude_from_sim no)
		(in_bom yes)
		(on_board yes)
		(dnp no)
		(property "Reference" "#FLG021"
			(at 400.685 38.1 0)
			(effects
				(font
					(size 1.27 1.27)
				)
				(hide yes)
			)
		)
		(property "Value" "PWR_FLAG"
			(at 402.336 40.64 90)
			(effects
				(font
					(size 1.27 1.27)
				)
			)
		)
		(property "Footprint" ""
			(at 398.78 38.1 0)
			(effects
				(font
					(size 1.27 1.27)
				)
				(hide yes)
			)
		)
		(property "Datasheet" ""
			(at 398.78 38.1 0)
			(effects
				(font
					(size 1.27 1.27)
				)
				(hide yes)
			)
		)
		(property "Description" ""
			(at 398.78 38.1 0)
			(effects
				(font
					(size 1.27 1.27)
				)
				(hide yes)
			)
		)
		(pin "1"
		)
		(instances
			(project "jetson-agx-thor-baseboard"
				(path ""
					(reference "#FLG021")
					(unit 1)
				)
			)
		)
	)
	(symbol
		(lib_id "antmicroDCDCConverters:SIC437AED-T1-GE3")
		(at 92.71 30.48 0)
		(unit 1)
		(exclude_from_sim no)
		(in_bom yes)
		(on_board yes)
		(dnp no)
		(property "Reference" "U11"
			(at 103.505 24.13 0)
			(effects
				(font
					(size 1.27 1.27)
					(thickness 0.15)
				)
			)
		)
		(property "Value" "SIC437AED-T1-GE3"
			(at 125.73 38.1 0)
			(effects
				(font
					(size 1.27 1.27)
					(thickness 0.15)
				)
				(justify left bottom)
				(hide yes)
			)
		)
		(property "Footprint" "antmicro-footprints:MLP44-24L_4x4x0.75mm"
			(at 125.73 40.64 0)
			(effects
				(font
					(size 1.27 1.27)
					(thickness 0.15)
				)
				(justify left bottom)
				(hide yes)
			)
		)
		(property "Datasheet" "https://www.vishay.com/docs/75921/sic437.pdf"
			(at 125.73 43.18 0)
			(effects
				(font
					(size 1.27 1.27)
					(thickness 0.15)
				)
				(justify left bottom)
				(hide yes)
			)
		)
		(property "Description" "DC/DC Buck Step Down Regulator Adjustable, 4.5-28V In, 0.6V to 20V/12A Out, 1MHz, PowerPAK MLP44-24"
			(at 125.73 53.34 0)
			(effects
				(font
					(size 1.27 1.27)
				)
				(justify left bottom)
				(hide yes)
			)
		)
		(property "Manufacturer" "Vishay"
			(at 125.73 45.72 0)
			(effects
				(font
					(size 1.27 1.27)
					(thickness 0.15)
				)
				(justify left bottom)
				(hide yes)
			)
		)
		(property "MPN" "SIC437AED-T1-GE3"
			(at 103.505 26.67 0)
			(effects
				(font
					(size 1.27 1.27)
					(thickness 0.15)
				)
			)
		)
		(property "Author" "Antmicro"
			(at 125.73 48.26 0)
			(effects
				(font
					(size 1.27 1.27)
					(thickness 0.15)
				)
				(justify left bottom)
				(hide yes)
			)
		)
		(property "License" "Apache-2.0"
			(at 125.73 50.8 0)
			(effects
				(font
					(size 1.27 1.27)
					(thickness 0.15)
				)
				(justify left bottom)
				(hide yes)
			)
		)
		(pin "7"
		)
		(pin "16"
		)
		(pin "18"
		)
		(pin "8"
		)
		(pin "15"
		)
		(pin "14"
		)
		(pin "20"
		)
		(pin "2"
		)
		(pin "12"
		)
		(pin "22"
		)
		(pin "11"
		)
		(pin "26"
		)
		(pin "10"
		)
		(pin "19"
		)
		(pin "5"
		)
		(pin "4"
		)
		(pin "17"
		)
		(pin "6"
		)
		(pin "3"
		)
		(pin "1"
		)
		(pin "13"
		)
		(pin "23"
		)
		(pin "25"
		)
		(pin "21"
		)
		(pin "24"
		)
		(pin "9"
		)
		(pin "27"
		)
		(pin "28"
		)
		(instances
			(project "jetson-agx-thor-baseboard"
				(path ""
					(reference "U11")
					(unit 1)
				)
			)
		)
	)
	(symbol
		(lib_id "antmicroCapacitorsmisc:C_22u_25V_0805")
		(at 177.8 73.66 90)
		(unit 1)
		(exclude_from_sim no)
		(in_bom yes)
		(on_board yes)
		(dnp no)
		(property "Reference" "C294"
			(at 179.324 68.5801 90)
			(effects
				(font
					(size 1.27 1.27)
					(thickness 0.15)
				)
				(justify right)
			)
		)
		(property "Value" "C_22u_25V_0805"
			(at 187.96 53.34 0)
			(effects
				(font
					(size 1.27 1.27)
					(thickness 0.15)
				)
				(justify left bottom)
				(hide yes)
			)
		)
		(property "Footprint" "antmicro-footprints:C_0805_2012Metric"
			(at 190.5 53.34 0)
			(effects
				(font
					(size 1.27 1.27)
					(thickness 0.15)
				)
				(justify left bottom)
				(hide yes)
			)
		)
		(property "Datasheet" "https://product.samsungsem.com/mlcc/CL21A226MAYNNN.do"
			(at 193.04 53.34 0)
			(effects
				(font
					(size 1.27 1.27)
					(thickness 0.15)
				)
				(justify left bottom)
				(hide yes)
			)
		)
		(property "Description" "SMT Multilayer Ceramic Capacitor, 22uF, +/-20%, 25V, X5R, 0805 [2012 Metric]"
			(at 210.82 53.34 0)
			(effects
				(font
					(size 1.27 1.27)
				)
				(justify left bottom)
				(hide yes)
			)
		)
		(property "MPN" "CL21A226MAYNNNE"
			(at 195.58 53.34 0)
			(effects
				(font
					(size 1.27 1.27)
					(thickness 0.15)
				)
				(justify left bottom)
				(hide yes)
			)
		)
		(property "Manufacturer" "Samsung Electro-Mechanics"
			(at 198.12 53.34 0)
			(effects
				(font
					(size 1.27 1.27)
					(thickness 0.15)
				)
				(justify left bottom)
				(hide yes)
			)
		)
		(property "License" "Apache-2.0"
			(at 200.66 53.34 0)
			(effects
				(font
					(size 1.27 1.27)
					(thickness 0.15)
				)
				(justify left bottom)
				(hide yes)
			)
		)
		(property "Author" "Antmicro"
			(at 203.2 53.34 0)
			(effects
				(font
					(size 1.27 1.27)
					(thickness 0.15)
				)
				(justify left bottom)
				(hide yes)
			)
		)
		(property "Val" "22u"
			(at 179.324 71.1201 90)
			(effects
				(font
					(size 1.27 1.27)
					(thickness 0.15)
				)
				(justify right)
			)
		)
		(property "Voltage" "25V"
			(at 179.324 73.66 90)
			(effects
				(font
					(size 1.27 1.27)
				)
				(justify right)
			)
		)
		(property "Dielectric" "X5R"
			(at 208.28 53.34 0)
			(effects
				(font
					(size 1.27 1.27)
				)
				(justify left bottom)
				(hide yes)
			)
		)
		(property "Public" "False"
			(at 210.82 53.34 0)
			(effects
				(font
					(size 1.27 1.27)
				)
				(justify left bottom)
				(hide yes)
			)
		)
		(pin "2"
		)
		(pin "1"
		)
		(instances
			(project "jetson-agx-thor-baseboard"
				(path ""
					(reference "C294")
					(unit 1)
				)
			)
		)
	)
	(symbol
		(lib_id "antmicropower:GND")
		(at 363.22 58.42 0)
		(unit 1)
		(exclude_from_sim no)
		(in_bom yes)
		(on_board yes)
		(dnp no)
		(property "Reference" "#PWR068"
			(at 363.22 64.77 0)
			(effects
				(font
					(size 1.27 1.27)
				)
				(justify left bottom)
				(hide yes)
			)
		)
		(property "Value" "GND"
			(at 363.22 62.23 0)
			(effects
				(font
					(size 1.27 1.27)
					(thickness 0.15)
				)
			)
		)
		(property "Footprint" ""
			(at 372.11 66.04 0)
			(effects
				(font
					(size 1.27 1.27)
					(thickness 0.15)
				)
				(justify left bottom)
				(hide yes)
			)
		)
		(property "Datasheet" ""
			(at 372.11 71.12 0)
			(effects
				(font
					(size 1.27 1.27)
					(thickness 0.15)
				)
				(justify left bottom)
				(hide yes)
			)
		)
		(property "Description" ""
			(at 363.22 58.42 0)
			(effects
				(font
					(size 1.27 1.27)
				)
				(hide yes)
			)
		)
		(property "Author" "Antmicro"
			(at 372.11 66.04 0)
			(effects
				(font
					(size 1.27 1.27)
					(thickness 0.15)
				)
				(justify left bottom)
				(hide yes)
			)
		)
		(property "License" "Apache-2.0"
			(at 372.11 68.58 0)
			(effects
				(font
					(size 1.27 1.27)
					(thickness 0.15)
				)
				(justify left bottom)
				(hide yes)
			)
		)
		(pin "1"
		)
		(instances
			(project "jetson-agx-thor-baseboard"
				(path ""
					(reference "#PWR068")
					(unit 1)
				)
			)
		)
	)
	(symbol
		(lib_id "antmicroCapacitorsmisc:C_22u_25V_0805")
		(at 262.89 43.18 90)
		(unit 1)
		(exclude_from_sim no)
		(in_bom yes)
		(on_board yes)
		(dnp no)
		(property "Reference" "C29"
			(at 264.922 38.1 90)
			(effects
				(font
					(size 1.27 1.27)
				)
				(justify right)
			)
		)
		(property "Value" "C_22u_25V_0805"
			(at 273.05 22.86 0)
			(effects
				(font
					(size 1.27 1.27)
					(thickness 0.15)
				)
				(justify left bottom)
				(hide yes)
			)
		)
		(property "Footprint" "antmicro-footprints:C_0805_2012Metric"
			(at 275.59 22.86 0)
			(effects
				(font
					(size 1.27 1.27)
					(thickness 0.15)
				)
				(justify left bottom)
				(hide yes)
			)
		)
		(property "Datasheet" "https://product.samsungsem.com/mlcc/CL21A226MAYNNN.do"
			(at 278.13 22.86 0)
			(effects
				(font
					(size 1.27 1.27)
					(thickness 0.15)
				)
				(justify left bottom)
				(hide yes)
			)
		)
		(property "Description" "SMT Multilayer Ceramic Capacitor, 22uF, +/-20%, 25V, X5R, 0805 [2012 Metric]"
			(at 262.89 43.18 0)
			(effects
				(font
					(size 1.27 1.27)
				)
				(hide yes)
			)
		)
		(property "Manufacturer" "Samsung Electro-Mechanics"
			(at 283.21 22.86 0)
			(effects
				(font
					(size 1.27 1.27)
					(thickness 0.15)
				)
				(justify left bottom)
				(hide yes)
			)
		)
		(property "MPN" "CL21A226MAYNNNE"
			(at 280.67 22.86 0)
			(effects
				(font
					(size 1.27 1.27)
					(thickness 0.15)
				)
				(justify left bottom)
				(hide yes)
			)
		)
		(property "Val" "22u"
			(at 264.922 40.6401 90)
			(effects
				(font
					(size 1.27 1.27)
					(thickness 0.15)
				)
				(justify right)
			)
		)
		(property "License" "Apache-2.0"
			(at 285.75 22.86 0)
			(effects
				(font
					(size 1.27 1.27)
					(thickness 0.15)
				)
				(justify left bottom)
				(hide yes)
			)
		)
		(property "Author" "Antmicro"
			(at 288.29 22.86 0)
			(effects
				(font
					(size 1.27 1.27)
					(thickness 0.15)
				)
				(justify left bottom)
				(hide yes)
			)
		)
		(property "Voltage" "25V"
			(at 264.922 43.18 90)
			(effects
				(font
					(size 1.27 1.27)
				)
				(justify right)
			)
		)
		(property "Dielectric" "X5R"
			(at 293.37 22.86 0)
			(effects
				(font
					(size 1.27 1.27)
				)
				(justify left bottom)
				(hide yes)
			)
		)
		(property "Public" "False"
			(at 295.91 22.86 0)
			(effects
				(font
					(size 1.27 1.27)
				)
				(justify left bottom)
				(hide yes)
			)
		)
		(pin "1"
		)
		(pin "2"
		)
		(instances
			(project "jetson-agx-thor-baseboard"
				(path ""
					(reference "C29")
					(unit 1)
				)
			)
		)
	)
	(symbol
		(lib_id "antmicroCapacitors0402:C_100n_0402")
		(at 209.55 210.82 180)
		(unit 1)
		(exclude_from_sim no)
		(in_bom yes)
		(on_board yes)
		(dnp no)
		(property "Reference" "C383"
			(at 207.01 205.486 0)
			(effects
				(font
					(size 1.27 1.27)
				)
			)
		)
		(property "Value" "C_100n_0402"
			(at 189.23 200.66 0)
			(effects
				(font
					(size 1.27 1.27)
					(thickness 0.15)
				)
				(justify left bottom)
				(hide yes)
			)
		)
		(property "Footprint" "antmicro-footprints:C_0402_1005Metric"
			(at 189.23 198.12 0)
			(effects
				(font
					(size 1.27 1.27)
					(thickness 0.15)
				)
				(justify left bottom)
				(hide yes)
			)
		)
		(property "Datasheet" "https://www.murata.com/products/productdetail?partno=GRM155R61H104KE14%23"
			(at 189.23 195.58 0)
			(effects
				(font
					(size 1.27 1.27)
					(thickness 0.15)
				)
				(justify left bottom)
				(hide yes)
			)
		)
		(property "Description" "SMD Multilayer Ceramic Capacitor, 0.1 µF, 50 V, 0402 [1005 Metric], ± 10%, X5R, GRM Series"
			(at 209.55 210.82 0)
			(effects
				(font
					(size 1.27 1.27)
				)
				(hide yes)
			)
		)
		(property "Manufacturer" "Murata"
			(at 189.23 190.5 0)
			(effects
				(font
					(size 1.27 1.27)
					(thickness 0.15)
				)
				(justify left bottom)
				(hide yes)
			)
		)
		(property "MPN" "GRM155R61H104KE14D"
			(at 189.23 193.04 0)
			(effects
				(font
					(size 1.27 1.27)
					(thickness 0.15)
				)
				(justify left bottom)
				(hide yes)
			)
		)
		(property "Val" "100n"
			(at 207.01 208.026 0)
			(effects
				(font
					(size 1.27 1.27)
					(thickness 0.15)
				)
			)
		)
		(property "License" "Apache-2.0"
			(at 189.23 187.96 0)
			(effects
				(font
					(size 1.27 1.27)
					(thickness 0.15)
				)
				(justify left bottom)
				(hide yes)
			)
		)
		(property "Author" "Antmicro"
			(at 189.23 185.42 0)
			(effects
				(font
					(size 1.27 1.27)
					(thickness 0.15)
				)
				(justify left bottom)
				(hide yes)
			)
		)
		(property "Voltage" "50V"
			(at 189.23 182.88 0)
			(effects
				(font
					(size 1.27 1.27)
				)
				(justify left bottom)
				(hide yes)
			)
		)
		(property "Dielectric" "X5R"
			(at 189.23 180.34 0)
			(effects
				(font
					(size 1.27 1.27)
				)
				(justify left bottom)
				(hide yes)
			)
		)
		(pin "1"
		)
		(pin "2"
		)
		(instances
			(project "jetson-agx-thor-baseboard"
				(path ""
					(reference "C383")
					(unit 1)
				)
			)
		)
	)
	(symbol
		(lib_id "antmicroCapacitorsmisc:C_22u_25V_0805")
		(at 170.18 109.22 90)
		(unit 1)
		(exclude_from_sim no)
		(in_bom yes)
		(on_board yes)
		(dnp no)
		(property "Reference" "C291"
			(at 171.958 104.1401 90)
			(effects
				(font
					(size 1.27 1.27)
					(thickness 0.15)
				)
				(justify right)
			)
		)
		(property "Value" "C_22u_25V_0805"
			(at 180.34 88.9 0)
			(effects
				(font
					(size 1.27 1.27)
					(thickness 0.15)
				)
				(justify left bottom)
				(hide yes)
			)
		)
		(property "Footprint" "antmicro-footprints:C_0805_2012Metric"
			(at 182.88 88.9 0)
			(effects
				(font
					(size 1.27 1.27)
					(thickness 0.15)
				)
				(justify left bottom)
				(hide yes)
			)
		)
		(property "Datasheet" "https://product.samsungsem.com/mlcc/CL21A226MAYNNN.do"
			(at 185.42 88.9 0)
			(effects
				(font
					(size 1.27 1.27)
					(thickness 0.15)
				)
				(justify left bottom)
				(hide yes)
			)
		)
		(property "Description" "SMT Multilayer Ceramic Capacitor, 22uF, +/-20%, 25V, X5R, 0805 [2012 Metric]"
			(at 203.2 88.9 0)
			(effects
				(font
					(size 1.27 1.27)
				)
				(justify left bottom)
				(hide yes)
			)
		)
		(property "MPN" "CL21A226MAYNNNE"
			(at 187.96 88.9 0)
			(effects
				(font
					(size 1.27 1.27)
					(thickness 0.15)
				)
				(justify left bottom)
				(hide yes)
			)
		)
		(property "Manufacturer" "Samsung Electro-Mechanics"
			(at 190.5 88.9 0)
			(effects
				(font
					(size 1.27 1.27)
					(thickness 0.15)
				)
				(justify left bottom)
				(hide yes)
			)
		)
		(property "License" "Apache-2.0"
			(at 193.04 88.9 0)
			(effects
				(font
					(size 1.27 1.27)
					(thickness 0.15)
				)
				(justify left bottom)
				(hide yes)
			)
		)
		(property "Author" "Antmicro"
			(at 195.58 88.9 0)
			(effects
				(font
					(size 1.27 1.27)
					(thickness 0.15)
				)
				(justify left bottom)
				(hide yes)
			)
		)
		(property "Val" "22u"
			(at 171.958 106.6801 90)
			(effects
				(font
					(size 1.27 1.27)
					(thickness 0.15)
				)
				(justify right)
			)
		)
		(property "Voltage" "25V"
			(at 171.958 109.22 90)
			(effects
				(font
					(size 1.27 1.27)
				)
				(justify right)
			)
		)
		(property "Dielectric" "X5R"
			(at 200.66 88.9 0)
			(effects
				(font
					(size 1.27 1.27)
				)
				(justify left bottom)
				(hide yes)
			)
		)
		(property "Public" "False"
			(at 203.2 88.9 0)
			(effects
				(font
					(size 1.27 1.27)
				)
				(justify left bottom)
				(hide yes)
			)
		)
		(pin "2"
		)
		(pin "1"
		)
		(instances
			(project "jetson-agx-thor-baseboard"
				(path ""
					(reference "C291")
					(unit 1)
				)
			)
		)
	)
	(symbol
		(lib_id "antmicroCapacitors0402:C_100n_0402")
		(at 48.26 100.33 270)
		(unit 1)
		(exclude_from_sim no)
		(in_bom yes)
		(on_board yes)
		(dnp no)
		(property "Reference" "C278"
			(at 48.895 100.965 90)
			(effects
				(font
					(size 1.27 1.27)
				)
				(justify left)
			)
		)
		(property "Value" "C_100n_0402"
			(at 38.1 120.65 0)
			(effects
				(font
					(size 1.27 1.27)
					(thickness 0.15)
				)
				(justify left bottom)
				(hide yes)
			)
		)
		(property "Footprint" "antmicro-footprints:C_0402_1005Metric"
			(at 35.56 120.65 0)
			(effects
				(font
					(size 1.27 1.27)
					(thickness 0.15)
				)
				(justify left bottom)
				(hide yes)
			)
		)
		(property "Datasheet" "https://www.murata.com/products/productdetail?partno=GRM155R61H104KE14%23"
			(at 33.02 120.65 0)
			(effects
				(font
					(size 1.27 1.27)
					(thickness 0.15)
				)
				(justify left bottom)
				(hide yes)
			)
		)
		(property "Description" "SMD Multilayer Ceramic Capacitor, 0.1 µF, 50 V, 0402 [1005 Metric], ± 10%, X5R, GRM Series"
			(at 48.26 100.33 0)
			(effects
				(font
					(size 1.27 1.27)
				)
				(hide yes)
			)
		)
		(property "Manufacturer" "Murata"
			(at 27.94 120.65 0)
			(effects
				(font
					(size 1.27 1.27)
					(thickness 0.15)
				)
				(justify left bottom)
				(hide yes)
			)
		)
		(property "MPN" "GRM155R61H104KE14D"
			(at 30.48 120.65 0)
			(effects
				(font
					(size 1.27 1.27)
					(thickness 0.15)
				)
				(justify left bottom)
				(hide yes)
			)
		)
		(property "Val" "100n"
			(at 48.895 104.775 90)
			(effects
				(font
					(size 1.27 1.27)
					(thickness 0.15)
				)
				(justify left)
			)
		)
		(property "License" "Apache-2.0"
			(at 25.4 120.65 0)
			(effects
				(font
					(size 1.27 1.27)
					(thickness 0.15)
				)
				(justify left bottom)
				(hide yes)
			)
		)
		(property "Author" "Antmicro"
			(at 22.86 120.65 0)
			(effects
				(font
					(size 1.27 1.27)
					(thickness 0.15)
				)
				(justify left bottom)
				(hide yes)
			)
		)
		(property "Voltage" "50V"
			(at 20.32 120.65 0)
			(effects
				(font
					(size 1.27 1.27)
				)
				(justify left bottom)
				(hide yes)
			)
		)
		(property "Dielectric" "X5R"
			(at 17.78 120.65 0)
			(effects
				(font
					(size 1.27 1.27)
				)
				(justify left bottom)
				(hide yes)
			)
		)
		(pin "1"
		)
		(pin "2"
		)
		(instances
			(project "jetson-agx-thor-baseboard"
				(path ""
					(reference "C278")
					(unit 1)
				)
			)
		)
	)
	(symbol
		(lib_id "antmicropower:VCC")
		(at 251.46 31.75 0)
		(unit 1)
		(exclude_from_sim no)
		(in_bom yes)
		(on_board yes)
		(dnp no)
		(property "Reference" "#PWR045"
			(at 251.46 35.56 0)
			(effects
				(font
					(size 1.27 1.27)
				)
				(justify left bottom)
				(hide yes)
			)
		)
		(property "Value" "VCC"
			(at 249.555 27.94 0)
			(effects
				(font
					(size 1.27 1.27)
				)
				(justify left)
			)
		)
		(property "Footprint" ""
			(at 251.46 31.75 0)
			(effects
				(font
					(size 1.27 1.27)
				)
				(hide yes)
			)
		)
		(property "Datasheet" ""
			(at 251.46 31.75 0)
			(effects
				(font
					(size 1.27 1.27)
				)
				(hide yes)
			)
		)
		(property "Description" ""
			(at 251.46 31.75 0)
			(effects
				(font
					(size 1.27 1.27)
				)
				(hide yes)
			)
		)
		(pin "1"
		)
		(instances
			(project "jetson-agx-thor-baseboard"
				(path ""
					(reference "#PWR045")
					(unit 1)
				)
			)
		)
	)
	(symbol
		(lib_id "antmicroDCDCConverters:SIC437AED-T1-GE3")
		(at 312.42 33.02 0)
		(unit 1)
		(exclude_from_sim no)
		(in_bom yes)
		(on_board yes)
		(dnp no)
		(property "Reference" "U8"
			(at 323.215 26.67 0)
			(effects
				(font
					(size 1.27 1.27)
					(thickness 0.15)
				)
			)
		)
		(property "Value" "SIC437AED-T1-GE3"
			(at 345.44 40.64 0)
			(effects
				(font
					(size 1.27 1.27)
					(thickness 0.15)
				)
				(justify left bottom)
				(hide yes)
			)
		)
		(property "Footprint" "antmicro-footprints:MLP44-24L_4x4x0.75mm"
			(at 345.44 43.18 0)
			(effects
				(font
					(size 1.27 1.27)
					(thickness 0.15)
				)
				(justify left bottom)
				(hide yes)
			)
		)
		(property "Datasheet" "https://www.vishay.com/docs/75921/sic437.pdf"
			(at 345.44 45.72 0)
			(effects
				(font
					(size 1.27 1.27)
					(thickness 0.15)
				)
				(justify left bottom)
				(hide yes)
			)
		)
		(property "Description" "DC/DC Buck Step Down Regulator Adjustable, 4.5-28V In, 0.6V to 20V/12A Out, 1MHz, PowerPAK MLP44-24"
			(at 345.44 55.88 0)
			(effects
				(font
					(size 1.27 1.27)
				)
				(justify left bottom)
				(hide yes)
			)
		)
		(property "Manufacturer" "Vishay"
			(at 345.44 48.26 0)
			(effects
				(font
					(size 1.27 1.27)
					(thickness 0.15)
				)
				(justify left bottom)
				(hide yes)
			)
		)
		(property "MPN" "SIC437AED-T1-GE3"
			(at 323.215 29.21 0)
			(effects
				(font
					(size 1.27 1.27)
					(thickness 0.15)
				)
			)
		)
		(property "Author" "Antmicro"
			(at 345.44 50.8 0)
			(effects
				(font
					(size 1.27 1.27)
					(thickness 0.15)
				)
				(justify left bottom)
				(hide yes)
			)
		)
		(property "License" "Apache-2.0"
			(at 345.44 53.34 0)
			(effects
				(font
					(size 1.27 1.27)
					(thickness 0.15)
				)
				(justify left bottom)
				(hide yes)
			)
		)
		(pin "7"
		)
		(pin "16"
		)
		(pin "18"
		)
		(pin "8"
		)
		(pin "15"
		)
		(pin "14"
		)
		(pin "20"
		)
		(pin "2"
		)
		(pin "12"
		)
		(pin "22"
		)
		(pin "11"
		)
		(pin "26"
		)
		(pin "10"
		)
		(pin "19"
		)
		(pin "5"
		)
		(pin "4"
		)
		(pin "17"
		)
		(pin "6"
		)
		(pin "3"
		)
		(pin "1"
		)
		(pin "13"
		)
		(pin "23"
		)
		(pin "25"
		)
		(pin "21"
		)
		(pin "24"
		)
		(pin "9"
		)
		(pin "27"
		)
		(pin "28"
		)
		(instances
			(project "jetson-agx-thor-baseboard"
				(path ""
					(reference "U8")
					(unit 1)
				)
			)
		)
	)
	(symbol
		(lib_id "antmicroResistors0402:R_12k_0402")
		(at 336.55 196.85 90)
		(unit 1)
		(exclude_from_sim no)
		(in_bom yes)
		(on_board yes)
		(dnp no)
		(fields_autoplaced yes)
		(property "Reference" "R16"
			(at 339.09 193.04 90)
			(effects
				(font
					(size 1.27 1.27)
					(thickness 0.15)
				)
				(justify right)
			)
		)
		(property "Value" "R_12k_0402"
			(at 349.25 176.53 0)
			(effects
				(font
					(size 1.27 1.27)
					(thickness 0.15)
				)
				(justify left bottom)
				(hide yes)
			)
		)
		(property "Footprint" "antmicro-footprints:R_0402_1005Metric"
			(at 351.79 176.53 0)
			(effects
				(font
					(size 1.27 1.27)
					(thickness 0.15)
				)
				(justify left bottom)
				(hide yes)
			)
		)
		(property "Datasheet" "https://www.bourns.com/docs/product-datasheets/cr.pdf"
			(at 354.33 176.53 0)
			(effects
				(font
					(size 1.27 1.27)
					(thickness 0.15)
				)
				(justify left bottom)
				(hide yes)
			)
		)
		(property "Description" "SMD Chip Resistor, 12 kohm, ± 1%, 62.5 mW, 0402 [1005 Metric], Thick Film, General Purpose"
			(at 336.55 196.85 0)
			(effects
				(font
					(size 1.27 1.27)
				)
				(hide yes)
			)
		)
		(property "MPN" "CR0402-FX-1202GLF"
			(at 356.87 176.53 0)
			(effects
				(font
					(size 1.27 1.27)
					(thickness 0.15)
				)
				(justify left bottom)
				(hide yes)
			)
		)
		(property "Manufacturer" "Bourns"
			(at 359.41 176.53 0)
			(effects
				(font
					(size 1.27 1.27)
					(thickness 0.15)
				)
				(justify left bottom)
				(hide yes)
			)
		)
		(property "License" "Apache-2.0"
			(at 361.95 176.53 0)
			(effects
				(font
					(size 1.27 1.27)
					(thickness 0.15)
				)
				(justify left bottom)
				(hide yes)
			)
		)
		(property "Author" "Antmicro"
			(at 364.49 176.53 0)
			(effects
				(font
					(size 1.27 1.27)
					(thickness 0.15)
				)
				(justify left bottom)
				(hide yes)
			)
		)
		(property "Val" "12k"
			(at 339.09 195.58 90)
			(effects
				(font
					(size 1.27 1.27)
					(thickness 0.15)
				)
				(justify right)
			)
		)
		(property "Tolerance" "1%"
			(at 346.71 176.53 0)
			(effects
				(font
					(size 1.27 1.27)
				)
				(justify left bottom)
				(hide yes)
			)
		)
		(pin "1"
		)
		(pin "2"
		)
		(instances
			(project "jetson-agx-thor-baseboard"
				(path ""
					(reference "R16")
					(unit 1)
				)
			)
		)
	)
	(symbol
		(lib_id "antmicropower:+5V")
		(at 397.51 36.83 0)
		(unit 1)
		(exclude_from_sim no)
		(in_bom yes)
		(on_board yes)
		(dnp no)
		(property "Reference" "#PWR090"
			(at 397.51 40.64 0)
			(effects
				(font
					(size 1.27 1.27)
				)
				(justify left bottom)
				(hide yes)
			)
		)
		(property "Value" "+12V"
			(at 397.51 32.512 0)
			(effects
				(font
					(size 1.27 1.27)
					(thickness 0.15)
				)
			)
		)
		(property "Footprint" ""
			(at 412.75 44.45 0)
			(effects
				(font
					(size 1.27 1.27)
					(thickness 0.15)
				)
				(justify left bottom)
				(hide yes)
			)
		)
		(property "Datasheet" ""
			(at 412.75 46.99 0)
			(effects
				(font
					(size 1.27 1.27)
					(thickness 0.15)
				)
				(justify left bottom)
				(hide yes)
			)
		)
		(property "Description" ""
			(at 397.51 36.83 0)
			(effects
				(font
					(size 1.27 1.27)
				)
				(hide yes)
			)
		)
		(property "Author" "Antmicro"
			(at 412.75 44.45 0)
			(effects
				(font
					(size 1.27 1.27)
					(thickness 0.15)
				)
				(justify left bottom)
				(hide yes)
			)
		)
		(property "License" "Apache-2.0"
			(at 412.75 46.99 0)
			(effects
				(font
					(size 1.27 1.27)
					(thickness 0.15)
				)
				(justify left bottom)
				(hide yes)
			)
		)
		(pin "1"
		)
		(instances
			(project "jetson-agx-thor-baseboard"
				(path ""
					(reference "#PWR090")
					(unit 1)
				)
			)
		)
	)
	(symbol
		(lib_id "antmicropower:GND")
		(at 266.7 128.27 0)
		(unit 1)
		(exclude_from_sim no)
		(in_bom yes)
		(on_board yes)
		(dnp no)
		(property "Reference" "#PWR0620"
			(at 275.59 130.81 0)
			(effects
				(font
					(size 1.27 1.27)
					(thickness 0.15)
				)
				(justify left bottom)
				(hide yes)
			)
		)
		(property "Value" "GND"
			(at 266.7 132.08 0)
			(effects
				(font
					(size 1.27 1.27)
					(thickness 0.15)
				)
			)
		)
		(property "Footprint" ""
			(at 275.59 135.89 0)
			(effects
				(font
					(size 1.27 1.27)
					(thickness 0.15)
				)
				(justify left bottom)
				(hide yes)
			)
		)
		(property "Datasheet" ""
			(at 275.59 140.97 0)
			(effects
				(font
					(size 1.27 1.27)
					(thickness 0.15)
				)
				(justify left bottom)
				(hide yes)
			)
		)
		(property "Description" ""
			(at 266.7 128.27 0)
			(effects
				(font
					(size 1.27 1.27)
				)
				(hide yes)
			)
		)
		(property "Author" "Antmicro"
			(at 275.59 135.89 0)
			(effects
				(font
					(size 1.27 1.27)
					(thickness 0.15)
				)
				(justify left bottom)
				(hide yes)
			)
		)
		(property "License" "Apache-2.0"
			(at 275.59 138.43 0)
			(effects
				(font
					(size 1.27 1.27)
					(thickness 0.15)
				)
				(justify left bottom)
				(hide yes)
			)
		)
		(pin "1"
		)
		(instances
			(project "jetson-agx-thor-baseboard"
				(path ""
					(reference "#PWR0620")
					(unit 1)
				)
			)
		)
	)
	(symbol
		(lib_id "antmicroCapacitors0402:C_100n_0402")
		(at 26.67 186.69 90)
		(unit 1)
		(exclude_from_sim no)
		(in_bom yes)
		(on_board yes)
		(dnp no)
		(fields_autoplaced yes)
		(property "Reference" "C6"
			(at 28.448 182.88 90)
			(effects
				(font
					(size 1.27 1.27)
					(thickness 0.15)
				)
				(justify right)
			)
		)
		(property "Value" "C_100n_0402"
			(at 36.83 166.37 0)
			(effects
				(font
					(size 1.27 1.27)
					(thickness 0.15)
				)
				(justify left bottom)
				(hide yes)
			)
		)
		(property "Footprint" "antmicro-footprints:C_0402_1005Metric"
			(at 39.37 166.37 0)
			(effects
				(font
					(size 1.27 1.27)
					(thickness 0.15)
				)
				(justify left bottom)
				(hide yes)
			)
		)
		(property "Datasheet" "https://www.murata.com/products/productdetail?partno=GRM155R61H104KE14%23"
			(at 41.91 166.37 0)
			(effects
				(font
					(size 1.27 1.27)
					(thickness 0.15)
				)
				(justify left bottom)
				(hide yes)
			)
		)
		(property "Description" "SMD Multilayer Ceramic Capacitor, 0.1 µF, 50 V, 0402 [1005 Metric], ± 10%, X5R, GRM Series"
			(at 59.69 166.37 0)
			(effects
				(font
					(size 1.27 1.27)
				)
				(justify left bottom)
				(hide yes)
			)
		)
		(property "MPN" "GRM155R61H104KE14D"
			(at 44.45 166.37 0)
			(effects
				(font
					(size 1.27 1.27)
					(thickness 0.15)
				)
				(justify left bottom)
				(hide yes)
			)
		)
		(property "Manufacturer" "Murata"
			(at 46.99 166.37 0)
			(effects
				(font
					(size 1.27 1.27)
					(thickness 0.15)
				)
				(justify left bottom)
				(hide yes)
			)
		)
		(property "License" "Apache-2.0"
			(at 49.53 166.37 0)
			(effects
				(font
					(size 1.27 1.27)
					(thickness 0.15)
				)
				(justify left bottom)
				(hide yes)
			)
		)
		(property "Author" "Antmicro"
			(at 52.07 166.37 0)
			(effects
				(font
					(size 1.27 1.27)
					(thickness 0.15)
				)
				(justify left bottom)
				(hide yes)
			)
		)
		(property "Val" "100n"
			(at 28.702 185.166 90)
			(effects
				(font
					(size 1.27 1.27)
					(thickness 0.15)
				)
				(justify right)
			)
		)
		(property "Voltage" "50V"
			(at 54.61 166.37 0)
			(effects
				(font
					(size 1.27 1.27)
				)
				(justify left bottom)
				(hide yes)
			)
		)
		(property "Dielectric" "X5R"
			(at 57.15 166.37 0)
			(effects
				(font
					(size 1.27 1.27)
				)
				(justify left bottom)
				(hide yes)
			)
		)
		(pin "1"
		)
		(pin "2"
		)
		(instances
			(project ""
				(path ""
					(reference "C6")
					(unit 1)
				)
			)
		)
	)
	(symbol
		(lib_id "antmicroResistors0603:R_0R_22.4A_0603")
		(at 367.03 182.88 0)
		(unit 1)
		(exclude_from_sim no)
		(in_bom yes)
		(on_board yes)
		(dnp no)
		(property "Reference" "R7"
			(at 369.57 178.562 0)
			(effects
				(font
					(size 1.27 1.27)
				)
			)
		)
		(property "Value" "R_0R_22.4A_0603"
			(at 369.57 173.99 0)
			(effects
				(font
					(size 1.27 1.27)
					(thickness 0.15)
				)
				(hide yes)
			)
		)
		(property "Footprint" "antmicro-footprints:R_0603_1608Metric"
			(at 382.27 193.04 0)
			(effects
				(font
					(size 1.27 1.27)
					(thickness 0.15)
				)
				(justify left bottom)
				(hide yes)
			)
		)
		(property "Datasheet" "https://fscdn.rohm.com/en/products/databook/datasheet/passive/resistor/chip_resistor/pmr-jpw-e.pdf"
			(at 382.27 195.58 0)
			(effects
				(font
					(size 1.27 1.27)
					(thickness 0.15)
				)
				(justify left bottom)
				(hide yes)
			)
		)
		(property "Description" "SMD Chip Resistor"
			(at 367.03 182.88 0)
			(effects
				(font
					(size 1.27 1.27)
				)
				(hide yes)
			)
		)
		(property "Manufacturer" "ROHM Semiconductor"
			(at 382.27 200.66 0)
			(effects
				(font
					(size 1.27 1.27)
					(thickness 0.15)
				)
				(justify left bottom)
				(hide yes)
			)
		)
		(property "MPN" "PMR03EZPJ000"
			(at 382.27 198.12 0)
			(effects
				(font
					(size 1.27 1.27)
					(thickness 0.15)
				)
				(justify left bottom)
				(hide yes)
			)
		)
		(property "Val" "0R"
			(at 369.57 180.34 0)
			(effects
				(font
					(size 1.27 1.27)
					(thickness 0.15)
				)
			)
		)
		(property "Author" "Antmicro"
			(at 382.27 205.74 0)
			(effects
				(font
					(size 1.27 1.27)
					(thickness 0.15)
				)
				(justify left bottom)
				(hide yes)
			)
		)
		(property "License" "Apache-2.0"
			(at 382.27 208.28 0)
			(effects
				(font
					(size 1.27 1.27)
					(thickness 0.15)
				)
				(justify left bottom)
				(hide yes)
			)
		)
		(property "Max. Curr." "22.4A"
			(at 369.57 185.42 0)
			(effects
				(font
					(size 1.27 1.27)
					(thickness 0.15)
				)
			)
		)
		(property "Tolerance" "template_tolerance"
			(at 387.35 193.04 0)
			(effects
				(font
					(size 1.27 1.27)
				)
				(justify left bottom)
				(hide yes)
			)
		)
		(pin "1"
		)
		(pin "2"
		)
		(instances
			(project "jetson-agx-thor-baseboard"
				(path ""
					(reference "R7")
					(unit 1)
				)
			)
		)
	)
	(symbol
		(lib_id "antmicropower:GND")
		(at 21.59 41.91 0)
		(unit 1)
		(exclude_from_sim no)
		(in_bom yes)
		(on_board yes)
		(dnp no)
		(property "Reference" "#PWR0582"
			(at 21.59 48.26 0)
			(effects
				(font
					(size 1.27 1.27)
				)
				(justify left bottom)
				(hide yes)
			)
		)
		(property "Value" "GND"
			(at 21.59 45.72 0)
			(effects
				(font
					(size 1.27 1.27)
					(thickness 0.15)
				)
			)
		)
		(property "Footprint" ""
			(at 30.48 49.53 0)
			(effects
				(font
					(size 1.27 1.27)
					(thickness 0.15)
				)
				(justify left bottom)
				(hide yes)
			)
		)
		(property "Datasheet" ""
			(at 30.48 54.61 0)
			(effects
				(font
					(size 1.27 1.27)
					(thickness 0.15)
				)
				(justify left bottom)
				(hide yes)
			)
		)
		(property "Description" ""
			(at 21.59 41.91 0)
			(effects
				(font
					(size 1.27 1.27)
				)
				(hide yes)
			)
		)
		(property "Author" "Antmicro"
			(at 30.48 49.53 0)
			(effects
				(font
					(size 1.27 1.27)
					(thickness 0.15)
				)
				(justify left bottom)
				(hide yes)
			)
		)
		(property "License" "Apache-2.0"
			(at 30.48 52.07 0)
			(effects
				(font
					(size 1.27 1.27)
					(thickness 0.15)
				)
				(justify left bottom)
				(hide yes)
			)
		)
		(pin "1"
		)
		(instances
			(project "jetson-agx-thor-baseboard"
				(path ""
					(reference "#PWR0582")
					(unit 1)
				)
			)
		)
	)
	(symbol
		(lib_id "antmicropower:GND")
		(at 177.8 232.41 0)
		(unit 1)
		(exclude_from_sim no)
		(in_bom yes)
		(on_board yes)
		(dnp no)
		(property "Reference" "#PWR0148"
			(at 177.8 238.76 0)
			(effects
				(font
					(size 1.27 1.27)
				)
				(justify left bottom)
				(hide yes)
			)
		)
		(property "Value" "GND"
			(at 177.8 236.22 0)
			(effects
				(font
					(size 1.27 1.27)
					(thickness 0.15)
				)
			)
		)
		(property "Footprint" ""
			(at 186.69 240.03 0)
			(effects
				(font
					(size 1.27 1.27)
					(thickness 0.15)
				)
				(justify left bottom)
				(hide yes)
			)
		)
		(property "Datasheet" ""
			(at 186.69 245.11 0)
			(effects
				(font
					(size 1.27 1.27)
					(thickness 0.15)
				)
				(justify left bottom)
				(hide yes)
			)
		)
		(property "Description" ""
			(at 177.8 232.41 0)
			(effects
				(font
					(size 1.27 1.27)
				)
				(hide yes)
			)
		)
		(property "Author" "Antmicro"
			(at 186.69 240.03 0)
			(effects
				(font
					(size 1.27 1.27)
					(thickness 0.15)
				)
				(justify left bottom)
				(hide yes)
			)
		)
		(property "License" "Apache-2.0"
			(at 186.69 242.57 0)
			(effects
				(font
					(size 1.27 1.27)
					(thickness 0.15)
				)
				(justify left bottom)
				(hide yes)
			)
		)
		(pin "1"
		)
		(instances
			(project "jetson-agx-thor-baseboard"
				(path ""
					(reference "#PWR0148")
					(unit 1)
				)
			)
		)
	)
	(symbol
		(lib_id "antmicropower:GND")
		(at 115.57 55.88 0)
		(unit 1)
		(exclude_from_sim no)
		(in_bom yes)
		(on_board yes)
		(dnp no)
		(property "Reference" "#PWR0532"
			(at 115.57 62.23 0)
			(effects
				(font
					(size 1.27 1.27)
				)
				(justify left bottom)
				(hide yes)
			)
		)
		(property "Value" "GND"
			(at 115.57 59.69 0)
			(effects
				(font
					(size 1.27 1.27)
					(thickness 0.15)
				)
			)
		)
		(property "Footprint" ""
			(at 124.46 63.5 0)
			(effects
				(font
					(size 1.27 1.27)
					(thickness 0.15)
				)
				(justify left bottom)
				(hide yes)
			)
		)
		(property "Datasheet" ""
			(at 124.46 68.58 0)
			(effects
				(font
					(size 1.27 1.27)
					(thickness 0.15)
				)
				(justify left bottom)
				(hide yes)
			)
		)
		(property "Description" ""
			(at 115.57 55.88 0)
			(effects
				(font
					(size 1.27 1.27)
				)
				(hide yes)
			)
		)
		(property "Author" "Antmicro"
			(at 124.46 63.5 0)
			(effects
				(font
					(size 1.27 1.27)
					(thickness 0.15)
				)
				(justify left bottom)
				(hide yes)
			)
		)
		(property "License" "Apache-2.0"
			(at 124.46 66.04 0)
			(effects
				(font
					(size 1.27 1.27)
					(thickness 0.15)
				)
				(justify left bottom)
				(hide yes)
			)
		)
		(pin "1"
		)
		(instances
			(project "jetson-agx-thor-baseboard"
				(path ""
					(reference "#PWR0532")
					(unit 1)
				)
			)
		)
	)
	(symbol
		(lib_id "antmicroResistors0402:R_10k_0402")
		(at 143.51 49.53 90)
		(unit 1)
		(exclude_from_sim no)
		(in_bom yes)
		(on_board yes)
		(dnp no)
		(property "Reference" "R70"
			(at 144.78 45.72 90)
			(effects
				(font
					(size 1.27 1.27)
					(thickness 0.15)
				)
				(justify right)
			)
		)
		(property "Value" "R_10k_0402"
			(at 156.21 29.21 0)
			(effects
				(font
					(size 1.27 1.27)
					(thickness 0.15)
				)
				(justify left bottom)
				(hide yes)
			)
		)
		(property "Footprint" "antmicro-footprints:R_0402_1005Metric"
			(at 158.75 29.21 0)
			(effects
				(font
					(size 1.27 1.27)
					(thickness 0.15)
				)
				(justify left bottom)
				(hide yes)
			)
		)
		(property "Datasheet" "https://www.bourns.com/docs/product-datasheets/cr.pdf"
			(at 161.29 29.21 0)
			(effects
				(font
					(size 1.27 1.27)
					(thickness 0.15)
				)
				(justify left bottom)
				(hide yes)
			)
		)
		(property "Description" "SMD Chip Resistor, 10 kohm, ± 1%, 62.5 mW, 0402 [1005 Metric], Thick Film, General Purpose"
			(at 143.51 49.53 0)
			(effects
				(font
					(size 1.27 1.27)
				)
				(hide yes)
			)
		)
		(property "MPN" "CR0402-FX-1002GLF"
			(at 163.83 29.21 0)
			(effects
				(font
					(size 1.27 1.27)
					(thickness 0.15)
				)
				(justify left bottom)
				(hide yes)
			)
		)
		(property "Manufacturer" "Bourns"
			(at 166.37 29.21 0)
			(effects
				(font
					(size 1.27 1.27)
					(thickness 0.15)
				)
				(justify left bottom)
				(hide yes)
			)
		)
		(property "License" "Apache-2.0"
			(at 168.91 29.21 0)
			(effects
				(font
					(size 1.27 1.27)
					(thickness 0.15)
				)
				(justify left bottom)
				(hide yes)
			)
		)
		(property "Author" "Antmicro"
			(at 171.45 29.21 0)
			(effects
				(font
					(size 1.27 1.27)
					(thickness 0.15)
				)
				(justify left bottom)
				(hide yes)
			)
		)
		(property "Val" "10k"
			(at 144.78 48.26 90)
			(effects
				(font
					(size 1.27 1.27)
					(thickness 0.15)
				)
				(justify right)
			)
		)
		(property "Tolerance" "1%"
			(at 153.67 29.21 0)
			(effects
				(font
					(size 1.27 1.27)
				)
				(justify left bottom)
				(hide yes)
			)
		)
		(pin "2"
		)
		(pin "1"
		)
		(instances
			(project "jetson-agx-thor-baseboard"
				(path ""
					(reference "R70")
					(unit 1)
				)
			)
		)
	)
	(symbol
		(lib_id "antmicropower:GND")
		(at 215.9 190.5 0)
		(unit 1)
		(exclude_from_sim no)
		(in_bom yes)
		(on_board yes)
		(dnp no)
		(property "Reference" "#PWR0657"
			(at 224.79 193.04 0)
			(effects
				(font
					(size 1.27 1.27)
					(thickness 0.15)
				)
				(justify left bottom)
				(hide yes)
			)
		)
		(property "Value" "GND"
			(at 219.202 192.024 0)
			(effects
				(font
					(size 1.27 1.27)
					(thickness 0.15)
				)
			)
		)
		(property "Footprint" ""
			(at 224.79 198.12 0)
			(effects
				(font
					(size 1.27 1.27)
					(thickness 0.15)
				)
				(justify left bottom)
				(hide yes)
			)
		)
		(property "Datasheet" ""
			(at 224.79 203.2 0)
			(effects
				(font
					(size 1.27 1.27)
					(thickness 0.15)
				)
				(justify left bottom)
				(hide yes)
			)
		)
		(property "Description" ""
			(at 215.9 190.5 0)
			(effects
				(font
					(size 1.27 1.27)
				)
				(hide yes)
			)
		)
		(property "Author" "Antmicro"
			(at 224.79 198.12 0)
			(effects
				(font
					(size 1.27 1.27)
					(thickness 0.15)
				)
				(justify left bottom)
				(hide yes)
			)
		)
		(property "License" "Apache-2.0"
			(at 224.79 200.66 0)
			(effects
				(font
					(size 1.27 1.27)
					(thickness 0.15)
				)
				(justify left bottom)
				(hide yes)
			)
		)
		(pin "1"
		)
		(instances
			(project "jetson-agx-thor-baseboard"
				(path ""
					(reference "#PWR0657")
					(unit 1)
				)
			)
		)
	)
	(symbol
		(lib_id "antmicroCapacitorsmisc:C_22u_25V_0805")
		(at 185.42 109.22 90)
		(unit 1)
		(exclude_from_sim no)
		(in_bom yes)
		(on_board yes)
		(dnp no)
		(property "Reference" "C301"
			(at 187.198 104.1401 90)
			(effects
				(font
					(size 1.27 1.27)
					(thickness 0.15)
				)
				(justify right)
			)
		)
		(property "Value" "C_22u_25V_0805"
			(at 195.58 88.9 0)
			(effects
				(font
					(size 1.27 1.27)
					(thickness 0.15)
				)
				(justify left bottom)
				(hide yes)
			)
		)
		(property "Footprint" "antmicro-footprints:C_0805_2012Metric"
			(at 198.12 88.9 0)
			(effects
				(font
					(size 1.27 1.27)
					(thickness 0.15)
				)
				(justify left bottom)
				(hide yes)
			)
		)
		(property "Datasheet" "https://product.samsungsem.com/mlcc/CL21A226MAYNNN.do"
			(at 200.66 88.9 0)
			(effects
				(font
					(size 1.27 1.27)
					(thickness 0.15)
				)
				(justify left bottom)
				(hide yes)
			)
		)
		(property "Description" "SMT Multilayer Ceramic Capacitor, 22uF, +/-20%, 25V, X5R, 0805 [2012 Metric]"
			(at 218.44 88.9 0)
			(effects
				(font
					(size 1.27 1.27)
				)
				(justify left bottom)
				(hide yes)
			)
		)
		(property "MPN" "CL21A226MAYNNNE"
			(at 203.2 88.9 0)
			(effects
				(font
					(size 1.27 1.27)
					(thickness 0.15)
				)
				(justify left bottom)
				(hide yes)
			)
		)
		(property "Manufacturer" "Samsung Electro-Mechanics"
			(at 205.74 88.9 0)
			(effects
				(font
					(size 1.27 1.27)
					(thickness 0.15)
				)
				(justify left bottom)
				(hide yes)
			)
		)
		(property "License" "Apache-2.0"
			(at 208.28 88.9 0)
			(effects
				(font
					(size 1.27 1.27)
					(thickness 0.15)
				)
				(justify left bottom)
				(hide yes)
			)
		)
		(property "Author" "Antmicro"
			(at 210.82 88.9 0)
			(effects
				(font
					(size 1.27 1.27)
					(thickness 0.15)
				)
				(justify left bottom)
				(hide yes)
			)
		)
		(property "Val" "22u"
			(at 187.198 106.6801 90)
			(effects
				(font
					(size 1.27 1.27)
					(thickness 0.15)
				)
				(justify right)
			)
		)
		(property "Voltage" "25V"
			(at 187.198 109.22 90)
			(effects
				(font
					(size 1.27 1.27)
				)
				(justify right)
			)
		)
		(property "Dielectric" "X5R"
			(at 215.9 88.9 0)
			(effects
				(font
					(size 1.27 1.27)
				)
				(justify left bottom)
				(hide yes)
			)
		)
		(property "Public" "False"
			(at 218.44 88.9 0)
			(effects
				(font
					(size 1.27 1.27)
				)
				(justify left bottom)
				(hide yes)
			)
		)
		(pin "2"
		)
		(pin "1"
		)
		(instances
			(project "jetson-agx-thor-baseboard"
				(path ""
					(reference "C301")
					(unit 1)
				)
			)
		)
	)
	(symbol
		(lib_id "antmicropower:GND")
		(at 176.53 176.53 0)
		(unit 1)
		(exclude_from_sim no)
		(in_bom yes)
		(on_board yes)
		(dnp no)
		(property "Reference" "#PWR0652"
			(at 176.53 182.88 0)
			(effects
				(font
					(size 1.27 1.27)
				)
				(justify left bottom)
				(hide yes)
			)
		)
		(property "Value" "GND"
			(at 176.53 180.34 0)
			(effects
				(font
					(size 1.27 1.27)
					(thickness 0.15)
				)
			)
		)
		(property "Footprint" ""
			(at 185.42 184.15 0)
			(effects
				(font
					(size 1.27 1.27)
					(thickness 0.15)
				)
				(justify left bottom)
				(hide yes)
			)
		)
		(property "Datasheet" ""
			(at 185.42 189.23 0)
			(effects
				(font
					(size 1.27 1.27)
					(thickness 0.15)
				)
				(justify left bottom)
				(hide yes)
			)
		)
		(property "Description" ""
			(at 176.53 176.53 0)
			(effects
				(font
					(size 1.27 1.27)
				)
				(hide yes)
			)
		)
		(property "Author" "Antmicro"
			(at 185.42 184.15 0)
			(effects
				(font
					(size 1.27 1.27)
					(thickness 0.15)
				)
				(justify left bottom)
				(hide yes)
			)
		)
		(property "License" "Apache-2.0"
			(at 185.42 186.69 0)
			(effects
				(font
					(size 1.27 1.27)
					(thickness 0.15)
				)
				(justify left bottom)
				(hide yes)
			)
		)
		(pin "1"
		)
		(instances
			(project "jetson-agx-thor-baseboard"
				(path ""
					(reference "#PWR0652")
					(unit 1)
				)
			)
		)
	)
	(symbol
		(lib_id "antmicroResistors0402:R_27R_0402")
		(at 198.12 256.54 270)
		(mirror x)
		(unit 1)
		(exclude_from_sim no)
		(in_bom yes)
		(on_board yes)
		(dnp no)
		(property "Reference" "R316"
			(at 196.85 252.7299 90)
			(effects
				(font
					(size 1.27 1.27)
				)
				(justify right)
			)
		)
		(property "Value" "R_27R_0402"
			(at 185.42 236.22 0)
			(effects
				(font
					(size 1.27 1.27)
					(thickness 0.15)
				)
				(justify left bottom)
				(hide yes)
			)
		)
		(property "Footprint" "antmicro-footprints:R_0402_1005Metric"
			(at 182.88 236.22 0)
			(effects
				(font
					(size 1.27 1.27)
					(thickness 0.15)
				)
				(justify left bottom)
				(hide yes)
			)
		)
		(property "Datasheet" "https://www.bourns.com/docs/product-datasheets/cr.pdf"
			(at 180.34 236.22 0)
			(effects
				(font
					(size 1.27 1.27)
					(thickness 0.15)
				)
				(justify left bottom)
				(hide yes)
			)
		)
		(property "Description" "SMD Chip Resistor, 27 ohm, ± 1%, 63 mW, 0402 [1005 Metric], Thick Film, General Purpose"
			(at 198.12 256.54 0)
			(effects
				(font
					(size 1.27 1.27)
				)
				(hide yes)
			)
		)
		(property "Manufacturer" "Bourns"
			(at 175.26 236.22 0)
			(effects
				(font
					(size 1.27 1.27)
					(thickness 0.15)
				)
				(justify left bottom)
				(hide yes)
			)
		)
		(property "MPN" "CR0402-FX-27R0GLF"
			(at 177.8 236.22 0)
			(effects
				(font
					(size 1.27 1.27)
					(thickness 0.15)
				)
				(justify left bottom)
				(hide yes)
			)
		)
		(property "Val" "27R"
			(at 196.85 255.27 90)
			(effects
				(font
					(size 1.27 1.27)
					(thickness 0.15)
				)
				(justify right)
			)
		)
		(property "License" "Apache-2.0"
			(at 172.72 236.22 0)
			(effects
				(font
					(size 1.27 1.27)
					(thickness 0.15)
				)
				(justify left bottom)
				(hide yes)
			)
		)
		(property "Author" "Antmicro"
			(at 170.18 236.22 0)
			(effects
				(font
					(size 1.27 1.27)
					(thickness 0.15)
				)
				(justify left bottom)
				(hide yes)
			)
		)
		(property "Tolerance" "1%"
			(at 187.96 236.22 0)
			(effects
				(font
					(size 1.27 1.27)
				)
				(justify left bottom)
				(hide yes)
			)
		)
		(pin "1"
		)
		(pin "2"
		)
		(instances
			(project "jetson-agx-thor-baseboard"
				(path ""
					(reference "R316")
					(unit 1)
				)
			)
		)
	)
	(symbol
		(lib_id "antmicroCapacitorsmisc:C_22u_25V_0805")
		(at 153.67 175.26 90)
		(unit 1)
		(exclude_from_sim no)
		(in_bom yes)
		(on_board yes)
		(dnp no)
		(property "Reference" "C378"
			(at 155.448 170.1801 90)
			(effects
				(font
					(size 1.27 1.27)
					(thickness 0.15)
				)
				(justify right)
			)
		)
		(property "Value" "C_22u_25V_0805"
			(at 163.83 154.94 0)
			(effects
				(font
					(size 1.27 1.27)
					(thickness 0.15)
				)
				(justify left bottom)
				(hide yes)
			)
		)
		(property "Footprint" "antmicro-footprints:C_0805_2012Metric"
			(at 166.37 154.94 0)
			(effects
				(font
					(size 1.27 1.27)
					(thickness 0.15)
				)
				(justify left bottom)
				(hide yes)
			)
		)
		(property "Datasheet" "https://product.samsungsem.com/mlcc/CL21A226MAYNNN.do"
			(at 168.91 154.94 0)
			(effects
				(font
					(size 1.27 1.27)
					(thickness 0.15)
				)
				(justify left bottom)
				(hide yes)
			)
		)
		(property "Description" "SMT Multilayer Ceramic Capacitor, 22uF, +/-20%, 25V, X5R, 0805 [2012 Metric]"
			(at 186.69 154.94 0)
			(effects
				(font
					(size 1.27 1.27)
				)
				(justify left bottom)
				(hide yes)
			)
		)
		(property "MPN" "CL21A226MAYNNNE"
			(at 171.45 154.94 0)
			(effects
				(font
					(size 1.27 1.27)
					(thickness 0.15)
				)
				(justify left bottom)
				(hide yes)
			)
		)
		(property "Manufacturer" "Samsung Electro-Mechanics"
			(at 173.99 154.94 0)
			(effects
				(font
					(size 1.27 1.27)
					(thickness 0.15)
				)
				(justify left bottom)
				(hide yes)
			)
		)
		(property "License" "Apache-2.0"
			(at 176.53 154.94 0)
			(effects
				(font
					(size 1.27 1.27)
					(thickness 0.15)
				)
				(justify left bottom)
				(hide yes)
			)
		)
		(property "Author" "Antmicro"
			(at 179.07 154.94 0)
			(effects
				(font
					(size 1.27 1.27)
					(thickness 0.15)
				)
				(justify left bottom)
				(hide yes)
			)
		)
		(property "Val" "22u"
			(at 155.448 172.7201 90)
			(effects
				(font
					(size 1.27 1.27)
					(thickness 0.15)
				)
				(justify right)
			)
		)
		(property "Voltage" "25V"
			(at 155.448 175.26 90)
			(effects
				(font
					(size 1.27 1.27)
				)
				(justify right)
			)
		)
		(property "Dielectric" "X5R"
			(at 184.15 154.94 0)
			(effects
				(font
					(size 1.27 1.27)
				)
				(justify left bottom)
				(hide yes)
			)
		)
		(property "Public" "False"
			(at 186.69 154.94 0)
			(effects
				(font
					(size 1.27 1.27)
				)
				(justify left bottom)
				(hide yes)
			)
		)
		(pin "2"
		)
		(pin "1"
		)
		(instances
			(project "jetson-agx-thor-baseboard"
				(path ""
					(reference "C378")
					(unit 1)
				)
			)
		)
	)
	(symbol
		(lib_id "antmicroPowerMeasurement:INA219AIDCNR")
		(at 204.47 49.53 0)
		(unit 1)
		(exclude_from_sim no)
		(in_bom yes)
		(on_board yes)
		(dnp no)
		(property "Reference" "U22"
			(at 211.836 64.77 0)
			(effects
				(font
					(size 1.27 1.27)
				)
			)
		)
		(property "Value" "INA219AIDCNR"
			(at 204.47 49.53 0)
			(effects
				(font
					(size 1.27 1.27)
				)
				(hide yes)
			)
		)
		(property "Footprint" "antmicro-footprints:SOT-23-8"
			(at 204.47 49.53 0)
			(effects
				(font
					(size 1.27 1.27)
				)
				(hide yes)
			)
		)
		(property "Datasheet" "https://www.ti.com/lit/ds/symlink/ina219.pdf?ts=1713856455637&ref_url=https%253A%252F%252Fwww.mouser.es%252F"
			(at 204.47 49.53 0)
			(effects
				(font
					(size 1.27 1.27)
				)
				(hide yes)
			)
		)
		(property "Description" "Zerø-Drift, Bidirectional Current/Power Monitor With I2C Interface"
			(at 204.47 49.53 0)
			(effects
				(font
					(size 1.27 1.27)
				)
				(hide yes)
			)
		)
		(property "Manufacturer" "Texas Instruments"
			(at 204.47 49.53 0)
			(effects
				(font
					(size 1.27 1.27)
				)
				(hide yes)
			)
		)
		(property "MPN" "INA219AIDCNR"
			(at 211.836 67.31 0)
			(effects
				(font
					(size 1.27 1.27)
				)
			)
		)
		(property "Author" "Antmicro"
			(at 229.87 69.85 0)
			(effects
				(font
					(size 1.27 1.27)
					(thickness 0.15)
				)
				(justify left bottom)
				(hide yes)
			)
		)
		(property "License" "Apache-2.0"
			(at 229.87 72.39 0)
			(effects
				(font
					(size 1.27 1.27)
					(thickness 0.15)
				)
				(justify left bottom)
				(hide yes)
			)
		)
		(pin "1"
		)
		(pin "2"
		)
		(pin "5"
		)
		(pin "6"
		)
		(pin "8"
		)
		(pin "3"
		)
		(pin "7"
		)
		(pin "4"
		)
		(instances
			(project "jetson-agx-thor-baseboard"
				(path ""
					(reference "U22")
					(unit 1)
				)
			)
		)
	)
	(symbol
		(lib_id "antmicropower:GND")
		(at 285.75 58.42 0)
		(unit 1)
		(exclude_from_sim no)
		(in_bom yes)
		(on_board yes)
		(dnp no)
		(property "Reference" "#PWR064"
			(at 285.75 64.77 0)
			(effects
				(font
					(size 1.27 1.27)
				)
				(justify left bottom)
				(hide yes)
			)
		)
		(property "Value" "GND"
			(at 285.75 62.23 0)
			(effects
				(font
					(size 1.27 1.27)
					(thickness 0.15)
				)
			)
		)
		(property "Footprint" ""
			(at 294.64 66.04 0)
			(effects
				(font
					(size 1.27 1.27)
					(thickness 0.15)
				)
				(justify left bottom)
				(hide yes)
			)
		)
		(property "Datasheet" ""
			(at 294.64 71.12 0)
			(effects
				(font
					(size 1.27 1.27)
					(thickness 0.15)
				)
				(justify left bottom)
				(hide yes)
			)
		)
		(property "Description" ""
			(at 285.75 58.42 0)
			(effects
				(font
					(size 1.27 1.27)
				)
				(hide yes)
			)
		)
		(property "Author" "Antmicro"
			(at 294.64 66.04 0)
			(effects
				(font
					(size 1.27 1.27)
					(thickness 0.15)
				)
				(justify left bottom)
				(hide yes)
			)
		)
		(property "License" "Apache-2.0"
			(at 294.64 68.58 0)
			(effects
				(font
					(size 1.27 1.27)
					(thickness 0.15)
				)
				(justify left bottom)
				(hide yes)
			)
		)
		(pin "1"
		)
		(instances
			(project "jetson-agx-thor-baseboard"
				(path ""
					(reference "#PWR064")
					(unit 1)
				)
			)
		)
	)
	(symbol
		(lib_id "antmicroCapacitors0603:C_22u_16V_0603")
		(at 162.56 273.05 90)
		(unit 1)
		(exclude_from_sim no)
		(in_bom yes)
		(on_board yes)
		(dnp no)
		(property "Reference" "C67"
			(at 163.195 268.605 90)
			(effects
				(font
					(size 1.27 1.27)
				)
				(justify right)
			)
		)
		(property "Value" "C_22u_16V_0603"
			(at 172.72 252.73 0)
			(effects
				(font
					(size 1.27 1.27)
					(thickness 0.15)
				)
				(justify left bottom)
				(hide yes)
			)
		)
		(property "Footprint" "antmicro-footprints:C_0603_1608Metric_EIA"
			(at 175.26 252.73 0)
			(effects
				(font
					(size 1.27 1.27)
					(thickness 0.15)
				)
				(justify left bottom)
				(hide yes)
			)
		)
		(property "Datasheet" "https://product.samsungsem.com/mlcc/CL10A226MO7JZN.do"
			(at 177.8 252.73 0)
			(effects
				(font
					(size 1.27 1.27)
					(thickness 0.15)
				)
				(justify left bottom)
				(hide yes)
			)
		)
		(property "Description" "SMD Multilayer Ceramic Capacitor"
			(at 162.56 273.05 0)
			(effects
				(font
					(size 1.27 1.27)
				)
				(hide yes)
			)
		)
		(property "Manufacturer" "Samsung Electro-Mechanics"
			(at 182.88 252.73 0)
			(effects
				(font
					(size 1.27 1.27)
					(thickness 0.15)
				)
				(justify left bottom)
				(hide yes)
			)
		)
		(property "MPN" "CL10A226MO7JZNC"
			(at 180.34 252.73 0)
			(effects
				(font
					(size 1.27 1.27)
					(thickness 0.15)
				)
				(justify left bottom)
				(hide yes)
			)
		)
		(property "Val" "22u"
			(at 163.195 272.415 90)
			(effects
				(font
					(size 1.27 1.27)
					(thickness 0.15)
				)
				(justify right)
			)
		)
		(property "License" "Apache-2.0"
			(at 185.42 252.73 0)
			(effects
				(font
					(size 1.27 1.27)
					(thickness 0.15)
				)
				(justify left bottom)
				(hide yes)
			)
		)
		(property "Author" "Antmicro"
			(at 187.96 252.73 0)
			(effects
				(font
					(size 1.27 1.27)
					(thickness 0.15)
				)
				(justify left bottom)
				(hide yes)
			)
		)
		(property "Voltage" "16V"
			(at 190.5 252.73 0)
			(effects
				(font
					(size 1.27 1.27)
				)
				(justify left bottom)
				(hide yes)
			)
		)
		(property "Dielectric" ""
			(at 193.04 252.73 0)
			(effects
				(font
					(size 1.27 1.27)
				)
				(justify left bottom)
				(hide yes)
			)
		)
		(pin "1"
		)
		(pin "2"
		)
		(instances
			(project "jetson-agx-thor-baseboard"
				(path ""
					(reference "C67")
					(unit 1)
				)
			)
		)
	)
	(symbol
		(lib_id "antmicropower:GND")
		(at 162.56 59.69 0)
		(unit 1)
		(exclude_from_sim no)
		(in_bom yes)
		(on_board yes)
		(dnp no)
		(property "Reference" "#PWR0541"
			(at 162.56 66.04 0)
			(effects
				(font
					(size 1.27 1.27)
				)
				(justify left bottom)
				(hide yes)
			)
		)
		(property "Value" "GND"
			(at 162.56 63.5 0)
			(effects
				(font
					(size 1.27 1.27)
					(thickness 0.15)
				)
			)
		)
		(property "Footprint" ""
			(at 171.45 67.31 0)
			(effects
				(font
					(size 1.27 1.27)
					(thickness 0.15)
				)
				(justify left bottom)
				(hide yes)
			)
		)
		(property "Datasheet" ""
			(at 171.45 72.39 0)
			(effects
				(font
					(size 1.27 1.27)
					(thickness 0.15)
				)
				(justify left bottom)
				(hide yes)
			)
		)
		(property "Description" ""
			(at 162.56 59.69 0)
			(effects
				(font
					(size 1.27 1.27)
				)
				(hide yes)
			)
		)
		(property "Author" "Antmicro"
			(at 171.45 67.31 0)
			(effects
				(font
					(size 1.27 1.27)
					(thickness 0.15)
				)
				(justify left bottom)
				(hide yes)
			)
		)
		(property "License" "Apache-2.0"
			(at 171.45 69.85 0)
			(effects
				(font
					(size 1.27 1.27)
					(thickness 0.15)
				)
				(justify left bottom)
				(hide yes)
			)
		)
		(pin "1"
		)
		(instances
			(project "jetson-agx-thor-baseboard"
				(path ""
					(reference "#PWR0541")
					(unit 1)
				)
			)
		)
	)
	(symbol
		(lib_id "antmicroCapacitors0402:C_100n_0402")
		(at 129.54 254 180)
		(unit 1)
		(exclude_from_sim no)
		(in_bom yes)
		(on_board yes)
		(dnp no)
		(fields_autoplaced yes)
		(property "Reference" "C60"
			(at 126.9936 247.65 0)
			(effects
				(font
					(size 1.27 1.27)
				)
			)
		)
		(property "Value" "C_100n_0402"
			(at 109.22 243.84 0)
			(effects
				(font
					(size 1.27 1.27)
					(thickness 0.15)
				)
				(justify left bottom)
				(hide yes)
			)
		)
		(property "Footprint" "antmicro-footprints:C_0402_1005Metric"
			(at 109.22 241.3 0)
			(effects
				(font
					(size 1.27 1.27)
					(thickness 0.15)
				)
				(justify left bottom)
				(hide yes)
			)
		)
		(property "Datasheet" "https://www.murata.com/products/productdetail?partno=GRM155R61H104KE14%23"
			(at 109.22 238.76 0)
			(effects
				(font
					(size 1.27 1.27)
					(thickness 0.15)
				)
				(justify left bottom)
				(hide yes)
			)
		)
		(property "Description" "SMD Multilayer Ceramic Capacitor, 0.1 µF, 50 V, 0402 [1005 Metric], ± 10%, X5R, GRM Series"
			(at 129.54 254 0)
			(effects
				(font
					(size 1.27 1.27)
				)
				(hide yes)
			)
		)
		(property "Manufacturer" "Murata"
			(at 109.22 233.68 0)
			(effects
				(font
					(size 1.27 1.27)
					(thickness 0.15)
				)
				(justify left bottom)
				(hide yes)
			)
		)
		(property "MPN" "GRM155R61H104KE14D"
			(at 109.22 236.22 0)
			(effects
				(font
					(size 1.27 1.27)
					(thickness 0.15)
				)
				(justify left bottom)
				(hide yes)
			)
		)
		(property "Val" "100n"
			(at 126.9936 250.19 0)
			(effects
				(font
					(size 1.27 1.27)
					(thickness 0.15)
				)
			)
		)
		(property "License" "Apache-2.0"
			(at 109.22 231.14 0)
			(effects
				(font
					(size 1.27 1.27)
					(thickness 0.15)
				)
				(justify left bottom)
				(hide yes)
			)
		)
		(property "Author" "Antmicro"
			(at 109.22 228.6 0)
			(effects
				(font
					(size 1.27 1.27)
					(thickness 0.15)
				)
				(justify left bottom)
				(hide yes)
			)
		)
		(property "Voltage" "50V"
			(at 109.22 226.06 0)
			(effects
				(font
					(size 1.27 1.27)
				)
				(justify left bottom)
				(hide yes)
			)
		)
		(property "Dielectric" "X5R"
			(at 109.22 223.52 0)
			(effects
				(font
					(size 1.27 1.27)
				)
				(justify left bottom)
				(hide yes)
			)
		)
		(pin "1"
		)
		(pin "2"
		)
		(instances
			(project "jetson-agx-thor-baseboard"
				(path ""
					(reference "C60")
					(unit 1)
				)
			)
		)
	)
	(symbol
		(lib_id "antmicropower:GND")
		(at 154.94 110.49 0)
		(unit 1)
		(exclude_from_sim no)
		(in_bom yes)
		(on_board yes)
		(dnp no)
		(property "Reference" "#PWR0554"
			(at 154.94 116.84 0)
			(effects
				(font
					(size 1.27 1.27)
				)
				(justify left bottom)
				(hide yes)
			)
		)
		(property "Value" "GND"
			(at 154.94 114.3 0)
			(effects
				(font
					(size 1.27 1.27)
					(thickness 0.15)
				)
			)
		)
		(property "Footprint" ""
			(at 163.83 118.11 0)
			(effects
				(font
					(size 1.27 1.27)
					(thickness 0.15)
				)
				(justify left bottom)
				(hide yes)
			)
		)
		(property "Datasheet" ""
			(at 163.83 123.19 0)
			(effects
				(font
					(size 1.27 1.27)
					(thickness 0.15)
				)
				(justify left bottom)
				(hide yes)
			)
		)
		(property "Description" ""
			(at 154.94 110.49 0)
			(effects
				(font
					(size 1.27 1.27)
				)
				(hide yes)
			)
		)
		(property "Author" "Antmicro"
			(at 163.83 118.11 0)
			(effects
				(font
					(size 1.27 1.27)
					(thickness 0.15)
				)
				(justify left bottom)
				(hide yes)
			)
		)
		(property "License" "Apache-2.0"
			(at 163.83 120.65 0)
			(effects
				(font
					(size 1.27 1.27)
					(thickness 0.15)
				)
				(justify left bottom)
				(hide yes)
			)
		)
		(pin "1"
		)
		(instances
			(project "jetson-agx-thor-baseboard"
				(path ""
					(reference "#PWR0554")
					(unit 1)
				)
			)
		)
	)
	(symbol
		(lib_id "antmicropower:GND")
		(at 346.71 196.85 0)
		(unit 1)
		(exclude_from_sim no)
		(in_bom yes)
		(on_board yes)
		(dnp no)
		(property "Reference" "#PWR055"
			(at 355.6 199.39 0)
			(effects
				(font
					(size 1.27 1.27)
					(thickness 0.15)
				)
				(justify left bottom)
				(hide yes)
			)
		)
		(property "Value" "GND"
			(at 346.71 200.66 0)
			(effects
				(font
					(size 1.27 1.27)
					(thickness 0.15)
				)
			)
		)
		(property "Footprint" ""
			(at 355.6 204.47 0)
			(effects
				(font
					(size 1.27 1.27)
					(thickness 0.15)
				)
				(justify left bottom)
				(hide yes)
			)
		)
		(property "Datasheet" ""
			(at 355.6 209.55 0)
			(effects
				(font
					(size 1.27 1.27)
					(thickness 0.15)
				)
				(justify left bottom)
				(hide yes)
			)
		)
		(property "Description" ""
			(at 346.71 196.85 0)
			(effects
				(font
					(size 1.27 1.27)
				)
				(hide yes)
			)
		)
		(property "Author" "Antmicro"
			(at 355.6 204.47 0)
			(effects
				(font
					(size 1.27 1.27)
					(thickness 0.15)
				)
				(justify left bottom)
				(hide yes)
			)
		)
		(property "License" "Apache-2.0"
			(at 355.6 207.01 0)
			(effects
				(font
					(size 1.27 1.27)
					(thickness 0.15)
				)
				(justify left bottom)
				(hide yes)
			)
		)
		(pin "1"
		)
		(instances
			(project "jetson-agx-thor-baseboard"
				(path ""
					(reference "#PWR055")
					(unit 1)
				)
			)
		)
	)
	(symbol
		(lib_id "antmicropower:GND")
		(at 278.13 58.42 0)
		(unit 1)
		(exclude_from_sim no)
		(in_bom yes)
		(on_board yes)
		(dnp no)
		(property "Reference" "#PWR058"
			(at 278.13 64.77 0)
			(effects
				(font
					(size 1.27 1.27)
				)
				(justify left bottom)
				(hide yes)
			)
		)
		(property "Value" "GND"
			(at 278.13 62.23 0)
			(effects
				(font
					(size 1.27 1.27)
					(thickness 0.15)
				)
			)
		)
		(property "Footprint" ""
			(at 287.02 66.04 0)
			(effects
				(font
					(size 1.27 1.27)
					(thickness 0.15)
				)
				(justify left bottom)
				(hide yes)
			)
		)
		(property "Datasheet" ""
			(at 287.02 71.12 0)
			(effects
				(font
					(size 1.27 1.27)
					(thickness 0.15)
				)
				(justify left bottom)
				(hide yes)
			)
		)
		(property "Description" ""
			(at 278.13 58.42 0)
			(effects
				(font
					(size 1.27 1.27)
				)
				(hide yes)
			)
		)
		(property "Author" "Antmicro"
			(at 287.02 66.04 0)
			(effects
				(font
					(size 1.27 1.27)
					(thickness 0.15)
				)
				(justify left bottom)
				(hide yes)
			)
		)
		(property "License" "Apache-2.0"
			(at 287.02 68.58 0)
			(effects
				(font
					(size 1.27 1.27)
					(thickness 0.15)
				)
				(justify left bottom)
				(hide yes)
			)
		)
		(pin "1"
		)
		(instances
			(project "jetson-agx-thor-baseboard"
				(path ""
					(reference "#PWR058")
					(unit 1)
				)
			)
		)
	)
	(symbol
		(lib_id "antmicroDCDCConverters:SIC437AED-T1-GE3")
		(at 92.71 254 0)
		(unit 1)
		(exclude_from_sim no)
		(in_bom yes)
		(on_board yes)
		(dnp no)
		(property "Reference" "U13"
			(at 103.505 247.65 0)
			(effects
				(font
					(size 1.27 1.27)
					(thickness 0.15)
				)
			)
		)
		(property "Value" "SIC437AED-T1-GE3"
			(at 125.73 261.62 0)
			(effects
				(font
					(size 1.27 1.27)
					(thickness 0.15)
				)
				(justify left bottom)
				(hide yes)
			)
		)
		(property "Footprint" "antmicro-footprints:MLP44-24L_4x4x0.75mm"
			(at 125.73 264.16 0)
			(effects
				(font
					(size 1.27 1.27)
					(thickness 0.15)
				)
				(justify left bottom)
				(hide yes)
			)
		)
		(property "Datasheet" "https://www.vishay.com/docs/75921/sic437.pdf"
			(at 125.73 266.7 0)
			(effects
				(font
					(size 1.27 1.27)
					(thickness 0.15)
				)
				(justify left bottom)
				(hide yes)
			)
		)
		(property "Description" "DC/DC Buck Step Down Regulator Adjustable, 4.5-28V In, 0.6V to 20V/12A Out, 1MHz, PowerPAK MLP44-24"
			(at 125.73 276.86 0)
			(effects
				(font
					(size 1.27 1.27)
				)
				(justify left bottom)
				(hide yes)
			)
		)
		(property "Manufacturer" "Vishay"
			(at 125.73 269.24 0)
			(effects
				(font
					(size 1.27 1.27)
					(thickness 0.15)
				)
				(justify left bottom)
				(hide yes)
			)
		)
		(property "MPN" "SIC437AED-T1-GE3"
			(at 103.505 250.19 0)
			(effects
				(font
					(size 1.27 1.27)
					(thickness 0.15)
				)
			)
		)
		(property "Author" "Antmicro"
			(at 125.73 271.78 0)
			(effects
				(font
					(size 1.27 1.27)
					(thickness 0.15)
				)
				(justify left bottom)
				(hide yes)
			)
		)
		(property "License" "Apache-2.0"
			(at 125.73 274.32 0)
			(effects
				(font
					(size 1.27 1.27)
					(thickness 0.15)
				)
				(justify left bottom)
				(hide yes)
			)
		)
		(pin "7"
		)
		(pin "16"
		)
		(pin "18"
		)
		(pin "8"
		)
		(pin "15"
		)
		(pin "14"
		)
		(pin "20"
		)
		(pin "2"
		)
		(pin "12"
		)
		(pin "22"
		)
		(pin "11"
		)
		(pin "26"
		)
		(pin "10"
		)
		(pin "19"
		)
		(pin "5"
		)
		(pin "4"
		)
		(pin "17"
		)
		(pin "6"
		)
		(pin "3"
		)
		(pin "1"
		)
		(pin "13"
		)
		(pin "23"
		)
		(pin "25"
		)
		(pin "21"
		)
		(pin "24"
		)
		(pin "9"
		)
		(pin "27"
		)
		(pin "28"
		)
		(instances
			(project "jetson-agx-thor-baseboard"
				(path ""
					(reference "U13")
					(unit 1)
				)
			)
		)
	)
	(symbol
		(lib_id "antmicropower:VCC")
		(at 21.59 29.21 0)
		(unit 1)
		(exclude_from_sim no)
		(in_bom yes)
		(on_board yes)
		(dnp no)
		(property "Reference" "#PWR043"
			(at 21.59 33.02 0)
			(effects
				(font
					(size 1.27 1.27)
				)
				(justify left bottom)
				(hide yes)
			)
		)
		(property "Value" "VCC"
			(at 19.685 25.4 0)
			(effects
				(font
					(size 1.27 1.27)
				)
				(justify left)
			)
		)
		(property "Footprint" ""
			(at 21.59 29.21 0)
			(effects
				(font
					(size 1.27 1.27)
				)
				(hide yes)
			)
		)
		(property "Datasheet" ""
			(at 21.59 29.21 0)
			(effects
				(font
					(size 1.27 1.27)
				)
				(hide yes)
			)
		)
		(property "Description" ""
			(at 21.59 29.21 0)
			(effects
				(font
					(size 1.27 1.27)
				)
				(hide yes)
			)
		)
		(pin "1"
		)
		(instances
			(project "jetson-agx-thor-baseboard"
				(path ""
					(reference "#PWR043")
					(unit 1)
				)
			)
		)
	)
	(symbol
		(lib_id "antmicroCapacitorsmisc:C_22u_25V_0805")
		(at 154.94 73.66 270)
		(mirror x)
		(unit 1)
		(exclude_from_sim no)
		(in_bom yes)
		(on_board yes)
		(dnp no)
		(property "Reference" "C282"
			(at 156.464 68.5801 90)
			(effects
				(font
					(size 1.27 1.27)
					(thickness 0.15)
				)
				(justify left)
			)
		)
		(property "Value" "C_22u_25V_0805"
			(at 144.78 53.34 0)
			(effects
				(font
					(size 1.27 1.27)
					(thickness 0.15)
				)
				(justify left bottom)
				(hide yes)
			)
		)
		(property "Footprint" "antmicro-footprints:C_0805_2012Metric"
			(at 142.24 53.34 0)
			(effects
				(font
					(size 1.27 1.27)
					(thickness 0.15)
				)
				(justify left bottom)
				(hide yes)
			)
		)
		(property "Datasheet" "https://product.samsungsem.com/mlcc/CL21A226MAYNNN.do"
			(at 139.7 53.34 0)
			(effects
				(font
					(size 1.27 1.27)
					(thickness 0.15)
				)
				(justify left bottom)
				(hide yes)
			)
		)
		(property "Description" "SMT Multilayer Ceramic Capacitor, 22uF, +/-20%, 25V, X5R, 0805 [2012 Metric]"
			(at 121.92 53.34 0)
			(effects
				(font
					(size 1.27 1.27)
				)
				(justify left bottom)
				(hide yes)
			)
		)
		(property "MPN" "CL21A226MAYNNNE"
			(at 137.16 53.34 0)
			(effects
				(font
					(size 1.27 1.27)
					(thickness 0.15)
				)
				(justify left bottom)
				(hide yes)
			)
		)
		(property "Manufacturer" "Samsung Electro-Mechanics"
			(at 134.62 53.34 0)
			(effects
				(font
					(size 1.27 1.27)
					(thickness 0.15)
				)
				(justify left bottom)
				(hide yes)
			)
		)
		(property "License" "Apache-2.0"
			(at 132.08 53.34 0)
			(effects
				(font
					(size 1.27 1.27)
					(thickness 0.15)
				)
				(justify left bottom)
				(hide yes)
			)
		)
		(property "Author" "Antmicro"
			(at 129.54 53.34 0)
			(effects
				(font
					(size 1.27 1.27)
					(thickness 0.15)
				)
				(justify left bottom)
				(hide yes)
			)
		)
		(property "Val" "22u"
			(at 156.464 71.1201 90)
			(effects
				(font
					(size 1.27 1.27)
					(thickness 0.15)
				)
				(justify left)
			)
		)
		(property "Voltage" "25V"
			(at 156.464 73.66 90)
			(effects
				(font
					(size 1.27 1.27)
				)
				(justify left)
			)
		)
		(property "Dielectric" "X5R"
			(at 124.46 53.34 0)
			(effects
				(font
					(size 1.27 1.27)
				)
				(justify left bottom)
				(hide yes)
			)
		)
		(property "Public" "False"
			(at 121.92 53.34 0)
			(effects
				(font
					(size 1.27 1.27)
				)
				(justify left bottom)
				(hide yes)
			)
		)
		(pin "2"
		)
		(pin "1"
		)
		(instances
			(project "jetson-agx-thor-baseboard"
				(path ""
					(reference "C282")
					(unit 1)
				)
			)
		)
	)
	(symbol
		(lib_id "antmicropower:GND")
		(at 143.51 55.88 0)
		(unit 1)
		(exclude_from_sim no)
		(in_bom yes)
		(on_board yes)
		(dnp no)
		(property "Reference" "#PWR0533"
			(at 143.51 62.23 0)
			(effects
				(font
					(size 1.27 1.27)
				)
				(justify left bottom)
				(hide yes)
			)
		)
		(property "Value" "GND"
			(at 143.51 59.69 0)
			(effects
				(font
					(size 1.27 1.27)
					(thickness 0.15)
				)
			)
		)
		(property "Footprint" ""
			(at 152.4 63.5 0)
			(effects
				(font
					(size 1.27 1.27)
					(thickness 0.15)
				)
				(justify left bottom)
				(hide yes)
			)
		)
		(property "Datasheet" ""
			(at 152.4 68.58 0)
			(effects
				(font
					(size 1.27 1.27)
					(thickness 0.15)
				)
				(justify left bottom)
				(hide yes)
			)
		)
		(property "Description" ""
			(at 143.51 55.88 0)
			(effects
				(font
					(size 1.27 1.27)
				)
				(hide yes)
			)
		)
		(property "Author" "Antmicro"
			(at 152.4 63.5 0)
			(effects
				(font
					(size 1.27 1.27)
					(thickness 0.15)
				)
				(justify left bottom)
				(hide yes)
			)
		)
		(property "License" "Apache-2.0"
			(at 152.4 66.04 0)
			(effects
				(font
					(size 1.27 1.27)
					(thickness 0.15)
				)
				(justify left bottom)
				(hide yes)
			)
		)
		(pin "1"
		)
		(instances
			(project "jetson-agx-thor-baseboard"
				(path ""
					(reference "#PWR0533")
					(unit 1)
				)
			)
		)
	)
	(symbol
		(lib_id "antmicroCapacitorsmisc:C_22u_25V_0805")
		(at 374.65 48.26 90)
		(unit 1)
		(exclude_from_sim no)
		(in_bom yes)
		(on_board yes)
		(dnp no)
		(property "Reference" "C235"
			(at 377.19 43.1735 90)
			(effects
				(font
					(size 1.27 1.27)
				)
				(justify right)
			)
		)
		(property "Value" "C_22u_25V_0805"
			(at 384.81 27.94 0)
			(effects
				(font
					(size 1.27 1.27)
					(thickness 0.15)
				)
				(justify left bottom)
				(hide yes)
			)
		)
		(property "Footprint" "antmicro-footprints:C_0805_2012Metric"
			(at 387.35 27.94 0)
			(effects
				(font
					(size 1.27 1.27)
					(thickness 0.15)
				)
				(justify left bottom)
				(hide yes)
			)
		)
		(property "Datasheet" "https://product.samsungsem.com/mlcc/CL21A226MAYNNN.do"
			(at 389.89 27.94 0)
			(effects
				(font
					(size 1.27 1.27)
					(thickness 0.15)
				)
				(justify left bottom)
				(hide yes)
			)
		)
		(property "Description" "SMT Multilayer Ceramic Capacitor, 22uF, +/-20%, 25V, X5R, 0805 [2012 Metric]"
			(at 374.65 48.26 0)
			(effects
				(font
					(size 1.27 1.27)
				)
				(hide yes)
			)
		)
		(property "Manufacturer" "Samsung Electro-Mechanics"
			(at 394.97 27.94 0)
			(effects
				(font
					(size 1.27 1.27)
					(thickness 0.15)
				)
				(justify left bottom)
				(hide yes)
			)
		)
		(property "MPN" "CL21A226MAYNNNE"
			(at 392.43 27.94 0)
			(effects
				(font
					(size 1.27 1.27)
					(thickness 0.15)
				)
				(justify left bottom)
				(hide yes)
			)
		)
		(property "Val" "22u"
			(at 377.19 45.7136 90)
			(effects
				(font
					(size 1.27 1.27)
					(thickness 0.15)
				)
				(justify right)
			)
		)
		(property "License" "Apache-2.0"
			(at 397.51 27.94 0)
			(effects
				(font
					(size 1.27 1.27)
					(thickness 0.15)
				)
				(justify left bottom)
				(hide yes)
			)
		)
		(property "Author" "Antmicro"
			(at 400.05 27.94 0)
			(effects
				(font
					(size 1.27 1.27)
					(thickness 0.15)
				)
				(justify left bottom)
				(hide yes)
			)
		)
		(property "Voltage" "25V"
			(at 377.19 48.2535 90)
			(effects
				(font
					(size 1.27 1.27)
				)
				(justify right)
			)
		)
		(property "Dielectric" "X5R"
			(at 405.13 27.94 0)
			(effects
				(font
					(size 1.27 1.27)
				)
				(justify left bottom)
				(hide yes)
			)
		)
		(property "Public" "False"
			(at 407.67 27.94 0)
			(effects
				(font
					(size 1.27 1.27)
				)
				(justify left bottom)
				(hide yes)
			)
		)
		(pin "1"
		)
		(pin "2"
		)
		(instances
			(project "jetson-agx-thor-baseboard"
				(path ""
					(reference "C235")
					(unit 1)
				)
			)
		)
	)
	(symbol
		(lib_id "antmicropower:GND")
		(at 74.93 187.96 0)
		(unit 1)
		(exclude_from_sim no)
		(in_bom yes)
		(on_board yes)
		(dnp no)
		(property "Reference" "#PWR0750"
			(at 74.93 194.31 0)
			(effects
				(font
					(size 1.27 1.27)
				)
				(justify left bottom)
				(hide yes)
			)
		)
		(property "Value" "GND"
			(at 74.93 191.77 0)
			(effects
				(font
					(size 1.27 1.27)
					(thickness 0.15)
				)
			)
		)
		(property "Footprint" ""
			(at 83.82 195.58 0)
			(effects
				(font
					(size 1.27 1.27)
					(thickness 0.15)
				)
				(justify left bottom)
				(hide yes)
			)
		)
		(property "Datasheet" ""
			(at 83.82 200.66 0)
			(effects
				(font
					(size 1.27 1.27)
					(thickness 0.15)
				)
				(justify left bottom)
				(hide yes)
			)
		)
		(property "Description" ""
			(at 74.93 187.96 0)
			(effects
				(font
					(size 1.27 1.27)
				)
				(hide yes)
			)
		)
		(property "Author" "Antmicro"
			(at 83.82 195.58 0)
			(effects
				(font
					(size 1.27 1.27)
					(thickness 0.15)
				)
				(justify left bottom)
				(hide yes)
			)
		)
		(property "License" "Apache-2.0"
			(at 83.82 198.12 0)
			(effects
				(font
					(size 1.27 1.27)
					(thickness 0.15)
				)
				(justify left bottom)
				(hide yes)
			)
		)
		(pin "1"
		)
		(instances
			(project "jetson-agx-thor-baseboard"
				(path ""
					(reference "#PWR0750")
					(unit 1)
				)
			)
		)
	)
	(symbol
		(lib_id "antmicropower:GND")
		(at 170.18 125.73 0)
		(unit 1)
		(exclude_from_sim no)
		(in_bom yes)
		(on_board yes)
		(dnp no)
		(property "Reference" "#PWR0561"
			(at 170.18 132.08 0)
			(effects
				(font
					(size 1.27 1.27)
				)
				(justify left bottom)
				(hide yes)
			)
		)
		(property "Value" "GND"
			(at 170.18 129.54 0)
			(effects
				(font
					(size 1.27 1.27)
					(thickness 0.15)
				)
			)
		)
		(property "Footprint" ""
			(at 179.07 133.35 0)
			(effects
				(font
					(size 1.27 1.27)
					(thickness 0.15)
				)
				(justify left bottom)
				(hide yes)
			)
		)
		(property "Datasheet" ""
			(at 179.07 138.43 0)
			(effects
				(font
					(size 1.27 1.27)
					(thickness 0.15)
				)
				(justify left bottom)
				(hide yes)
			)
		)
		(property "Description" ""
			(at 170.18 125.73 0)
			(effects
				(font
					(size 1.27 1.27)
				)
				(hide yes)
			)
		)
		(property "Author" "Antmicro"
			(at 179.07 133.35 0)
			(effects
				(font
					(size 1.27 1.27)
					(thickness 0.15)
				)
				(justify left bottom)
				(hide yes)
			)
		)
		(property "License" "Apache-2.0"
			(at 179.07 135.89 0)
			(effects
				(font
					(size 1.27 1.27)
					(thickness 0.15)
				)
				(justify left bottom)
				(hide yes)
			)
		)
		(pin "1"
		)
		(instances
			(project "jetson-agx-thor-baseboard"
				(path ""
					(reference "#PWR0561")
					(unit 1)
				)
			)
		)
	)
	(symbol
		(lib_id "antmicropower:GND")
		(at 55.88 55.88 0)
		(unit 1)
		(exclude_from_sim no)
		(in_bom yes)
		(on_board yes)
		(dnp no)
		(property "Reference" "#PWR0431"
			(at 55.88 62.23 0)
			(effects
				(font
					(size 1.27 1.27)
				)
				(justify left bottom)
				(hide yes)
			)
		)
		(property "Value" "GND"
			(at 55.88 59.69 0)
			(effects
				(font
					(size 1.27 1.27)
					(thickness 0.15)
				)
			)
		)
		(property "Footprint" ""
			(at 64.77 63.5 0)
			(effects
				(font
					(size 1.27 1.27)
					(thickness 0.15)
				)
				(justify left bottom)
				(hide yes)
			)
		)
		(property "Datasheet" ""
			(at 64.77 68.58 0)
			(effects
				(font
					(size 1.27 1.27)
					(thickness 0.15)
				)
				(justify left bottom)
				(hide yes)
			)
		)
		(property "Description" ""
			(at 55.88 55.88 0)
			(effects
				(font
					(size 1.27 1.27)
				)
				(hide yes)
			)
		)
		(property "Author" "Antmicro"
			(at 64.77 63.5 0)
			(effects
				(font
					(size 1.27 1.27)
					(thickness 0.15)
				)
				(justify left bottom)
				(hide yes)
			)
		)
		(property "License" "Apache-2.0"
			(at 64.77 66.04 0)
			(effects
				(font
					(size 1.27 1.27)
					(thickness 0.15)
				)
				(justify left bottom)
				(hide yes)
			)
		)
		(pin "1"
		)
		(instances
			(project "jetson-agx-thor-baseboard"
				(path ""
					(reference "#PWR0431")
					(unit 1)
				)
			)
		)
	)
	(symbol
		(lib_id "antmicropower:GND")
		(at 162.56 232.41 0)
		(unit 1)
		(exclude_from_sim no)
		(in_bom yes)
		(on_board yes)
		(dnp no)
		(property "Reference" "#PWR0142"
			(at 162.56 238.76 0)
			(effects
				(font
					(size 1.27 1.27)
				)
				(justify left bottom)
				(hide yes)
			)
		)
		(property "Value" "GND"
			(at 162.56 236.22 0)
			(effects
				(font
					(size 1.27 1.27)
					(thickness 0.15)
				)
			)
		)
		(property "Footprint" ""
			(at 171.45 240.03 0)
			(effects
				(font
					(size 1.27 1.27)
					(thickness 0.15)
				)
				(justify left bottom)
				(hide yes)
			)
		)
		(property "Datasheet" ""
			(at 171.45 245.11 0)
			(effects
				(font
					(size 1.27 1.27)
					(thickness 0.15)
				)
				(justify left bottom)
				(hide yes)
			)
		)
		(property "Description" ""
			(at 162.56 232.41 0)
			(effects
				(font
					(size 1.27 1.27)
				)
				(hide yes)
			)
		)
		(property "Author" "Antmicro"
			(at 171.45 240.03 0)
			(effects
				(font
					(size 1.27 1.27)
					(thickness 0.15)
				)
				(justify left bottom)
				(hide yes)
			)
		)
		(property "License" "Apache-2.0"
			(at 171.45 242.57 0)
			(effects
				(font
					(size 1.27 1.27)
					(thickness 0.15)
				)
				(justify left bottom)
				(hide yes)
			)
		)
		(pin "1"
		)
		(instances
			(project "jetson-agx-thor-baseboard"
				(path ""
					(reference "#PWR0142")
					(unit 1)
				)
			)
		)
	)
	(symbol
		(lib_id "antmicropower:GND")
		(at 58.42 187.96 0)
		(unit 1)
		(exclude_from_sim no)
		(in_bom yes)
		(on_board yes)
		(dnp no)
		(property "Reference" "#PWR0752"
			(at 58.42 194.31 0)
			(effects
				(font
					(size 1.27 1.27)
				)
				(justify left bottom)
				(hide yes)
			)
		)
		(property "Value" "GND"
			(at 58.42 191.77 0)
			(effects
				(font
					(size 1.27 1.27)
					(thickness 0.15)
				)
			)
		)
		(property "Footprint" ""
			(at 67.31 195.58 0)
			(effects
				(font
					(size 1.27 1.27)
					(thickness 0.15)
				)
				(justify left bottom)
				(hide yes)
			)
		)
		(property "Datasheet" ""
			(at 67.31 200.66 0)
			(effects
				(font
					(size 1.27 1.27)
					(thickness 0.15)
				)
				(justify left bottom)
				(hide yes)
			)
		)
		(property "Description" ""
			(at 58.42 187.96 0)
			(effects
				(font
					(size 1.27 1.27)
				)
				(hide yes)
			)
		)
		(property "Author" "Antmicro"
			(at 67.31 195.58 0)
			(effects
				(font
					(size 1.27 1.27)
					(thickness 0.15)
				)
				(justify left bottom)
				(hide yes)
			)
		)
		(property "License" "Apache-2.0"
			(at 67.31 198.12 0)
			(effects
				(font
					(size 1.27 1.27)
					(thickness 0.15)
				)
				(justify left bottom)
				(hide yes)
			)
		)
		(pin "1"
		)
		(instances
			(project "jetson-agx-thor-baseboard"
				(path ""
					(reference "#PWR0752")
					(unit 1)
				)
			)
		)
	)
	(symbol
		(lib_id "antmicroCapacitorsmisc:C_22u_25V_0805")
		(at 162.56 58.42 90)
		(unit 1)
		(exclude_from_sim no)
		(in_bom yes)
		(on_board yes)
		(dnp no)
		(property "Reference" "C258"
			(at 164.084 53.3401 90)
			(effects
				(font
					(size 1.27 1.27)
					(thickness 0.15)
				)
				(justify right)
			)
		)
		(property "Value" "C_22u_25V_0805"
			(at 172.72 38.1 0)
			(effects
				(font
					(size 1.27 1.27)
					(thickness 0.15)
				)
				(justify left bottom)
				(hide yes)
			)
		)
		(property "Footprint" "antmicro-footprints:C_0805_2012Metric"
			(at 175.26 38.1 0)
			(effects
				(font
					(size 1.27 1.27)
					(thickness 0.15)
				)
				(justify left bottom)
				(hide yes)
			)
		)
		(property "Datasheet" "https://product.samsungsem.com/mlcc/CL21A226MAYNNN.do"
			(at 177.8 38.1 0)
			(effects
				(font
					(size 1.27 1.27)
					(thickness 0.15)
				)
				(justify left bottom)
				(hide yes)
			)
		)
		(property "Description" "SMT Multilayer Ceramic Capacitor, 22uF, +/-20%, 25V, X5R, 0805 [2012 Metric]"
			(at 195.58 38.1 0)
			(effects
				(font
					(size 1.27 1.27)
				)
				(justify left bottom)
				(hide yes)
			)
		)
		(property "MPN" "CL21A226MAYNNNE"
			(at 180.34 38.1 0)
			(effects
				(font
					(size 1.27 1.27)
					(thickness 0.15)
				)
				(justify left bottom)
				(hide yes)
			)
		)
		(property "Manufacturer" "Samsung Electro-Mechanics"
			(at 182.88 38.1 0)
			(effects
				(font
					(size 1.27 1.27)
					(thickness 0.15)
				)
				(justify left bottom)
				(hide yes)
			)
		)
		(property "License" "Apache-2.0"
			(at 185.42 38.1 0)
			(effects
				(font
					(size 1.27 1.27)
					(thickness 0.15)
				)
				(justify left bottom)
				(hide yes)
			)
		)
		(property "Author" "Antmicro"
			(at 187.96 38.1 0)
			(effects
				(font
					(size 1.27 1.27)
					(thickness 0.15)
				)
				(justify left bottom)
				(hide yes)
			)
		)
		(property "Val" "22u"
			(at 164.084 55.8801 90)
			(effects
				(font
					(size 1.27 1.27)
					(thickness 0.15)
				)
				(justify right)
			)
		)
		(property "Voltage" "25V"
			(at 164.084 58.42 90)
			(effects
				(font
					(size 1.27 1.27)
				)
				(justify right)
			)
		)
		(property "Dielectric" "X5R"
			(at 193.04 38.1 0)
			(effects
				(font
					(size 1.27 1.27)
				)
				(justify left bottom)
				(hide yes)
			)
		)
		(property "Public" "False"
			(at 195.58 38.1 0)
			(effects
				(font
					(size 1.27 1.27)
				)
				(justify left bottom)
				(hide yes)
			)
		)
		(pin "2"
		)
		(pin "1"
		)
		(instances
			(project "jetson-agx-thor-baseboard"
				(path ""
					(reference "C258")
					(unit 1)
				)
			)
		)
	)
	(symbol
		(lib_id "antmicropower:GND")
		(at 154.94 140.97 0)
		(unit 1)
		(exclude_from_sim no)
		(in_bom yes)
		(on_board yes)
		(dnp no)
		(property "Reference" "#PWR0588"
			(at 154.94 147.32 0)
			(effects
				(font
					(size 1.27 1.27)
				)
				(justify left bottom)
				(hide yes)
			)
		)
		(property "Value" "GND"
			(at 154.94 144.78 0)
			(effects
				(font
					(size 1.27 1.27)
					(thickness 0.15)
				)
			)
		)
		(property "Footprint" ""
			(at 163.83 148.59 0)
			(effects
				(font
					(size 1.27 1.27)
					(thickness 0.15)
				)
				(justify left bottom)
				(hide yes)
			)
		)
		(property "Datasheet" ""
			(at 163.83 153.67 0)
			(effects
				(font
					(size 1.27 1.27)
					(thickness 0.15)
				)
				(justify left bottom)
				(hide yes)
			)
		)
		(property "Description" ""
			(at 154.94 140.97 0)
			(effects
				(font
					(size 1.27 1.27)
				)
				(hide yes)
			)
		)
		(property "Author" "Antmicro"
			(at 163.83 148.59 0)
			(effects
				(font
					(size 1.27 1.27)
					(thickness 0.15)
				)
				(justify left bottom)
				(hide yes)
			)
		)
		(property "License" "Apache-2.0"
			(at 163.83 151.13 0)
			(effects
				(font
					(size 1.27 1.27)
					(thickness 0.15)
				)
				(justify left bottom)
				(hide yes)
			)
		)
		(pin "1"
		)
		(instances
			(project "jetson-agx-thor-baseboard"
				(path ""
					(reference "#PWR0588")
					(unit 1)
				)
			)
		)
	)
	(symbol
		(lib_id "antmicroCapacitorsmisc:C_22u_25V_0805")
		(at 34.29 271.78 90)
		(unit 1)
		(exclude_from_sim no)
		(in_bom yes)
		(on_board yes)
		(dnp no)
		(property "Reference" "C43"
			(at 34.925 267.335 90)
			(effects
				(font
					(size 1.27 1.27)
					(thickness 0.15)
				)
				(justify right)
			)
		)
		(property "Value" "C_22u_25V_0805"
			(at 44.45 251.46 0)
			(effects
				(font
					(size 1.27 1.27)
					(thickness 0.15)
				)
				(justify left bottom)
				(hide yes)
			)
		)
		(property "Footprint" "antmicro-footprints:C_0805_2012Metric"
			(at 46.99 251.46 0)
			(effects
				(font
					(size 1.27 1.27)
					(thickness 0.15)
				)
				(justify left bottom)
				(hide yes)
			)
		)
		(property "Datasheet" "https://product.samsungsem.com/mlcc/CL21A226MAYNNN.do"
			(at 49.53 251.46 0)
			(effects
				(font
					(size 1.27 1.27)
					(thickness 0.15)
				)
				(justify left bottom)
				(hide yes)
			)
		)
		(property "Description" "SMT Multilayer Ceramic Capacitor, 22uF, +/-20%, 25V, X5R, 0805 [2012 Metric]"
			(at 34.29 271.78 0)
			(effects
				(font
					(size 1.27 1.27)
				)
				(hide yes)
			)
		)
		(property "MPN" "CL21A226MAYNNNE"
			(at 52.07 251.46 0)
			(effects
				(font
					(size 1.27 1.27)
					(thickness 0.15)
				)
				(justify left bottom)
				(hide yes)
			)
		)
		(property "Manufacturer" "Samsung Electro-Mechanics"
			(at 54.61 251.46 0)
			(effects
				(font
					(size 1.27 1.27)
					(thickness 0.15)
				)
				(justify left bottom)
				(hide yes)
			)
		)
		(property "License" "Apache-2.0"
			(at 57.15 251.46 0)
			(effects
				(font
					(size 1.27 1.27)
					(thickness 0.15)
				)
				(justify left bottom)
				(hide yes)
			)
		)
		(property "Author" "Antmicro"
			(at 59.69 251.46 0)
			(effects
				(font
					(size 1.27 1.27)
					(thickness 0.15)
				)
				(justify left bottom)
				(hide yes)
			)
		)
		(property "Val" "22u"
			(at 34.925 271.145 90)
			(effects
				(font
					(size 1.27 1.27)
					(thickness 0.15)
				)
				(justify right)
			)
		)
		(property "Voltage" "25V"
			(at 34.925 273.05 90)
			(effects
				(font
					(size 1.27 1.27)
				)
				(justify right)
			)
		)
		(property "Dielectric" "X5R"
			(at 64.77 251.46 0)
			(effects
				(font
					(size 1.27 1.27)
				)
				(justify left bottom)
				(hide yes)
			)
		)
		(property "Public" "False"
			(at 67.31 251.46 0)
			(effects
				(font
					(size 1.27 1.27)
				)
				(justify left bottom)
				(hide yes)
			)
		)
		(pin "2"
		)
		(pin "1"
		)
		(instances
			(project "jetson-agx-thor-baseboard"
				(path ""
					(reference "C43")
					(unit 1)
				)
			)
		)
	)
	(symbol
		(lib_id "antmicropower:VCC")
		(at 233.68 34.29 0)
		(mirror y)
		(unit 1)
		(exclude_from_sim no)
		(in_bom yes)
		(on_board yes)
		(dnp no)
		(property "Reference" "#PWR0451"
			(at 233.68 38.1 0)
			(effects
				(font
					(size 1.27 1.27)
				)
				(hide yes)
			)
		)
		(property "Value" "SYS_VIN_HV"
			(at 228.854 29.21 0)
			(effects
				(font
					(size 1.27 1.27)
				)
				(justify right)
			)
		)
		(property "Footprint" ""
			(at 233.68 34.29 0)
			(effects
				(font
					(size 1.27 1.27)
				)
				(hide yes)
			)
		)
		(property "Datasheet" ""
			(at 233.68 34.29 0)
			(effects
				(font
					(size 1.27 1.27)
				)
				(hide yes)
			)
		)
		(property "Description" ""
			(at 233.68 34.29 0)
			(effects
				(font
					(size 1.27 1.27)
				)
				(hide yes)
			)
		)
		(pin "1"
		)
		(instances
			(project "jetson-agx-thor-baseboard"
				(path ""
					(reference "#PWR0451")
					(unit 1)
				)
			)
		)
	)
	(symbol
		(lib_id "antmicropower:+12V_AON")
		(at 266.7 181.61 0)
		(unit 1)
		(exclude_from_sim no)
		(in_bom yes)
		(on_board yes)
		(dnp no)
		(fields_autoplaced yes)
		(property "Reference" "#PWR037"
			(at 266.7 185.42 0)
			(effects
				(font
					(size 1.27 1.27)
				)
				(hide yes)
			)
		)
		(property "Value" "+5V"
			(at 266.7 176.53 0)
			(effects
				(font
					(size 1.27 1.27)
				)
			)
		)
		(property "Footprint" ""
			(at 266.7 181.61 0)
			(effects
				(font
					(size 1.27 1.27)
				)
				(hide yes)
			)
		)
		(property "Datasheet" ""
			(at 266.7 181.61 0)
			(effects
				(font
					(size 1.27 1.27)
				)
				(hide yes)
			)
		)
		(property "Description" ""
			(at 266.7 181.61 0)
			(effects
				(font
					(size 1.27 1.27)
				)
				(hide yes)
			)
		)
		(pin "1"
		)
		(instances
			(project "jetson-agx-thor-baseboard"
				(path ""
					(reference "#PWR037")
					(unit 1)
				)
			)
		)
	)
	(symbol
		(lib_id "antmicropower:GND")
		(at 50.8 167.64 0)
		(unit 1)
		(exclude_from_sim no)
		(in_bom yes)
		(on_board yes)
		(dnp no)
		(property "Reference" "#PWR0749"
			(at 50.8 173.99 0)
			(effects
				(font
					(size 1.27 1.27)
				)
				(justify left bottom)
				(hide yes)
			)
		)
		(property "Value" "GND"
			(at 50.8 171.45 0)
			(effects
				(font
					(size 1.27 1.27)
					(thickness 0.15)
				)
			)
		)
		(property "Footprint" ""
			(at 59.69 175.26 0)
			(effects
				(font
					(size 1.27 1.27)
					(thickness 0.15)
				)
				(justify left bottom)
				(hide yes)
			)
		)
		(property "Datasheet" ""
			(at 59.69 180.34 0)
			(effects
				(font
					(size 1.27 1.27)
					(thickness 0.15)
				)
				(justify left bottom)
				(hide yes)
			)
		)
		(property "Description" ""
			(at 50.8 167.64 0)
			(effects
				(font
					(size 1.27 1.27)
				)
				(hide yes)
			)
		)
		(property "Author" "Antmicro"
			(at 59.69 175.26 0)
			(effects
				(font
					(size 1.27 1.27)
					(thickness 0.15)
				)
				(justify left bottom)
				(hide yes)
			)
		)
		(property "License" "Apache-2.0"
			(at 59.69 177.8 0)
			(effects
				(font
					(size 1.27 1.27)
					(thickness 0.15)
				)
				(justify left bottom)
				(hide yes)
			)
		)
		(pin "1"
		)
		(instances
			(project "jetson-agx-thor-baseboard"
				(path ""
					(reference "#PWR0749")
					(unit 1)
				)
			)
		)
	)
	(symbol
		(lib_id "antmicroCapacitors0402:C_100n_0402")
		(at 220.98 60.96 90)
		(unit 1)
		(exclude_from_sim no)
		(in_bom yes)
		(on_board yes)
		(dnp no)
		(property "Reference" "C36"
			(at 223.52 57.1435 90)
			(effects
				(font
					(size 1.27 1.27)
					(thickness 0.15)
				)
				(justify right)
			)
		)
		(property "Value" "C_100n_0402"
			(at 231.14 40.64 0)
			(effects
				(font
					(size 1.27 1.27)
					(thickness 0.15)
				)
				(justify left bottom)
				(hide yes)
			)
		)
		(property "Footprint" "antmicro-footprints:C_0402_1005Metric"
			(at 233.68 40.64 0)
			(effects
				(font
					(size 1.27 1.27)
					(thickness 0.15)
				)
				(justify left bottom)
				(hide yes)
			)
		)
		(property "Datasheet" "https://www.murata.com/products/productdetail?partno=GRM155R61H104KE14%23"
			(at 236.22 40.64 0)
			(effects
				(font
					(size 1.27 1.27)
					(thickness 0.15)
				)
				(justify left bottom)
				(hide yes)
			)
		)
		(property "Description" "SMD Multilayer Ceramic Capacitor, 0.1 µF, 50 V, 0402 [1005 Metric], ± 10%, X5R, GRM Series"
			(at 220.98 60.96 0)
			(effects
				(font
					(size 1.27 1.27)
				)
				(hide yes)
			)
		)
		(property "MPN" "GRM155R61H104KE14D"
			(at 238.76 40.64 0)
			(effects
				(font
					(size 1.27 1.27)
					(thickness 0.15)
				)
				(justify left bottom)
				(hide yes)
			)
		)
		(property "Manufacturer" "Murata"
			(at 241.3 40.64 0)
			(effects
				(font
					(size 1.27 1.27)
					(thickness 0.15)
				)
				(justify left bottom)
				(hide yes)
			)
		)
		(property "License" "Apache-2.0"
			(at 243.84 40.64 0)
			(effects
				(font
					(size 1.27 1.27)
					(thickness 0.15)
				)
				(justify left bottom)
				(hide yes)
			)
		)
		(property "Author" "Antmicro"
			(at 246.38 40.64 0)
			(effects
				(font
					(size 1.27 1.27)
					(thickness 0.15)
				)
				(justify left bottom)
				(hide yes)
			)
		)
		(property "Val" "100n"
			(at 223.52 59.6835 90)
			(effects
				(font
					(size 1.27 1.27)
					(thickness 0.15)
				)
				(justify right)
			)
		)
		(property "Voltage" "50V"
			(at 248.92 40.64 0)
			(effects
				(font
					(size 1.27 1.27)
				)
				(justify left bottom)
				(hide yes)
			)
		)
		(property "Dielectric" "X5R"
			(at 251.46 40.64 0)
			(effects
				(font
					(size 1.27 1.27)
				)
				(justify left bottom)
				(hide yes)
			)
		)
		(property "Public" "False"
			(at 254 40.64 0)
			(effects
				(font
					(size 1.27 1.27)
				)
				(justify left bottom)
				(hide yes)
			)
		)
		(pin "1"
		)
		(pin "2"
		)
		(instances
			(project "jetson-agx-thor-baseboard"
				(path ""
					(reference "C36")
					(unit 1)
				)
			)
		)
	)
	(symbol
		(lib_id "antmicroResistors0402:R_0R_0402")
		(at 36.83 135.89 0)
		(unit 1)
		(exclude_from_sim no)
		(in_bom yes)
		(on_board yes)
		(dnp no)
		(property "Reference" "R217"
			(at 39.37 133.604 0)
			(effects
				(font
					(size 1.27 1.27)
					(thickness 0.15)
				)
			)
		)
		(property "Value" "R_0R_0402"
			(at 57.15 148.59 0)
			(effects
				(font
					(size 1.27 1.27)
					(thickness 0.15)
				)
				(justify left bottom)
				(hide yes)
			)
		)
		(property "Footprint" "antmicro-footprints:R_0402_1005Metric"
			(at 57.15 151.13 0)
			(effects
				(font
					(size 1.27 1.27)
					(thickness 0.15)
				)
				(justify left bottom)
				(hide yes)
			)
		)
		(property "Datasheet" "https://industrial.panasonic.com/cdbs/www-data/pdf/RDA0000/AOA0000C301.pdf"
			(at 57.15 153.67 0)
			(effects
				(font
					(size 1.27 1.27)
					(thickness 0.15)
				)
				(justify left bottom)
				(hide yes)
			)
		)
		(property "Description" "SMD Chip Resistor, Jumper, 0 ohm, 100 mW, 0402 [1005 Metric], Thick Film, General Purpose"
			(at 57.15 168.91 0)
			(effects
				(font
					(size 1.27 1.27)
				)
				(justify left bottom)
				(hide yes)
			)
		)
		(property "MPN" "ERJ2GE0R00X"
			(at 57.15 156.21 0)
			(effects
				(font
					(size 1.27 1.27)
					(thickness 0.15)
				)
				(justify left bottom)
				(hide yes)
			)
		)
		(property "Manufacturer" "Panasonic"
			(at 57.15 158.75 0)
			(effects
				(font
					(size 1.27 1.27)
					(thickness 0.15)
				)
				(justify left bottom)
				(hide yes)
			)
		)
		(property "License" "Apache-2.0"
			(at 57.15 161.29 0)
			(effects
				(font
					(size 1.27 1.27)
					(thickness 0.15)
				)
				(justify left bottom)
				(hide yes)
			)
		)
		(property "Author" "Antmicro"
			(at 57.15 163.83 0)
			(effects
				(font
					(size 1.27 1.27)
					(thickness 0.15)
				)
				(justify left bottom)
				(hide yes)
			)
		)
		(property "Val" "0R"
			(at 39.37 135.89 0)
			(effects
				(font
					(size 1.27 1.27)
					(thickness 0.15)
				)
			)
		)
		(property "Tolerance" "~"
			(at 57.15 146.05 0)
			(effects
				(font
					(size 1.27 1.27)
				)
				(justify left bottom)
				(hide yes)
			)
		)
		(property "Current" "1A"
			(at 57.15 166.37 0)
			(effects
				(font
					(size 1.27 1.27)
					(thickness 0.15)
				)
				(justify left bottom)
				(hide yes)
			)
		)
		(pin "2"
		)
		(pin "1"
		)
		(instances
			(project ""
				(path ""
					(reference "R217")
					(unit 1)
				)
			)
		)
	)
	(symbol
		(lib_id "antmicropower:GND")
		(at 262.89 58.42 0)
		(unit 1)
		(exclude_from_sim no)
		(in_bom yes)
		(on_board yes)
		(dnp no)
		(property "Reference" "#PWR0619"
			(at 262.89 64.77 0)
			(effects
				(font
					(size 1.27 1.27)
				)
				(justify left bottom)
				(hide yes)
			)
		)
		(property "Value" "GND"
			(at 262.89 62.23 0)
			(effects
				(font
					(size 1.27 1.27)
					(thickness 0.15)
				)
			)
		)
		(property "Footprint" ""
			(at 271.78 66.04 0)
			(effects
				(font
					(size 1.27 1.27)
					(thickness 0.15)
				)
				(justify left bottom)
				(hide yes)
			)
		)
		(property "Datasheet" ""
			(at 271.78 71.12 0)
			(effects
				(font
					(size 1.27 1.27)
					(thickness 0.15)
				)
				(justify left bottom)
				(hide yes)
			)
		)
		(property "Description" ""
			(at 262.89 58.42 0)
			(effects
				(font
					(size 1.27 1.27)
				)
				(hide yes)
			)
		)
		(property "Author" "Antmicro"
			(at 271.78 66.04 0)
			(effects
				(font
					(size 1.27 1.27)
					(thickness 0.15)
				)
				(justify left bottom)
				(hide yes)
			)
		)
		(property "License" "Apache-2.0"
			(at 271.78 68.58 0)
			(effects
				(font
					(size 1.27 1.27)
					(thickness 0.15)
				)
				(justify left bottom)
				(hide yes)
			)
		)
		(pin "1"
		)
		(instances
			(project "jetson-agx-thor-baseboard"
				(path ""
					(reference "#PWR0619")
					(unit 1)
				)
			)
		)
	)
	(symbol
		(lib_id "antmicropower:GND")
		(at 48.26 41.91 0)
		(unit 1)
		(exclude_from_sim no)
		(in_bom yes)
		(on_board yes)
		(dnp no)
		(property "Reference" "#PWR085"
			(at 48.26 48.26 0)
			(effects
				(font
					(size 1.27 1.27)
				)
				(justify left bottom)
				(hide yes)
			)
		)
		(property "Value" "GND"
			(at 48.26 45.72 0)
			(effects
				(font
					(size 1.27 1.27)
					(thickness 0.15)
				)
			)
		)
		(property "Footprint" ""
			(at 57.15 49.53 0)
			(effects
				(font
					(size 1.27 1.27)
					(thickness 0.15)
				)
				(justify left bottom)
				(hide yes)
			)
		)
		(property "Datasheet" ""
			(at 57.15 54.61 0)
			(effects
				(font
					(size 1.27 1.27)
					(thickness 0.15)
				)
				(justify left bottom)
				(hide yes)
			)
		)
		(property "Description" ""
			(at 48.26 41.91 0)
			(effects
				(font
					(size 1.27 1.27)
				)
				(hide yes)
			)
		)
		(property "Author" "Antmicro"
			(at 57.15 49.53 0)
			(effects
				(font
					(size 1.27 1.27)
					(thickness 0.15)
				)
				(justify left bottom)
				(hide yes)
			)
		)
		(property "License" "Apache-2.0"
			(at 57.15 52.07 0)
			(effects
				(font
					(size 1.27 1.27)
					(thickness 0.15)
				)
				(justify left bottom)
				(hide yes)
			)
		)
		(pin "1"
		)
		(instances
			(project "jetson-agx-thor-baseboard"
				(path ""
					(reference "#PWR085")
					(unit 1)
				)
			)
		)
	)
	(symbol
		(lib_id "antmicropower:GND")
		(at 335.28 58.42 0)
		(unit 1)
		(exclude_from_sim no)
		(in_bom yes)
		(on_board yes)
		(dnp no)
		(property "Reference" "#PWR067"
			(at 335.28 64.77 0)
			(effects
				(font
					(size 1.27 1.27)
				)
				(justify left bottom)
				(hide yes)
			)
		)
		(property "Value" "GND"
			(at 335.28 62.23 0)
			(effects
				(font
					(size 1.27 1.27)
					(thickness 0.15)
				)
			)
		)
		(property "Footprint" ""
			(at 344.17 66.04 0)
			(effects
				(font
					(size 1.27 1.27)
					(thickness 0.15)
				)
				(justify left bottom)
				(hide yes)
			)
		)
		(property "Datasheet" ""
			(at 344.17 71.12 0)
			(effects
				(font
					(size 1.27 1.27)
					(thickness 0.15)
				)
				(justify left bottom)
				(hide yes)
			)
		)
		(property "Description" ""
			(at 335.28 58.42 0)
			(effects
				(font
					(size 1.27 1.27)
				)
				(hide yes)
			)
		)
		(property "Author" "Antmicro"
			(at 344.17 66.04 0)
			(effects
				(font
					(size 1.27 1.27)
					(thickness 0.15)
				)
				(justify left bottom)
				(hide yes)
			)
		)
		(property "License" "Apache-2.0"
			(at 344.17 68.58 0)
			(effects
				(font
					(size 1.27 1.27)
					(thickness 0.15)
				)
				(justify left bottom)
				(hide yes)
			)
		)
		(pin "1"
		)
		(instances
			(project "jetson-agx-thor-baseboard"
				(path ""
					(reference "#PWR067")
					(unit 1)
				)
			)
		)
	)
	(symbol
		(lib_id "antmicropower:GND")
		(at 185.42 74.93 0)
		(unit 1)
		(exclude_from_sim no)
		(in_bom yes)
		(on_board yes)
		(dnp no)
		(property "Reference" "#PWR0597"
			(at 185.42 81.28 0)
			(effects
				(font
					(size 1.27 1.27)
				)
				(justify left bottom)
				(hide yes)
			)
		)
		(property "Value" "GND"
			(at 185.42 78.74 0)
			(effects
				(font
					(size 1.27 1.27)
					(thickness 0.15)
				)
			)
		)
		(property "Footprint" ""
			(at 194.31 82.55 0)
			(effects
				(font
					(size 1.27 1.27)
					(thickness 0.15)
				)
				(justify left bottom)
				(hide yes)
			)
		)
		(property "Datasheet" ""
			(at 194.31 87.63 0)
			(effects
				(font
					(size 1.27 1.27)
					(thickness 0.15)
				)
				(justify left bottom)
				(hide yes)
			)
		)
		(property "Description" ""
			(at 185.42 74.93 0)
			(effects
				(font
					(size 1.27 1.27)
				)
				(hide yes)
			)
		)
		(property "Author" "Antmicro"
			(at 194.31 82.55 0)
			(effects
				(font
					(size 1.27 1.27)
					(thickness 0.15)
				)
				(justify left bottom)
				(hide yes)
			)
		)
		(property "License" "Apache-2.0"
			(at 194.31 85.09 0)
			(effects
				(font
					(size 1.27 1.27)
					(thickness 0.15)
				)
				(justify left bottom)
				(hide yes)
			)
		)
		(pin "1"
		)
		(instances
			(project "jetson-agx-thor-baseboard"
				(path ""
					(reference "#PWR0597")
					(unit 1)
				)
			)
		)
	)
	(symbol
		(lib_id "antmicroTVSDiodes:ESDA25P35-1U1M")
		(at 233.68 106.68 270)
		(unit 1)
		(exclude_from_sim no)
		(in_bom yes)
		(on_board yes)
		(dnp no)
		(property "Reference" "D56"
			(at 234.95 107.95 90)
			(effects
				(font
					(size 1.27 1.27)
				)
				(justify left)
			)
		)
		(property "Value" "ESDA25P35-1U1M"
			(at 218.44 128.27 0)
			(effects
				(font
					(size 1.27 1.27)
					(thickness 0.15)
				)
				(justify left bottom)
				(hide yes)
			)
		)
		(property "Footprint" "antmicro-footprints:QFN-2L_1.6x1x0.55mm"
			(at 223.52 130.81 0)
			(effects
				(font
					(size 1.27 1.27)
					(thickness 0.15)
				)
				(justify left bottom)
				(hide yes)
			)
		)
		(property "Datasheet" "https://www.st.com/resource/en/datasheet/esda25p35-1u1m.pdf"
			(at 220.98 130.81 0)
			(effects
				(font
					(size 1.27 1.27)
					(thickness 0.15)
				)
				(justify left bottom)
				(hide yes)
			)
		)
		(property "Description" "Unidirectional TVS, 30 kV, QFN-2L, 22 V, 195 pF"
			(at 208.28 130.81 0)
			(effects
				(font
					(size 1.27 1.27)
				)
				(justify left bottom)
				(hide yes)
			)
		)
		(property "Manufacturer" "STMicroelectronics"
			(at 215.9 130.81 0)
			(effects
				(font
					(size 1.27 1.27)
					(thickness 0.15)
				)
				(justify left bottom)
				(hide yes)
			)
		)
		(property "MPN" "ESDA25P35-1U1M"
			(at 239.014 106.68 0)
			(effects
				(font
					(size 1.27 1.27)
					(thickness 0.15)
				)
				(justify left bottom)
			)
		)
		(property "Author" "Antmicro"
			(at 213.36 130.81 0)
			(effects
				(font
					(size 1.27 1.27)
					(thickness 0.15)
				)
				(justify left bottom)
				(hide yes)
			)
		)
		(property "License" "Apache-2.0"
			(at 210.82 130.81 0)
			(effects
				(font
					(size 1.27 1.27)
					(thickness 0.15)
				)
				(justify left bottom)
				(hide yes)
			)
		)
		(pin "1"
		)
		(pin "2"
		)
		(instances
			(project "jetson-agx-thor-baseboard"
				(path ""
					(reference "D56")
					(unit 1)
				)
			)
		)
	)
	(symbol
		(lib_id "antmicroCapacitors0402:C_100n_0402")
		(at 271.78 45.72 270)
		(unit 1)
		(exclude_from_sim no)
		(in_bom yes)
		(on_board yes)
		(dnp no)
		(property "Reference" "C51"
			(at 272.415 46.355 90)
			(effects
				(font
					(size 1.27 1.27)
				)
				(justify left)
			)
		)
		(property "Value" "C_100n_0402"
			(at 261.62 66.04 0)
			(effects
				(font
					(size 1.27 1.27)
					(thickness 0.15)
				)
				(justify left bottom)
				(hide yes)
			)
		)
		(property "Footprint" "antmicro-footprints:C_0402_1005Metric"
			(at 259.08 66.04 0)
			(effects
				(font
					(size 1.27 1.27)
					(thickness 0.15)
				)
				(justify left bottom)
				(hide yes)
			)
		)
		(property "Datasheet" "https://www.murata.com/products/productdetail?partno=GRM155R61H104KE14%23"
			(at 256.54 66.04 0)
			(effects
				(font
					(size 1.27 1.27)
					(thickness 0.15)
				)
				(justify left bottom)
				(hide yes)
			)
		)
		(property "Description" "SMD Multilayer Ceramic Capacitor, 0.1 µF, 50 V, 0402 [1005 Metric], ± 10%, X5R, GRM Series"
			(at 271.78 45.72 0)
			(effects
				(font
					(size 1.27 1.27)
				)
				(hide yes)
			)
		)
		(property "Manufacturer" "Murata"
			(at 251.46 66.04 0)
			(effects
				(font
					(size 1.27 1.27)
					(thickness 0.15)
				)
				(justify left bottom)
				(hide yes)
			)
		)
		(property "MPN" "GRM155R61H104KE14D"
			(at 254 66.04 0)
			(effects
				(font
					(size 1.27 1.27)
					(thickness 0.15)
				)
				(justify left bottom)
				(hide yes)
			)
		)
		(property "Val" "100n"
			(at 272.415 50.165 90)
			(effects
				(font
					(size 1.27 1.27)
					(thickness 0.15)
				)
				(justify left)
			)
		)
		(property "License" "Apache-2.0"
			(at 248.92 66.04 0)
			(effects
				(font
					(size 1.27 1.27)
					(thickness 0.15)
				)
				(justify left bottom)
				(hide yes)
			)
		)
		(property "Author" "Antmicro"
			(at 246.38 66.04 0)
			(effects
				(font
					(size 1.27 1.27)
					(thickness 0.15)
				)
				(justify left bottom)
				(hide yes)
			)
		)
		(property "Voltage" "50V"
			(at 243.84 66.04 0)
			(effects
				(font
					(size 1.27 1.27)
				)
				(justify left bottom)
				(hide yes)
			)
		)
		(property "Dielectric" "X5R"
			(at 241.3 66.04 0)
			(effects
				(font
					(size 1.27 1.27)
				)
				(justify left bottom)
				(hide yes)
			)
		)
		(pin "1"
		)
		(pin "2"
		)
		(instances
			(project "jetson-agx-thor-baseboard"
				(path ""
					(reference "C51")
					(unit 1)
				)
			)
		)
	)
	(symbol
		(lib_id "antmicropower:GND")
		(at 294.64 58.42 0)
		(unit 1)
		(exclude_from_sim no)
		(in_bom yes)
		(on_board yes)
		(dnp no)
		(property "Reference" "#PWR065"
			(at 294.64 64.77 0)
			(effects
				(font
					(size 1.27 1.27)
				)
				(justify left bottom)
				(hide yes)
			)
		)
		(property "Value" "GND"
			(at 294.64 62.23 0)
			(effects
				(font
					(size 1.27 1.27)
					(thickness 0.15)
				)
			)
		)
		(property "Footprint" ""
			(at 303.53 66.04 0)
			(effects
				(font
					(size 1.27 1.27)
					(thickness 0.15)
				)
				(justify left bottom)
				(hide yes)
			)
		)
		(property "Datasheet" ""
			(at 303.53 71.12 0)
			(effects
				(font
					(size 1.27 1.27)
					(thickness 0.15)
				)
				(justify left bottom)
				(hide yes)
			)
		)
		(property "Description" ""
			(at 294.64 58.42 0)
			(effects
				(font
					(size 1.27 1.27)
				)
				(hide yes)
			)
		)
		(property "Author" "Antmicro"
			(at 303.53 66.04 0)
			(effects
				(font
					(size 1.27 1.27)
					(thickness 0.15)
				)
				(justify left bottom)
				(hide yes)
			)
		)
		(property "License" "Apache-2.0"
			(at 303.53 68.58 0)
			(effects
				(font
					(size 1.27 1.27)
					(thickness 0.15)
				)
				(justify left bottom)
				(hide yes)
			)
		)
		(pin "1"
		)
		(instances
			(project "jetson-agx-thor-baseboard"
				(path ""
					(reference "#PWR065")
					(unit 1)
				)
			)
		)
	)
	(symbol
		(lib_id "antmicropower:+12V_AON")
		(at 266.7 115.57 0)
		(unit 1)
		(exclude_from_sim no)
		(in_bom yes)
		(on_board yes)
		(dnp no)
		(fields_autoplaced yes)
		(property "Reference" "#PWR0138"
			(at 266.7 119.38 0)
			(effects
				(font
					(size 1.27 1.27)
				)
				(hide yes)
			)
		)
		(property "Value" "+5V"
			(at 266.7 110.49 0)
			(effects
				(font
					(size 1.27 1.27)
				)
			)
		)
		(property "Footprint" ""
			(at 266.7 115.57 0)
			(effects
				(font
					(size 1.27 1.27)
				)
				(hide yes)
			)
		)
		(property "Datasheet" ""
			(at 266.7 115.57 0)
			(effects
				(font
					(size 1.27 1.27)
				)
				(hide yes)
			)
		)
		(property "Description" ""
			(at 266.7 115.57 0)
			(effects
				(font
					(size 1.27 1.27)
				)
				(hide yes)
			)
		)
		(pin "1"
		)
		(instances
			(project "jetson-agx-thor-baseboard"
				(path ""
					(reference "#PWR0138")
					(unit 1)
				)
			)
		)
	)
	(symbol
		(lib_id "antmicroCapacitorsmisc:C_22u_25V_0805")
		(at 177.8 139.7 90)
		(unit 1)
		(exclude_from_sim no)
		(in_bom yes)
		(on_board yes)
		(dnp no)
		(property "Reference" "C297"
			(at 179.578 134.6201 90)
			(effects
				(font
					(size 1.27 1.27)
					(thickness 0.15)
				)
				(justify right)
			)
		)
		(property "Value" "C_22u_25V_0805"
			(at 187.96 119.38 0)
			(effects
				(font
					(size 1.27 1.27)
					(thickness 0.15)
				)
				(justify left bottom)
				(hide yes)
			)
		)
		(property "Footprint" "antmicro-footprints:C_0805_2012Metric"
			(at 190.5 119.38 0)
			(effects
				(font
					(size 1.27 1.27)
					(thickness 0.15)
				)
				(justify left bottom)
				(hide yes)
			)
		)
		(property "Datasheet" "https://product.samsungsem.com/mlcc/CL21A226MAYNNN.do"
			(at 193.04 119.38 0)
			(effects
				(font
					(size 1.27 1.27)
					(thickness 0.15)
				)
				(justify left bottom)
				(hide yes)
			)
		)
		(property "Description" "SMT Multilayer Ceramic Capacitor, 22uF, +/-20%, 25V, X5R, 0805 [2012 Metric]"
			(at 210.82 119.38 0)
			(effects
				(font
					(size 1.27 1.27)
				)
				(justify left bottom)
				(hide yes)
			)
		)
		(property "MPN" "CL21A226MAYNNNE"
			(at 195.58 119.38 0)
			(effects
				(font
					(size 1.27 1.27)
					(thickness 0.15)
				)
				(justify left bottom)
				(hide yes)
			)
		)
		(property "Manufacturer" "Samsung Electro-Mechanics"
			(at 198.12 119.38 0)
			(effects
				(font
					(size 1.27 1.27)
					(thickness 0.15)
				)
				(justify left bottom)
				(hide yes)
			)
		)
		(property "License" "Apache-2.0"
			(at 200.66 119.38 0)
			(effects
				(font
					(size 1.27 1.27)
					(thickness 0.15)
				)
				(justify left bottom)
				(hide yes)
			)
		)
		(property "Author" "Antmicro"
			(at 203.2 119.38 0)
			(effects
				(font
					(size 1.27 1.27)
					(thickness 0.15)
				)
				(justify left bottom)
				(hide yes)
			)
		)
		(property "Val" "22u"
			(at 179.578 137.1601 90)
			(effects
				(font
					(size 1.27 1.27)
					(thickness 0.15)
				)
				(justify right)
			)
		)
		(property "Voltage" "25V"
			(at 179.578 139.7 90)
			(effects
				(font
					(size 1.27 1.27)
				)
				(justify right)
			)
		)
		(property "Dielectric" "X5R"
			(at 208.28 119.38 0)
			(effects
				(font
					(size 1.27 1.27)
				)
				(justify left bottom)
				(hide yes)
			)
		)
		(property "Public" "False"
			(at 210.82 119.38 0)
			(effects
				(font
					(size 1.27 1.27)
				)
				(justify left bottom)
				(hide yes)
			)
		)
		(pin "2"
		)
		(pin "1"
		)
		(instances
			(project "jetson-agx-thor-baseboard"
				(path ""
					(reference "C297")
					(unit 1)
				)
			)
		)
	)
	(symbol
		(lib_id "antmicropower:+12V_AON")
		(at 232.41 210.82 0)
		(unit 1)
		(exclude_from_sim no)
		(in_bom yes)
		(on_board yes)
		(dnp no)
		(fields_autoplaced yes)
		(property "Reference" "#PWR0156"
			(at 232.41 214.63 0)
			(effects
				(font
					(size 1.27 1.27)
				)
				(hide yes)
			)
		)
		(property "Value" "+5V"
			(at 232.41 205.74 0)
			(effects
				(font
					(size 1.27 1.27)
				)
			)
		)
		(property "Footprint" ""
			(at 232.41 210.82 0)
			(effects
				(font
					(size 1.27 1.27)
				)
				(hide yes)
			)
		)
		(property "Datasheet" ""
			(at 232.41 210.82 0)
			(effects
				(font
					(size 1.27 1.27)
				)
				(hide yes)
			)
		)
		(property "Description" ""
			(at 232.41 210.82 0)
			(effects
				(font
					(size 1.27 1.27)
				)
				(hide yes)
			)
		)
		(pin "1"
		)
		(instances
			(project "jetson-agx-thor-baseboard"
				(path ""
					(reference "#PWR0156")
					(unit 1)
				)
			)
		)
	)
	(symbol
		(lib_id "antmicroCapacitors0603:C_22u_16V_0603")
		(at 266.7 190.5 90)
		(unit 1)
		(exclude_from_sim no)
		(in_bom yes)
		(on_board yes)
		(dnp no)
		(fields_autoplaced yes)
		(property "Reference" "C35"
			(at 269.24 185.4135 90)
			(effects
				(font
					(size 1.27 1.27)
					(thickness 0.15)
				)
				(justify right)
			)
		)
		(property "Value" "C_22u_16V_0603"
			(at 276.86 170.18 0)
			(effects
				(font
					(size 1.27 1.27)
					(thickness 0.15)
				)
				(justify left bottom)
				(hide yes)
			)
		)
		(property "Footprint" "antmicro-footprints:C_0603_1608Metric_EIA"
			(at 279.4 170.18 0)
			(effects
				(font
					(size 1.27 1.27)
					(thickness 0.15)
				)
				(justify left bottom)
				(hide yes)
			)
		)
		(property "Datasheet" "https://product.samsungsem.com/mlcc/CL10A226MO7JZN.do"
			(at 281.94 170.18 0)
			(effects
				(font
					(size 1.27 1.27)
					(thickness 0.15)
				)
				(justify left bottom)
				(hide yes)
			)
		)
		(property "Description" "SMD Multilayer Ceramic Capacitor"
			(at 266.7 190.5 0)
			(effects
				(font
					(size 1.27 1.27)
				)
				(hide yes)
			)
		)
		(property "MPN" "CL10A226MO7JZNC"
			(at 284.48 170.18 0)
			(effects
				(font
					(size 1.27 1.27)
					(thickness 0.15)
				)
				(justify left bottom)
				(hide yes)
			)
		)
		(property "Manufacturer" "Samsung Electro-Mechanics"
			(at 287.02 170.18 0)
			(effects
				(font
					(size 1.27 1.27)
					(thickness 0.15)
				)
				(justify left bottom)
				(hide yes)
			)
		)
		(property "License" "Apache-2.0"
			(at 289.56 170.18 0)
			(effects
				(font
					(size 1.27 1.27)
					(thickness 0.15)
				)
				(justify left bottom)
				(hide yes)
			)
		)
		(property "Author" "Antmicro"
			(at 292.1 170.18 0)
			(effects
				(font
					(size 1.27 1.27)
					(thickness 0.15)
				)
				(justify left bottom)
				(hide yes)
			)
		)
		(property "Val" "22u"
			(at 269.24 187.9535 90)
			(effects
				(font
					(size 1.27 1.27)
					(thickness 0.15)
				)
				(justify right)
			)
		)
		(property "Voltage" "16V"
			(at 269.24 190.4935 90)
			(effects
				(font
					(size 1.27 1.27)
				)
				(justify right)
				(hide yes)
			)
		)
		(property "Dielectric" ""
			(at 297.18 170.18 0)
			(effects
				(font
					(size 1.27 1.27)
				)
				(justify left bottom)
				(hide yes)
			)
		)
		(property "Public" "False"
			(at 299.72 170.18 0)
			(effects
				(font
					(size 1.27 1.27)
				)
				(justify left bottom)
				(hide yes)
			)
		)
		(pin "2"
		)
		(pin "1"
		)
		(instances
			(project "jetson-agx-thor-baseboard"
				(path ""
					(reference "C35")
					(unit 1)
				)
			)
		)
	)
	(symbol
		(lib_id "antmicroCapacitors0402:C_100n_0402")
		(at 129.54 30.48 180)
		(unit 1)
		(exclude_from_sim no)
		(in_bom yes)
		(on_board yes)
		(dnp no)
		(fields_autoplaced yes)
		(property "Reference" "C246"
			(at 126.9936 24.13 0)
			(effects
				(font
					(size 1.27 1.27)
				)
			)
		)
		(property "Value" "C_100n_0402"
			(at 109.22 20.32 0)
			(effects
				(font
					(size 1.27 1.27)
					(thickness 0.15)
				)
				(justify left bottom)
				(hide yes)
			)
		)
		(property "Footprint" "antmicro-footprints:C_0402_1005Metric"
			(at 109.22 17.78 0)
			(effects
				(font
					(size 1.27 1.27)
					(thickness 0.15)
				)
				(justify left bottom)
				(hide yes)
			)
		)
		(property "Datasheet" "https://www.murata.com/products/productdetail?partno=GRM155R61H104KE14%23"
			(at 109.22 15.24 0)
			(effects
				(font
					(size 1.27 1.27)
					(thickness 0.15)
				)
				(justify left bottom)
				(hide yes)
			)
		)
		(property "Description" "SMD Multilayer Ceramic Capacitor, 0.1 µF, 50 V, 0402 [1005 Metric], ± 10%, X5R, GRM Series"
			(at 129.54 30.48 0)
			(effects
				(font
					(size 1.27 1.27)
				)
				(hide yes)
			)
		)
		(property "Manufacturer" "Murata"
			(at 109.22 10.16 0)
			(effects
				(font
					(size 1.27 1.27)
					(thickness 0.15)
				)
				(justify left bottom)
				(hide yes)
			)
		)
		(property "MPN" "GRM155R61H104KE14D"
			(at 109.22 12.7 0)
			(effects
				(font
					(size 1.27 1.27)
					(thickness 0.15)
				)
				(justify left bottom)
				(hide yes)
			)
		)
		(property "Val" "100n"
			(at 126.9936 26.67 0)
			(effects
				(font
					(size 1.27 1.27)
					(thickness 0.15)
				)
			)
		)
		(property "License" "Apache-2.0"
			(at 109.22 7.62 0)
			(effects
				(font
					(size 1.27 1.27)
					(thickness 0.15)
				)
				(justify left bottom)
				(hide yes)
			)
		)
		(property "Author" "Antmicro"
			(at 109.22 5.08 0)
			(effects
				(font
					(size 1.27 1.27)
					(thickness 0.15)
				)
				(justify left bottom)
				(hide yes)
			)
		)
		(property "Voltage" "50V"
			(at 109.22 2.54 0)
			(effects
				(font
					(size 1.27 1.27)
				)
				(justify left bottom)
				(hide yes)
			)
		)
		(property "Dielectric" "X5R"
			(at 109.22 0 0)
			(effects
				(font
					(size 1.27 1.27)
				)
				(justify left bottom)
				(hide yes)
			)
		)
		(pin "1"
		)
		(pin "2"
		)
		(instances
			(project "jetson-agx-thor-baseboard"
				(path ""
					(reference "C246")
					(unit 1)
				)
			)
		)
	)
	(symbol
		(lib_id "antmicropower:GND")
		(at 196.85 280.67 0)
		(unit 1)
		(exclude_from_sim no)
		(in_bom yes)
		(on_board yes)
		(dnp no)
		(property "Reference" "#PWR0524"
			(at 205.74 283.21 0)
			(effects
				(font
					(size 1.27 1.27)
					(thickness 0.15)
				)
				(justify left bottom)
				(hide yes)
			)
		)
		(property "Value" "GND"
			(at 193.548 282.448 0)
			(effects
				(font
					(size 1.27 1.27)
					(thickness 0.15)
				)
			)
		)
		(property "Footprint" ""
			(at 205.74 288.29 0)
			(effects
				(font
					(size 1.27 1.27)
					(thickness 0.15)
				)
				(justify left bottom)
				(hide yes)
			)
		)
		(property "Datasheet" ""
			(at 205.74 293.37 0)
			(effects
				(font
					(size 1.27 1.27)
					(thickness 0.15)
				)
				(justify left bottom)
				(hide yes)
			)
		)
		(property "Description" ""
			(at 196.85 280.67 0)
			(effects
				(font
					(size 1.27 1.27)
				)
				(hide yes)
			)
		)
		(property "Author" "Antmicro"
			(at 205.74 288.29 0)
			(effects
				(font
					(size 1.27 1.27)
					(thickness 0.15)
				)
				(justify left bottom)
				(hide yes)
			)
		)
		(property "License" "Apache-2.0"
			(at 205.74 290.83 0)
			(effects
				(font
					(size 1.27 1.27)
					(thickness 0.15)
				)
				(justify left bottom)
				(hide yes)
			)
		)
		(pin "1"
		)
		(instances
			(project "jetson-agx-thor-baseboard"
				(path ""
					(reference "#PWR0524")
					(unit 1)
				)
			)
		)
	)
	(symbol
		(lib_id "antmicropower:GND")
		(at 115.57 121.92 0)
		(unit 1)
		(exclude_from_sim no)
		(in_bom yes)
		(on_board yes)
		(dnp no)
		(property "Reference" "#PWR0551"
			(at 115.57 128.27 0)
			(effects
				(font
					(size 1.27 1.27)
				)
				(justify left bottom)
				(hide yes)
			)
		)
		(property "Value" "GND"
			(at 115.57 125.73 0)
			(effects
				(font
					(size 1.27 1.27)
					(thickness 0.15)
				)
			)
		)
		(property "Footprint" ""
			(at 124.46 129.54 0)
			(effects
				(font
					(size 1.27 1.27)
					(thickness 0.15)
				)
				(justify left bottom)
				(hide yes)
			)
		)
		(property "Datasheet" ""
			(at 124.46 134.62 0)
			(effects
				(font
					(size 1.27 1.27)
					(thickness 0.15)
				)
				(justify left bottom)
				(hide yes)
			)
		)
		(property "Description" ""
			(at 115.57 121.92 0)
			(effects
				(font
					(size 1.27 1.27)
				)
				(hide yes)
			)
		)
		(property "Author" "Antmicro"
			(at 124.46 129.54 0)
			(effects
				(font
					(size 1.27 1.27)
					(thickness 0.15)
				)
				(justify left bottom)
				(hide yes)
			)
		)
		(property "License" "Apache-2.0"
			(at 124.46 132.08 0)
			(effects
				(font
					(size 1.27 1.27)
					(thickness 0.15)
				)
				(justify left bottom)
				(hide yes)
			)
		)
		(pin "1"
		)
		(instances
			(project "jetson-agx-thor-baseboard"
				(path ""
					(reference "#PWR0551")
					(unit 1)
				)
			)
		)
	)
	(symbol
		(lib_id "antmicropower:GND")
		(at 262.89 44.45 0)
		(unit 1)
		(exclude_from_sim no)
		(in_bom yes)
		(on_board yes)
		(dnp no)
		(property "Reference" "#PWR047"
			(at 262.89 50.8 0)
			(effects
				(font
					(size 1.27 1.27)
				)
				(justify left bottom)
				(hide yes)
			)
		)
		(property "Value" "GND"
			(at 262.89 48.26 0)
			(effects
				(font
					(size 1.27 1.27)
					(thickness 0.15)
				)
			)
		)
		(property "Footprint" ""
			(at 271.78 52.07 0)
			(effects
				(font
					(size 1.27 1.27)
					(thickness 0.15)
				)
				(justify left bottom)
				(hide yes)
			)
		)
		(property "Datasheet" ""
			(at 271.78 57.15 0)
			(effects
				(font
					(size 1.27 1.27)
					(thickness 0.15)
				)
				(justify left bottom)
				(hide yes)
			)
		)
		(property "Description" ""
			(at 262.89 44.45 0)
			(effects
				(font
					(size 1.27 1.27)
				)
				(hide yes)
			)
		)
		(property "Author" "Antmicro"
			(at 271.78 52.07 0)
			(effects
				(font
					(size 1.27 1.27)
					(thickness 0.15)
				)
				(justify left bottom)
				(hide yes)
			)
		)
		(property "License" "Apache-2.0"
			(at 271.78 54.61 0)
			(effects
				(font
					(size 1.27 1.27)
					(thickness 0.15)
				)
				(justify left bottom)
				(hide yes)
			)
		)
		(pin "1"
		)
		(instances
			(project "jetson-agx-thor-baseboard"
				(path ""
					(reference "#PWR047")
					(unit 1)
				)
			)
		)
	)
	(symbol
		(lib_id "antmicropower:GND")
		(at 177.8 110.49 0)
		(unit 1)
		(exclude_from_sim no)
		(in_bom yes)
		(on_board yes)
		(dnp no)
		(property "Reference" "#PWR0562"
			(at 177.8 116.84 0)
			(effects
				(font
					(size 1.27 1.27)
				)
				(justify left bottom)
				(hide yes)
			)
		)
		(property "Value" "GND"
			(at 177.8 114.3 0)
			(effects
				(font
					(size 1.27 1.27)
					(thickness 0.15)
				)
			)
		)
		(property "Footprint" ""
			(at 186.69 118.11 0)
			(effects
				(font
					(size 1.27 1.27)
					(thickness 0.15)
				)
				(justify left bottom)
				(hide yes)
			)
		)
		(property "Datasheet" ""
			(at 186.69 123.19 0)
			(effects
				(font
					(size 1.27 1.27)
					(thickness 0.15)
				)
				(justify left bottom)
				(hide yes)
			)
		)
		(property "Description" ""
			(at 177.8 110.49 0)
			(effects
				(font
					(size 1.27 1.27)
				)
				(hide yes)
			)
		)
		(property "Author" "Antmicro"
			(at 186.69 118.11 0)
			(effects
				(font
					(size 1.27 1.27)
					(thickness 0.15)
				)
				(justify left bottom)
				(hide yes)
			)
		)
		(property "License" "Apache-2.0"
			(at 186.69 120.65 0)
			(effects
				(font
					(size 1.27 1.27)
					(thickness 0.15)
				)
				(justify left bottom)
				(hide yes)
			)
		)
		(pin "1"
		)
		(instances
			(project "jetson-agx-thor-baseboard"
				(path ""
					(reference "#PWR0562")
					(unit 1)
				)
			)
		)
	)
	(symbol
		(lib_id "antmicropower:+3V3_AON")
		(at 227.33 119.38 0)
		(unit 1)
		(exclude_from_sim no)
		(in_bom yes)
		(on_board yes)
		(dnp no)
		(property "Reference" "#PWR0570"
			(at 227.33 123.19 0)
			(effects
				(font
					(size 1.27 1.27)
				)
				(hide yes)
			)
		)
		(property "Value" "+3V3_AON"
			(at 227.33 114.3 0)
			(effects
				(font
					(size 1.27 1.27)
				)
			)
		)
		(property "Footprint" ""
			(at 227.33 119.38 0)
			(effects
				(font
					(size 1.27 1.27)
				)
				(hide yes)
			)
		)
		(property "Datasheet" ""
			(at 227.33 119.38 0)
			(effects
				(font
					(size 1.27 1.27)
				)
				(hide yes)
			)
		)
		(property "Description" ""
			(at 227.33 119.38 0)
			(effects
				(font
					(size 1.27 1.27)
				)
				(hide yes)
			)
		)
		(pin "1"
		)
		(instances
			(project "jetson-agx-thor-baseboard"
				(path ""
					(reference "#PWR0570")
					(unit 1)
				)
			)
		)
	)
	(symbol
		(lib_id "antmicropower:GND")
		(at 177.8 125.73 0)
		(unit 1)
		(exclude_from_sim no)
		(in_bom yes)
		(on_board yes)
		(dnp no)
		(property "Reference" "#PWR0564"
			(at 177.8 132.08 0)
			(effects
				(font
					(size 1.27 1.27)
				)
				(justify left bottom)
				(hide yes)
			)
		)
		(property "Value" "GND"
			(at 177.8 129.54 0)
			(effects
				(font
					(size 1.27 1.27)
					(thickness 0.15)
				)
			)
		)
		(property "Footprint" ""
			(at 186.69 133.35 0)
			(effects
				(font
					(size 1.27 1.27)
					(thickness 0.15)
				)
				(justify left bottom)
				(hide yes)
			)
		)
		(property "Datasheet" ""
			(at 186.69 138.43 0)
			(effects
				(font
					(size 1.27 1.27)
					(thickness 0.15)
				)
				(justify left bottom)
				(hide yes)
			)
		)
		(property "Description" ""
			(at 177.8 125.73 0)
			(effects
				(font
					(size 1.27 1.27)
				)
				(hide yes)
			)
		)
		(property "Author" "Antmicro"
			(at 186.69 133.35 0)
			(effects
				(font
					(size 1.27 1.27)
					(thickness 0.15)
				)
				(justify left bottom)
				(hide yes)
			)
		)
		(property "License" "Apache-2.0"
			(at 186.69 135.89 0)
			(effects
				(font
					(size 1.27 1.27)
					(thickness 0.15)
				)
				(justify left bottom)
				(hide yes)
			)
		)
		(pin "1"
		)
		(instances
			(project "jetson-agx-thor-baseboard"
				(path ""
					(reference "#PWR0564")
					(unit 1)
				)
			)
		)
	)
	(symbol
		(lib_id "antmicroResistors0603:R_0R_22.4A_0603")
		(at 367.03 116.84 0)
		(unit 1)
		(exclude_from_sim no)
		(in_bom yes)
		(on_board yes)
		(dnp no)
		(property "Reference" "R10"
			(at 369.57 112.522 0)
			(effects
				(font
					(size 1.27 1.27)
				)
			)
		)
		(property "Value" "R_0R_22.4A_0603"
			(at 369.57 107.95 0)
			(effects
				(font
					(size 1.27 1.27)
					(thickness 0.15)
				)
				(hide yes)
			)
		)
		(property "Footprint" "antmicro-footprints:R_0603_1608Metric"
			(at 382.27 127 0)
			(effects
				(font
					(size 1.27 1.27)
					(thickness 0.15)
				)
				(justify left bottom)
				(hide yes)
			)
		)
		(property "Datasheet" "https://fscdn.rohm.com/en/products/databook/datasheet/passive/resistor/chip_resistor/pmr-jpw-e.pdf"
			(at 382.27 129.54 0)
			(effects
				(font
					(size 1.27 1.27)
					(thickness 0.15)
				)
				(justify left bottom)
				(hide yes)
			)
		)
		(property "Description" "SMD Chip Resistor"
			(at 367.03 116.84 0)
			(effects
				(font
					(size 1.27 1.27)
				)
				(hide yes)
			)
		)
		(property "Manufacturer" "ROHM Semiconductor"
			(at 382.27 134.62 0)
			(effects
				(font
					(size 1.27 1.27)
					(thickness 0.15)
				)
				(justify left bottom)
				(hide yes)
			)
		)
		(property "MPN" "PMR03EZPJ000"
			(at 382.27 132.08 0)
			(effects
				(font
					(size 1.27 1.27)
					(thickness 0.15)
				)
				(justify left bottom)
				(hide yes)
			)
		)
		(property "Val" "0R"
			(at 369.57 114.3 0)
			(effects
				(font
					(size 1.27 1.27)
					(thickness 0.15)
				)
			)
		)
		(property "Author" "Antmicro"
			(at 382.27 139.7 0)
			(effects
				(font
					(size 1.27 1.27)
					(thickness 0.15)
				)
				(justify left bottom)
				(hide yes)
			)
		)
		(property "License" "Apache-2.0"
			(at 382.27 142.24 0)
			(effects
				(font
					(size 1.27 1.27)
					(thickness 0.15)
				)
				(justify left bottom)
				(hide yes)
			)
		)
		(property "Max. Curr." "22.4A"
			(at 369.57 119.38 0)
			(effects
				(font
					(size 1.27 1.27)
					(thickness 0.15)
				)
			)
		)
		(property "Tolerance" "template_tolerance"
			(at 387.35 127 0)
			(effects
				(font
					(size 1.27 1.27)
				)
				(justify left bottom)
				(hide yes)
			)
		)
		(pin "1"
		)
		(pin "2"
		)
		(instances
			(project "jetson-agx-thor-baseboard"
				(path ""
					(reference "R10")
					(unit 1)
				)
			)
		)
	)
	(symbol
		(lib_id "antmicroCapacitorsmisc:C_22u_25V_0805")
		(at 162.56 109.22 90)
		(unit 1)
		(exclude_from_sim no)
		(in_bom yes)
		(on_board yes)
		(dnp no)
		(property "Reference" "C287"
			(at 164.338 104.1401 90)
			(effects
				(font
					(size 1.27 1.27)
					(thickness 0.15)
				)
				(justify right)
			)
		)
		(property "Value" "C_22u_25V_0805"
			(at 172.72 88.9 0)
			(effects
				(font
					(size 1.27 1.27)
					(thickness 0.15)
				)
				(justify left bottom)
				(hide yes)
			)
		)
		(property "Footprint" "antmicro-footprints:C_0805_2012Metric"
			(at 175.26 88.9 0)
			(effects
				(font
					(size 1.27 1.27)
					(thickness 0.15)
				)
				(justify left bottom)
				(hide yes)
			)
		)
		(property "Datasheet" "https://product.samsungsem.com/mlcc/CL21A226MAYNNN.do"
			(at 177.8 88.9 0)
			(effects
				(font
					(size 1.27 1.27)
					(thickness 0.15)
				)
				(justify left bottom)
				(hide yes)
			)
		)
		(property "Description" "SMT Multilayer Ceramic Capacitor, 22uF, +/-20%, 25V, X5R, 0805 [2012 Metric]"
			(at 195.58 88.9 0)
			(effects
				(font
					(size 1.27 1.27)
				)
				(justify left bottom)
				(hide yes)
			)
		)
		(property "MPN" "CL21A226MAYNNNE"
			(at 180.34 88.9 0)
			(effects
				(font
					(size 1.27 1.27)
					(thickness 0.15)
				)
				(justify left bottom)
				(hide yes)
			)
		)
		(property "Manufacturer" "Samsung Electro-Mechanics"
			(at 182.88 88.9 0)
			(effects
				(font
					(size 1.27 1.27)
					(thickness 0.15)
				)
				(justify left bottom)
				(hide yes)
			)
		)
		(property "License" "Apache-2.0"
			(at 185.42 88.9 0)
			(effects
				(font
					(size 1.27 1.27)
					(thickness 0.15)
				)
				(justify left bottom)
				(hide yes)
			)
		)
		(property "Author" "Antmicro"
			(at 187.96 88.9 0)
			(effects
				(font
					(size 1.27 1.27)
					(thickness 0.15)
				)
				(justify left bottom)
				(hide yes)
			)
		)
		(property "Val" "22u"
			(at 164.338 106.6801 90)
			(effects
				(font
					(size 1.27 1.27)
					(thickness 0.15)
				)
				(justify right)
			)
		)
		(property "Voltage" "25V"
			(at 164.338 109.22 90)
			(effects
				(font
					(size 1.27 1.27)
				)
				(justify right)
			)
		)
		(property "Dielectric" "X5R"
			(at 193.04 88.9 0)
			(effects
				(font
					(size 1.27 1.27)
				)
				(justify left bottom)
				(hide yes)
			)
		)
		(property "Public" "False"
			(at 195.58 88.9 0)
			(effects
				(font
					(size 1.27 1.27)
				)
				(justify left bottom)
				(hide yes)
			)
		)
		(pin "2"
		)
		(pin "1"
		)
		(instances
			(project "jetson-agx-thor-baseboard"
				(path ""
					(reference "C287")
					(unit 1)
				)
			)
		)
	)
	(symbol
		(lib_id "antmicroCapacitors0402:C_4u7_25V_0402")
		(at 303.53 57.15 90)
		(unit 1)
		(exclude_from_sim no)
		(in_bom yes)
		(on_board yes)
		(dnp no)
		(property "Reference" "C218"
			(at 304.165 52.705 90)
			(effects
				(font
					(size 1.27 1.27)
					(thickness 0.15)
				)
				(justify right)
			)
		)
		(property "Value" "C_4u7_25V_0402"
			(at 313.69 36.83 0)
			(effects
				(font
					(size 1.27 1.27)
					(thickness 0.15)
				)
				(justify left bottom)
				(hide yes)
			)
		)
		(property "Footprint" "antmicro-footprints:C_0402_1005Metric"
			(at 316.23 36.83 0)
			(effects
				(font
					(size 1.27 1.27)
					(thickness 0.15)
				)
				(justify left bottom)
				(hide yes)
			)
		)
		(property "Datasheet" "https://www.murata.com/products/productdetail?partno=GRM155C61E475ME15%23"
			(at 318.77 36.83 0)
			(effects
				(font
					(size 1.27 1.27)
					(thickness 0.15)
				)
				(justify left bottom)
				(hide yes)
			)
		)
		(property "Description" "SMD Multilayer Ceramic Capacitor"
			(at 303.53 57.15 0)
			(effects
				(font
					(size 1.27 1.27)
				)
				(hide yes)
			)
		)
		(property "MPN" "GRM155C61E475ME15J"
			(at 321.31 36.83 0)
			(effects
				(font
					(size 1.27 1.27)
					(thickness 0.15)
				)
				(justify left bottom)
				(hide yes)
			)
		)
		(property "Manufacturer" "Murata"
			(at 323.85 36.83 0)
			(effects
				(font
					(size 1.27 1.27)
					(thickness 0.15)
				)
				(justify left bottom)
				(hide yes)
			)
		)
		(property "License" "Apache-2.0"
			(at 326.39 36.83 0)
			(effects
				(font
					(size 1.27 1.27)
					(thickness 0.15)
				)
				(justify left bottom)
				(hide yes)
			)
		)
		(property "Author" "Antmicro"
			(at 328.93 36.83 0)
			(effects
				(font
					(size 1.27 1.27)
					(thickness 0.15)
				)
				(justify left bottom)
				(hide yes)
			)
		)
		(property "Val" "4u7"
			(at 304.165 56.515 90)
			(effects
				(font
					(size 1.27 1.27)
					(thickness 0.15)
				)
				(justify right)
			)
		)
		(property "Voltage" "25V"
			(at 331.47 36.83 0)
			(effects
				(font
					(size 1.27 1.27)
				)
				(justify left bottom)
				(hide yes)
			)
		)
		(property "Dielectric" "X5S"
			(at 334.01 36.83 0)
			(effects
				(font
					(size 1.27 1.27)
				)
				(justify left bottom)
				(hide yes)
			)
		)
		(pin "2"
		)
		(pin "1"
		)
		(instances
			(project "jetson-agx-thor-baseboard"
				(path ""
					(reference "C218")
					(unit 1)
				)
			)
		)
	)
	(symbol
		(lib_id "antmicropower:GND")
		(at 170.18 74.93 0)
		(unit 1)
		(exclude_from_sim no)
		(in_bom yes)
		(on_board yes)
		(dnp no)
		(property "Reference" "#PWR0595"
			(at 170.18 81.28 0)
			(effects
				(font
					(size 1.27 1.27)
				)
				(justify left bottom)
				(hide yes)
			)
		)
		(property "Value" "GND"
			(at 170.18 78.74 0)
			(effects
				(font
					(size 1.27 1.27)
					(thickness 0.15)
				)
			)
		)
		(property "Footprint" ""
			(at 179.07 82.55 0)
			(effects
				(font
					(size 1.27 1.27)
					(thickness 0.15)
				)
				(justify left bottom)
				(hide yes)
			)
		)
		(property "Datasheet" ""
			(at 179.07 87.63 0)
			(effects
				(font
					(size 1.27 1.27)
					(thickness 0.15)
				)
				(justify left bottom)
				(hide yes)
			)
		)
		(property "Description" ""
			(at 170.18 74.93 0)
			(effects
				(font
					(size 1.27 1.27)
				)
				(hide yes)
			)
		)
		(property "Author" "Antmicro"
			(at 179.07 82.55 0)
			(effects
				(font
					(size 1.27 1.27)
					(thickness 0.15)
				)
				(justify left bottom)
				(hide yes)
			)
		)
		(property "License" "Apache-2.0"
			(at 179.07 85.09 0)
			(effects
				(font
					(size 1.27 1.27)
					(thickness 0.15)
				)
				(justify left bottom)
				(hide yes)
			)
		)
		(pin "1"
		)
		(instances
			(project "jetson-agx-thor-baseboard"
				(path ""
					(reference "#PWR0595")
					(unit 1)
				)
			)
		)
	)
	(symbol
		(lib_id "antmicroCapacitorsmisc:C_22u_25V_0805")
		(at 27.94 271.78 90)
		(unit 1)
		(exclude_from_sim no)
		(in_bom yes)
		(on_board yes)
		(dnp no)
		(property "Reference" "C273"
			(at 28.575 267.335 90)
			(effects
				(font
					(size 1.27 1.27)
					(thickness 0.15)
				)
				(justify right)
			)
		)
		(property "Value" "C_22u_25V_0805"
			(at 38.1 251.46 0)
			(effects
				(font
					(size 1.27 1.27)
					(thickness 0.15)
				)
				(justify left bottom)
				(hide yes)
			)
		)
		(property "Footprint" "antmicro-footprints:C_0805_2012Metric"
			(at 40.64 251.46 0)
			(effects
				(font
					(size 1.27 1.27)
					(thickness 0.15)
				)
				(justify left bottom)
				(hide yes)
			)
		)
		(property "Datasheet" "https://product.samsungsem.com/mlcc/CL21A226MAYNNN.do"
			(at 43.18 251.46 0)
			(effects
				(font
					(size 1.27 1.27)
					(thickness 0.15)
				)
				(justify left bottom)
				(hide yes)
			)
		)
		(property "Description" "SMT Multilayer Ceramic Capacitor, 22uF, +/-20%, 25V, X5R, 0805 [2012 Metric]"
			(at 27.94 271.78 0)
			(effects
				(font
					(size 1.27 1.27)
				)
				(hide yes)
			)
		)
		(property "MPN" "CL21A226MAYNNNE"
			(at 45.72 251.46 0)
			(effects
				(font
					(size 1.27 1.27)
					(thickness 0.15)
				)
				(justify left bottom)
				(hide yes)
			)
		)
		(property "Manufacturer" "Samsung Electro-Mechanics"
			(at 48.26 251.46 0)
			(effects
				(font
					(size 1.27 1.27)
					(thickness 0.15)
				)
				(justify left bottom)
				(hide yes)
			)
		)
		(property "License" "Apache-2.0"
			(at 50.8 251.46 0)
			(effects
				(font
					(size 1.27 1.27)
					(thickness 0.15)
				)
				(justify left bottom)
				(hide yes)
			)
		)
		(property "Author" "Antmicro"
			(at 53.34 251.46 0)
			(effects
				(font
					(size 1.27 1.27)
					(thickness 0.15)
				)
				(justify left bottom)
				(hide yes)
			)
		)
		(property "Val" "22u"
			(at 28.575 271.145 90)
			(effects
				(font
					(size 1.27 1.27)
					(thickness 0.15)
				)
				(justify right)
			)
		)
		(property "Voltage" "25V"
			(at 28.575 273.685 90)
			(effects
				(font
					(size 1.27 1.27)
				)
				(justify right)
			)
		)
		(property "Dielectric" "X5R"
			(at 58.42 251.46 0)
			(effects
				(font
					(size 1.27 1.27)
				)
				(justify left bottom)
				(hide yes)
			)
		)
		(property "Public" "False"
			(at 60.96 251.46 0)
			(effects
				(font
					(size 1.27 1.27)
				)
				(justify left bottom)
				(hide yes)
			)
		)
		(pin "1"
		)
		(pin "2"
		)
		(instances
			(project "jetson-agx-thor-baseboard"
				(path ""
					(reference "C273")
					(unit 1)
				)
			)
		)
	)
	(symbol
		(lib_id "antmicropower:PWR_FLAG")
		(at 375.92 182.88 270)
		(mirror x)
		(unit 1)
		(exclude_from_sim no)
		(in_bom yes)
		(on_board yes)
		(dnp no)
		(property "Reference" "#FLG011"
			(at 377.825 182.88 0)
			(effects
				(font
					(size 1.27 1.27)
				)
				(hide yes)
			)
		)
		(property "Value" "PWR_FLAG"
			(at 379.73 183.134 90)
			(effects
				(font
					(size 1.27 1.27)
				)
				(justify left)
			)
		)
		(property "Footprint" ""
			(at 375.92 182.88 0)
			(effects
				(font
					(size 1.27 1.27)
				)
				(hide yes)
			)
		)
		(property "Datasheet" ""
			(at 375.92 182.88 0)
			(effects
				(font
					(size 1.27 1.27)
				)
				(hide yes)
			)
		)
		(property "Description" ""
			(at 375.92 182.88 0)
			(effects
				(font
					(size 1.27 1.27)
				)
				(hide yes)
			)
		)
		(pin "1"
		)
		(instances
			(project "jetson-agx-thor-baseboard"
				(path ""
					(reference "#FLG011")
					(unit 1)
				)
			)
		)
	)
)
